FILE_TYPE = EXPANDEDNETLIST;
{ Packager-XL run on 14-Sep-2023 AT 16:11:04 CONSTRAINTS_VIEW_GENERATED}
NET_NAME
'ADC128_2_A0'
 '@T6G_MB_LIB.T6G(SCH_1):ADC128_2_A0':
 C_SIGNAL='@t6g_mb_lib.t6g(sch_1):adc128_2_a0';
NODE_NAME     R1242 1
 '@T6G_MB_LIB.T6G(SCH_1):PAGE263_I58@PURE_QUANTA.Q_RES(CHIPS)':
 'A': CDS_PINID='A';
NODE_NAME     R1241 2
 '@T6G_MB_LIB.T6G(SCH_1):PAGE263_I60@PURE_QUANTA.Q_RES(CHIPS)':
 'B': CDS_PINID='B';
NODE_NAME     U51 7
 '@T6G_MB_LIB.T6G(SCH_1):PAGE263_I142@PURE_QUANTA.ADC128D818CIMTXNOPB(CHIPS)':
 'A0': CDS_PINID='A0';
NET_NAME
'ADC128_2_A1'
 '@T6G_MB_LIB.T6G(SCH_1):ADC128_2_A1':
 C_SIGNAL='@t6g_mb_lib.t6g(sch_1):adc128_2_a1';
NODE_NAME     R1240 1
 '@T6G_MB_LIB.T6G(SCH_1):PAGE263_I57@PURE_QUANTA.Q_RES(CHIPS)':
 'A': CDS_PINID='A';
NODE_NAME     R1239 2
 '@T6G_MB_LIB.T6G(SCH_1):PAGE263_I59@PURE_QUANTA.Q_RES(CHIPS)':
 'B': CDS_PINID='B';
NODE_NAME     U51 8
 '@T6G_MB_LIB.T6G(SCH_1):PAGE263_I142@PURE_QUANTA.ADC128D818CIMTXNOPB(CHIPS)':
 'A1': CDS_PINID='A1';
NET_NAME
'ADC128_2_VREF'
 '@T6G_MB_LIB.T6G(SCH_1):ADC128_2_VREF':
 C_SIGNAL='@t6g_mb_lib.t6g(sch_1):adc128_2_vref';
NODE_NAME     R1268 1
 '@T6G_MB_LIB.T6G(SCH_1):PAGE263_I119@PURE_QUANTA.Q_RES(CHIPS)':
 'A': CDS_PINID='A';
NODE_NAME     R1267 2
 '@T6G_MB_LIB.T6G(SCH_1):PAGE263_I131@PURE_QUANTA.Q_RES(CHIPS)':
 'B': CDS_PINID='B';
NODE_NAME     U51 1
 '@T6G_MB_LIB.T6G(SCH_1):PAGE263_I142@PURE_QUANTA.ADC128D818CIMTXNOPB(CHIPS)':
 'VREF': CDS_PINID='VREF';
NET_NAME
'ADC128_A0'
 '@T6G_MB_LIB.T6G(SCH_1):ADC128_A0':
 C_SIGNAL='@t6g_mb_lib.t6g(sch_1):adc128_a0';
NODE_NAME     R3670 1
 '@T6G_MB_LIB.T6G(SCH_1):PAGE369_I40@PURE_QUANTA.Q_RES(CHIPS)':
 'A': CDS_PINID='A';
NODE_NAME     R3669 2
 '@T6G_MB_LIB.T6G(SCH_1):PAGE369_I68@PURE_QUANTA.Q_RES(CHIPS)':
 'B': CDS_PINID='B';
NODE_NAME     U269 7
 '@T6G_MB_LIB.T6G(SCH_1):PAGE369_I142@PURE_QUANTA.ADC128D818CIMTXNOPB(CHIPS)':
 'A0': CDS_PINID='A0';
NET_NAME
'ADC128_A1'
 '@T6G_MB_LIB.T6G(SCH_1):ADC128_A1':
 C_SIGNAL='@t6g_mb_lib.t6g(sch_1):adc128_a1';
NODE_NAME     R3668 1
 '@T6G_MB_LIB.T6G(SCH_1):PAGE369_I38@PURE_QUANTA.Q_RES(CHIPS)':
 'A': CDS_PINID='A';
NODE_NAME     R3667 2
 '@T6G_MB_LIB.T6G(SCH_1):PAGE369_I66@PURE_QUANTA.Q_RES(CHIPS)':
 'B': CDS_PINID='B';
NODE_NAME     U269 8
 '@T6G_MB_LIB.T6G(SCH_1):PAGE369_I142@PURE_QUANTA.ADC128D818CIMTXNOPB(CHIPS)':
 'A1': CDS_PINID='A1';
NET_NAME
'ADC128_VREF'
 '@T6G_MB_LIB.T6G(SCH_1):ADC128_VREF':
 C_SIGNAL='@t6g_mb_lib.t6g(sch_1):adc128_vref';
NODE_NAME     R3690 1
 '@T6G_MB_LIB.T6G(SCH_1):PAGE369_I130@PURE_QUANTA.Q_RES(CHIPS)':
 'A': CDS_PINID='A';
NODE_NAME     R3689 2
 '@T6G_MB_LIB.T6G(SCH_1):PAGE369_I131@PURE_QUANTA.Q_RES(CHIPS)':
 'B': CDS_PINID='B';
NODE_NAME     U269 1
 '@T6G_MB_LIB.T6G(SCH_1):PAGE369_I142@PURE_QUANTA.ADC128D818CIMTXNOPB(CHIPS)':
 'VREF': CDS_PINID='VREF';
NET_NAME
'AGND_HSC'
 '@T6G_MB_LIB.T6G(SCH_1):AGND_HSC':
 C_SIGNAL='@t6g_mb_lib.t6g(sch_1):agnd_hsc',
 CDS_GLOBAL_NET='TRUE';
NODE_NAME     PC2183 2
 '@T6G_MB_LIB.T6G(SCH_1):PAGE301_I2@PURE_QUANTA.Q_CAP(CHIPS)':
 'B': CDS_PINID='B';
NODE_NAME     PC2181 2
 '@T6G_MB_LIB.T6G(SCH_1):PAGE301_I4@PURE_QUANTA.Q_CAP(CHIPS)':
 'B': CDS_PINID='B';
NODE_NAME     PR3912 1
 '@T6G_MB_LIB.T6G(SCH_1):PAGE301_I11@PURE_QUANTA.Q_RES(CHIPS)':
 'A': CDS_PINID='A';
NODE_NAME     PC2348 2
 '@T6G_MB_LIB.T6G(SCH_1):PAGE301_I12@PURE_QUANTA.Q_CAP(CHIPS)':
 'B': CDS_PINID='B';
NODE_NAME     PR3915 2
 '@T6G_MB_LIB.T6G(SCH_1):PAGE301_I13@PURE_QUANTA.Q_RES(CHIPS)':
 'B': CDS_PINID='B';
NODE_NAME     PR1101 2
 '@T6G_MB_LIB.T6G(SCH_1):PAGE301_I15@PURE_QUANTA.Q_RES(CHIPS)':
 'B': CDS_PINID='B';
NODE_NAME     PU288 20
 '@T6G_MB_LIB.T6G(SCH_1):PAGE301_I16@PURE_QUANTA.MP5991GLUZ(CHIPS)':
 'GND': CDS_PINID='GND';
NODE_NAME     PC1525 2
 '@T6G_MB_LIB.T6G(SCH_1):PAGE301_I20@PURE_QUANTA.Q_CAP(CHIPS)':
 'B': CDS_PINID='B';
NODE_NAME     PC2182 2
 '@T6G_MB_LIB.T6G(SCH_1):PAGE301_I24@PURE_QUANTA.Q_CAP(CHIPS)':
 'B': CDS_PINID='B';
NODE_NAME     PR1134 1
 '@T6G_MB_LIB.T6G(SCH_1):PAGE301_I29@PURE_QUANTA.Q_RES(CHIPS)':
 'A': CDS_PINID='A';
NODE_NAME     PC2347 2
 '@T6G_MB_LIB.T6G(SCH_1):PAGE301_I30@PURE_QUANTA.Q_CAP(CHIPS)':
 'B': CDS_PINID='B';
NODE_NAME     PR3914 2
 '@T6G_MB_LIB.T6G(SCH_1):PAGE301_I31@PURE_QUANTA.Q_RES(CHIPS)':
 'B': CDS_PINID='B';
NODE_NAME     PR3918 2
 '@T6G_MB_LIB.T6G(SCH_1):PAGE301_I34@PURE_QUANTA.Q_RES(CHIPS)':
 'B': CDS_PINID='B';
NODE_NAME     PU287 20
 '@T6G_MB_LIB.T6G(SCH_1):PAGE301_I35@PURE_QUANTA.MP5991GLUZ(CHIPS)':
 'GND': CDS_PINID='GND';
NODE_NAME     PC2185 2
 '@T6G_MB_LIB.T6G(SCH_1):PAGE301_I38@PURE_QUANTA.Q_CAP(CHIPS)':
 'B': CDS_PINID='B';
NODE_NAME     PC2184 2
 '@T6G_MB_LIB.T6G(SCH_1):PAGE301_I47@PURE_QUANTA.Q_CAP(CHIPS)':
 'B': CDS_PINID='B';
NODE_NAME     PC2225 2
 '@T6G_MB_LIB.T6G(SCH_1):PAGE325_I2@PURE_QUANTA.Q_CAP(CHIPS)':
 'B': CDS_PINID='B';
NODE_NAME     PC2223 2
 '@T6G_MB_LIB.T6G(SCH_1):PAGE325_I4@PURE_QUANTA.Q_CAP(CHIPS)':
 'B': CDS_PINID='B';
NODE_NAME     PR3984 1
 '@T6G_MB_LIB.T6G(SCH_1):PAGE325_I11@PURE_QUANTA.Q_RES(CHIPS)':
 'A': CDS_PINID='A';
NODE_NAME     PC2349 2
 '@T6G_MB_LIB.T6G(SCH_1):PAGE325_I12@PURE_QUANTA.Q_CAP(CHIPS)':
 'B': CDS_PINID='B';
NODE_NAME     PR3987 2
 '@T6G_MB_LIB.T6G(SCH_1):PAGE325_I13@PURE_QUANTA.Q_RES(CHIPS)':
 'B': CDS_PINID='B';
NODE_NAME     PR3991 2
 '@T6G_MB_LIB.T6G(SCH_1):PAGE325_I14@PURE_QUANTA.Q_RES(CHIPS)':
 'B': CDS_PINID='B';
NODE_NAME     PU297 20
 '@T6G_MB_LIB.T6G(SCH_1):PAGE325_I17@PURE_QUANTA.MP5991GLUZ(CHIPS)':
 'GND': CDS_PINID='GND';
NODE_NAME     PC3272 2
 '@T6G_MB_LIB.T6G(SCH_1):PAGE325_I20@PURE_QUANTA.Q_CAP(CHIPS)':
 'B': CDS_PINID='B';
NODE_NAME     PC2224 2
 '@T6G_MB_LIB.T6G(SCH_1):PAGE325_I24@PURE_QUANTA.Q_CAP(CHIPS)':
 'B': CDS_PINID='B';
NODE_NAME     PR3982 1
 '@T6G_MB_LIB.T6G(SCH_1):PAGE325_I28@PURE_QUANTA.Q_RES(CHIPS)':
 'A': CDS_PINID='A';
NODE_NAME     PC2350 2
 '@T6G_MB_LIB.T6G(SCH_1):PAGE325_I30@PURE_QUANTA.Q_CAP(CHIPS)':
 'B': CDS_PINID='B';
NODE_NAME     PR3986 2
 '@T6G_MB_LIB.T6G(SCH_1):PAGE325_I31@PURE_QUANTA.Q_RES(CHIPS)':
 'B': CDS_PINID='B';
NODE_NAME     PR3990 2
 '@T6G_MB_LIB.T6G(SCH_1):PAGE325_I34@PURE_QUANTA.Q_RES(CHIPS)':
 'B': CDS_PINID='B';
NODE_NAME     PU296 20
 '@T6G_MB_LIB.T6G(SCH_1):PAGE325_I35@PURE_QUANTA.MP5991GLUZ(CHIPS)':
 'GND': CDS_PINID='GND';
NODE_NAME     PC2227 2
 '@T6G_MB_LIB.T6G(SCH_1):PAGE325_I38@PURE_QUANTA.Q_CAP(CHIPS)':
 'B': CDS_PINID='B';
NODE_NAME     PC2226 2
 '@T6G_MB_LIB.T6G(SCH_1):PAGE325_I47@PURE_QUANTA.Q_CAP(CHIPS)':
 'B': CDS_PINID='B';
NODE_NAME     R1117 2
 '@T6G_MB_LIB.T6G(SCH_1):PAGE267_I22@PURE_QUANTA.Q_RES(CHIPS)':
 'B': CDS_PINID='B';
NODE_NAME     PC2186 2
 '@T6G_MB_LIB.T6G(SCH_1):PAGE267_I27@PURE_QUANTA.Q_CAP(CHIPS)':
 'B': CDS_PINID='B';
NODE_NAME     PC2187 2
 '@T6G_MB_LIB.T6G(SCH_1):PAGE267_I30@PURE_QUANTA.Q_CAP(CHIPS)':
 'B': CDS_PINID='B';
NODE_NAME     PR3927 2
 '@T6G_MB_LIB.T6G(SCH_1):PAGE267_I47@PURE_QUANTA.Q_RES(CHIPS)':
 'B': CDS_PINID='B';
NODE_NAME     PC2103 2
 '@T6G_MB_LIB.T6G(SCH_1):PAGE267_I50@PURE_QUANTA.Q_CAP(CHIPS)':
 'B': CDS_PINID='B';
NODE_NAME     PR3930 1
 '@T6G_MB_LIB.T6G(SCH_1):PAGE267_I52@PURE_QUANTA.Q_RES(CHIPS)':
 'A': CDS_PINID='A';
NODE_NAME     PU289 18
 '@T6G_MB_LIB.T6G(SCH_1):PAGE267_I58@PURE_QUANTA.MP5990GMA1111Z(CHIPS)':
 'GND1': CDS_PINID='GND1';
NODE_NAME     PU289 44
 '@T6G_MB_LIB.T6G(SCH_1):PAGE267_I58@PURE_QUANTA.MP5990GMA1111Z(CHIPS)':
 'GND2': CDS_PINID='GND2';
NODE_NAME     PC2189 2
 '@T6G_MB_LIB.T6G(SCH_1):PAGE267_I59@PURE_QUANTA.Q_CAP(CHIPS)':
 'B': CDS_PINID='B';
NODE_NAME     PR1131 2
 '@T6G_MB_LIB.T6G(SCH_1):PAGE267_I65@PURE_QUANTA.Q_RES(CHIPS)':
 'B': CDS_PINID='B';
NODE_NAME     PR3932 2
 '@T6G_MB_LIB.T6G(SCH_1):PAGE267_I70@PURE_QUANTA.Q_RES(CHIPS)':
 'B': CDS_PINID='B';
NODE_NAME     PC2190 2
 '@T6G_MB_LIB.T6G(SCH_1):PAGE267_I72@PURE_QUANTA.Q_CAP(CHIPS)':
 'B': CDS_PINID='B';
NODE_NAME     PC2191 2
 '@T6G_MB_LIB.T6G(SCH_1):PAGE267_I75@PURE_QUANTA.Q_CAP(CHIPS)':
 'B': CDS_PINID='B';
NODE_NAME     PC2192 2
 '@T6G_MB_LIB.T6G(SCH_1):PAGE267_I78@PURE_QUANTA.Q_CAP(CHIPS)':
 'B': CDS_PINID='B';
NODE_NAME     PR3935 2
 '@T6G_MB_LIB.T6G(SCH_1):PAGE267_I81@PURE_QUANTA.Q_RES(CHIPS)':
 'B': CDS_PINID='B';
NODE_NAME     PC2193 2
 '@T6G_MB_LIB.T6G(SCH_1):PAGE267_I84@PURE_QUANTA.Q_CAP(CHIPS)':
 'B': CDS_PINID='B';
NODE_NAME     PR3937 2
 '@T6G_MB_LIB.T6G(SCH_1):PAGE267_I85@PURE_QUANTA.Q_RES(CHIPS)':
 'B': CDS_PINID='B';
NODE_NAME     PR1133 2
 '@T6G_MB_LIB.T6G(SCH_1):PAGE267_I86@PURE_QUANTA.Q_RES(CHIPS)':
 'B': CDS_PINID='B';
NODE_NAME     PR3002 2
 '@T6G_MB_LIB.T6G(SCH_1):PAGE372_I27@PURE_QUANTA.Q_RES(CHIPS)':
 'B': CDS_PINID='B';
NET_NAME
'APML_CPU0_ALERT_N'
 '@T6G_MB_LIB.T6G(SCH_1):APML_CPU0_ALERT_N':
 C_SIGNAL='@t6g_mb_lib.t6g(sch_1):apml_cpu0_alert_n';
NODE_NAME     U25 A68
 '@T6G_MB_LIB.T6G(SCH_1):PAGE27_I227@PURE_QUANTA.GENOA_SP5(CHIPS)':
 'ALERT_L': CDS_PINID='ALERT_L';
NODE_NAME     R418 1
 '@T6G_MB_LIB.T6G(SCH_1):PAGE27_I378@PURE_QUANTA.Q_RES(CHIPS)':
 'A': CDS_PINID='A';
NODE_NAME     R247 1
 '@T6G_MB_LIB.T6G(SCH_1):PAGE27_I401@PURE_QUANTA.Q_RES(CHIPS)':
 'A': CDS_PINID='A';
NET_NAME
'APML_CPU0_ALERT_R_N'
 '@T6G_MB_LIB.T6G(SCH_1):APML_CPU0_ALERT_R_N':
 C_SIGNAL='@t6g_mb_lib.t6g(sch_1):apml_cpu0_alert_r_n';
NODE_NAME     R247 2
 '@T6G_MB_LIB.T6G(SCH_1):PAGE27_I401@PURE_QUANTA.Q_RES(CHIPS)':
 'B': CDS_PINID='B';
NODE_NAME     U18 L17
 '@T6G_MB_LIB.T6G(SCH_1):PAGE80_I217@PURE_QUANTA.LCMXO3LF9400C5BG484C(CHIPS)':
 'PR14A': CDS_PINID='PR14A';
NET_NAME
'APML_CPU1_ALERT_N'
 '@T6G_MB_LIB.T6G(SCH_1):APML_CPU1_ALERT_N':
 C_SIGNAL='@t6g_mb_lib.t6g(sch_1):apml_cpu1_alert_n';
NODE_NAME     U26 A68
 '@T6G_MB_LIB.T6G(SCH_1):PAGE54_I190@PURE_QUANTA.GENOA_SP5(CHIPS)':
 'ALERT_L': CDS_PINID='ALERT_L';
NODE_NAME     R535 1
 '@T6G_MB_LIB.T6G(SCH_1):PAGE54_I398@PURE_QUANTA.Q_RES(CHIPS)':
 'A': CDS_PINID='A';
NODE_NAME     R497 1
 '@T6G_MB_LIB.T6G(SCH_1):PAGE54_I417@PURE_QUANTA.Q_RES(CHIPS)':
 'A': CDS_PINID='A';
NET_NAME
'APML_CPU1_ALERT_R_N'
 '@T6G_MB_LIB.T6G(SCH_1):APML_CPU1_ALERT_R_N':
 C_SIGNAL='@t6g_mb_lib.t6g(sch_1):apml_cpu1_alert_r_n';
NODE_NAME     R497 2
 '@T6G_MB_LIB.T6G(SCH_1):PAGE54_I417@PURE_QUANTA.Q_RES(CHIPS)':
 'B': CDS_PINID='B';
NODE_NAME     U18 K16
 '@T6G_MB_LIB.T6G(SCH_1):PAGE80_I217@PURE_QUANTA.LCMXO3LF9400C5BG484C(CHIPS)':
 'PR13D': CDS_PINID='PR13D';
NET_NAME
'A_HSC_HIGH'
 '@T6G_MB_LIB.T6G(SCH_1):A_HSC_HIGH':
 C_SIGNAL='@t6g_mb_lib.t6g(sch_1):a_hsc_high';
NODE_NAME     U142 4
 '@T6G_MB_LIB.T6G(SCH_1):PAGE371_I50@PURE_QUANTA.LT6700CS61TRPBF(CHIPS)':
 'INB-': CDS_PINID='\inb-\';
NODE_NAME     R6234 2
 '@T6G_MB_LIB.T6G(SCH_1):PAGE371_I55@PURE_QUANTA.Q_RES(CHIPS)':
 'B': CDS_PINID='B';
NODE_NAME     R6235 1
 '@T6G_MB_LIB.T6G(SCH_1):PAGE371_I58@PURE_QUANTA.Q_RES(CHIPS)':
 'A': CDS_PINID='A';
NET_NAME
'A_HSC_LOW'
 '@T6G_MB_LIB.T6G(SCH_1):A_HSC_LOW':
 C_SIGNAL='@t6g_mb_lib.t6g(sch_1):a_hsc_low';
NODE_NAME     U142 3
 '@T6G_MB_LIB.T6G(SCH_1):PAGE371_I50@PURE_QUANTA.LT6700CS61TRPBF(CHIPS)':
 'INA+': CDS_PINID='\ina+\';
NODE_NAME     R6232 2
 '@T6G_MB_LIB.T6G(SCH_1):PAGE371_I56@PURE_QUANTA.Q_RES(CHIPS)':
 'B': CDS_PINID='B';
NODE_NAME     R6233 1
 '@T6G_MB_LIB.T6G(SCH_1):PAGE371_I57@PURE_QUANTA.Q_RES(CHIPS)':
 'A': CDS_PINID='A';
NET_NAME
'A_HSC_LOW_DRAIN'
 '@T6G_MB_LIB.T6G(SCH_1):A_HSC_LOW_DRAIN':
 C_SIGNAL='@t6g_mb_lib.t6g(sch_1):a_hsc_low_drain';
NODE_NAME     U6004 D
 '@T6G_MB_LIB.T6G(SCH_1):PAGE371_I68@PURE_QUANTA.MOSFET_NCH_GDS_ESD_PROTECTED(CHIPS)':
 'D': CDS_PINID='D';
NODE_NAME     R6238 1
 '@T6G_MB_LIB.T6G(SCH_1):PAGE371_I72@PURE_QUANTA.Q_RES(CHIPS)':
 'A': CDS_PINID='A';
NET_NAME
'A_HSC_LOW_GATE'
 '@T6G_MB_LIB.T6G(SCH_1):A_HSC_LOW_GATE':
 C_SIGNAL='@t6g_mb_lib.t6g(sch_1):a_hsc_low_gate';
NODE_NAME     U142 1
 '@T6G_MB_LIB.T6G(SCH_1):PAGE371_I50@PURE_QUANTA.LT6700CS61TRPBF(CHIPS)':
 'OUTA': CDS_PINID='OUTA';
NODE_NAME     R6236 2
 '@T6G_MB_LIB.T6G(SCH_1):PAGE371_I63@PURE_QUANTA.Q_RES(CHIPS)':
 'B': CDS_PINID='B';
NODE_NAME     R6237 1
 '@T6G_MB_LIB.T6G(SCH_1):PAGE371_I66@PURE_QUANTA.Q_RES(CHIPS)':
 'A': CDS_PINID='A';
NODE_NAME     U6004 G
 '@T6G_MB_LIB.T6G(SCH_1):PAGE371_I68@PURE_QUANTA.MOSFET_NCH_GDS_ESD_PROTECTED(CHIPS)':
 'G': CDS_PINID='G';
NODE_NAME     R8110 2
 '@T6G_MB_LIB.T6G(SCH_1):PAGE371_I96@PURE_QUANTA.Q_RES(CHIPS)':
 'B': CDS_PINID='B';
NODE_NAME     R8111 2
 '@T6G_MB_LIB.T6G(SCH_1):PAGE371_I98@PURE_QUANTA.Q_RES(CHIPS)':
 'B': CDS_PINID='B';
NET_NAME
'A_P12V_STBY_ADR_TRIGGER'
 '@T6G_MB_LIB.T6G(SCH_1):A_P12V_STBY_ADR_TRIGGER':
 C_SIGNAL='@t6g_mb_lib.t6g(sch_1):a_p12v_stby_adr_trigger';
NODE_NAME     R2227 1
 '@T6G_MB_LIB.T6G(SCH_1):PAGE372_I29@PURE_QUANTA.Q_RES(CHIPS)':
 'A': CDS_PINID='A';
NODE_NAME     R2219 2
 '@T6G_MB_LIB.T6G(SCH_1):PAGE372_I30@PURE_QUANTA.Q_RES(CHIPS)':
 'B': CDS_PINID='B';
NODE_NAME     U206 3
 '@T6G_MB_LIB.T6G(SCH_1):PAGE372_I49@PURE_QUANTA.LT6700CS61TRPBF(CHIPS)':
 'INA+': CDS_PINID='\ina+\';
NET_NAME
'A_P12V_STBY_FPH_GATE'
 '@T6G_MB_LIB.T6G(SCH_1):A_P12V_STBY_FPH_GATE':
 C_SIGNAL='@t6g_mb_lib.t6g(sch_1):a_p12v_stby_fph_gate';
NODE_NAME     U325 G
 '@T6G_MB_LIB.T6G(SCH_1):PAGE372_I42@PURE_QUANTA.MOSFET_N(CHIPS)':
 'GATE': CDS_PINID='GATE';
NODE_NAME     R2230 2
 '@T6G_MB_LIB.T6G(SCH_1):PAGE372_I43@PURE_QUANTA.Q_RES(CHIPS)':
 'B': CDS_PINID='B';
NODE_NAME     U206 6
 '@T6G_MB_LIB.T6G(SCH_1):PAGE372_I49@PURE_QUANTA.LT6700CS61TRPBF(CHIPS)':
 'OUTB': CDS_PINID='OUTB';
NET_NAME
'A_P12V_STBY_FP_TRIGGER'
 '@T6G_MB_LIB.T6G(SCH_1):A_P12V_STBY_FP_TRIGGER':
 C_SIGNAL='@t6g_mb_lib.t6g(sch_1):a_p12v_stby_fp_trigger';
NODE_NAME     R2222 1
 '@T6G_MB_LIB.T6G(SCH_1):PAGE372_I33@PURE_QUANTA.Q_RES(CHIPS)':
 'A': CDS_PINID='A';
NODE_NAME     R2221 2
 '@T6G_MB_LIB.T6G(SCH_1):PAGE372_I35@PURE_QUANTA.Q_RES(CHIPS)':
 'B': CDS_PINID='B';
NODE_NAME     U206 4
 '@T6G_MB_LIB.T6G(SCH_1):PAGE372_I49@PURE_QUANTA.LT6700CS61TRPBF(CHIPS)':
 'INB-': CDS_PINID='\inb-\';
NET_NAME
'BAT_LDO_EN'
 '@T6G_MB_LIB.T6G(SCH_1):BAT_LDO_EN':
 C_SIGNAL='@t6g_mb_lib.t6g(sch_1):bat_ldo_en';
NODE_NAME     U9 3
 '@T6G_MB_LIB.T6G(SCH_1):PAGE156_I91@PURE_QUANTA.TPS71715DCKR(CHIPS)':
 'EN': CDS_PINID='EN';
NODE_NAME     Q8 3
 '@T6G_MB_LIB.T6G(SCH_1):PAGE156_I104@PURE_QUANTA.MOSFET_DUAL_6P(CHIPS)':
 'D2': CDS_PINID='D2';
NODE_NAME     R1777 2
 '@T6G_MB_LIB.T6G(SCH_1):PAGE156_I129@PURE_QUANTA.Q_RES(CHIPS)':
 'B': CDS_PINID='B';
NODE_NAME     U167 4
 '@T6G_MB_LIB.T6G(SCH_1):PAGE156_I130@PURE_QUANTA.NCP698SQ15T1G(CHIPS)':
 'EN': CDS_PINID='EN';
NET_NAME
'BIC_MONITER'
 '@T6G_MB_LIB.T6G(SCH_1):BIC_MONITER':
 C_SIGNAL='@t6g_mb_lib.t6g(sch_1):bic_moniter';
NODE_NAME     Q67 2
 '@T6G_MB_LIB.T6G(SCH_1):PAGE333_I33@PURE_QUANTA.MOSFET_NCH_DUAL(CHIPS)':
 'G1': CDS_PINID='G1';
NODE_NAME     R2831 1
 '@T6G_MB_LIB.T6G(SCH_1):PAGE333_I56@PURE_QUANTA.Q_RES(CHIPS)':
 'A': CDS_PINID='A';
NODE_NAME     R2830 2
 '@T6G_MB_LIB.T6G(SCH_1):PAGE333_I68@PURE_QUANTA.Q_RES(CHIPS)':
 'B': CDS_PINID='B';
NODE_NAME     J109 A3
 '@T6G_MB_LIB.T6G(SCH_1):PAGE319_I76@PURE_QUANTA.CONN112_10137002101LF(CHIPS)':
 'A3': CDS_PINID='A3';
NET_NAME
'BIC_MONITER_ISO'
 '@T6G_MB_LIB.T6G(SCH_1):BIC_MONITER_ISO':
 C_SIGNAL='@t6g_mb_lib.t6g(sch_1):bic_moniter_iso';
NODE_NAME     Q67 3
 '@T6G_MB_LIB.T6G(SCH_1):PAGE333_I82@PURE_QUANTA.MOSFET_NCH_DUAL(CHIPS)':
 'D2': CDS_PINID='D2';
NODE_NAME     C1773 1
 '@T6G_MB_LIB.T6G(SCH_1):PAGE333_I114@PURE_QUANTA.Q_CAP(CHIPS)':
 'A': CDS_PINID='A';
NODE_NAME     R2846 2
 '@T6G_MB_LIB.T6G(SCH_1):PAGE80_I262@PURE_QUANTA.Q_RES(CHIPS)':
 'B': CDS_PINID='B';
NODE_NAME     R2920 2
 '@T6G_MB_LIB.T6G(SCH_1):PAGE333_I177@PURE_QUANTA.Q_RES(CHIPS)':
 'B': CDS_PINID='B';
NET_NAME
'BIC_MONITER_ISO_R'
 '@T6G_MB_LIB.T6G(SCH_1):BIC_MONITER_ISO_R':
 C_SIGNAL='@t6g_mb_lib.t6g(sch_1):bic_moniter_iso_r';
NODE_NAME     U18 V15
 '@T6G_MB_LIB.T6G(SCH_1):PAGE80_I216@PURE_QUANTA.LCMXO3LF9400C5BG484C(CHIPS)':
 'PB38C': CDS_PINID='PB38C';
NODE_NAME     R2846 1
 '@T6G_MB_LIB.T6G(SCH_1):PAGE80_I262@PURE_QUANTA.Q_RES(CHIPS)':
 'A': CDS_PINID='A';
NET_NAME
'BIC_MONITER_N'
 '@T6G_MB_LIB.T6G(SCH_1):BIC_MONITER_N':
 C_SIGNAL='@t6g_mb_lib.t6g(sch_1):bic_moniter_n';
NODE_NAME     R2835 2
 '@T6G_MB_LIB.T6G(SCH_1):PAGE333_I14@PURE_QUANTA.Q_RES(CHIPS)':
 'B': CDS_PINID='B';
NODE_NAME     Q67 6
 '@T6G_MB_LIB.T6G(SCH_1):PAGE333_I33@PURE_QUANTA.MOSFET_NCH_DUAL(CHIPS)':
 'D1': CDS_PINID='D1';
NODE_NAME     Q67 5
 '@T6G_MB_LIB.T6G(SCH_1):PAGE333_I82@PURE_QUANTA.MOSFET_NCH_DUAL(CHIPS)':
 'G2': CDS_PINID='G2';
NET_NAME
'BIOS_DEBUG_MODE'
 '@T6G_MB_LIB.T6G(SCH_1):BIOS_DEBUG_MODE':
 C_SIGNAL='@t6g_mb_lib.t6g(sch_1):bios_debug_mode';
NODE_NAME     Q30 G
 '@T6G_MB_LIB.T6G(SCH_1):PAGE142_I81@PURE_QUANTA.MOSFET_N_GSD(CHIPS)':
 'GATE': CDS_PINID='GATE';
NODE_NAME     R1264 2
 '@T6G_MB_LIB.T6G(SCH_1):PAGE144_I44@PURE_QUANTA.Q_RES(CHIPS)':
 'B': CDS_PINID='B';
NODE_NAME     R1203 2
 '@T6G_MB_LIB.T6G(SCH_1):PAGE80_I178@PURE_QUANTA.Q_RES(CHIPS)':
 'B': CDS_PINID='B';
NODE_NAME     U25 DE30
 '@T6G_MB_LIB.T6G(SCH_1):PAGE28_I188@PURE_QUANTA.GENOA_SP5(CHIPS)':
 'AGPIO105': CDS_PINID='AGPIO105';
NODE_NAME     R6107 2
 '@T6G_MB_LIB.T6G(SCH_1):PAGE144_I83@PURE_QUANTA.Q_RES(CHIPS)':
 'B': CDS_PINID='B';
NODE_NAME     SW1 16
 '@T6G_MB_LIB.T6G(SCH_1):PAGE144_I90@PURE_QUANTA.SW20S_DHNF10FQTR(CHIPS)':
 '16': CDS_PINID='\16\';
NET_NAME
'BIOS_DEBUG_MODE_R'
 '@T6G_MB_LIB.T6G(SCH_1):BIOS_DEBUG_MODE_R':
 C_SIGNAL='@t6g_mb_lib.t6g(sch_1):bios_debug_mode_r';
NODE_NAME     R1203 1
 '@T6G_MB_LIB.T6G(SCH_1):PAGE80_I178@PURE_QUANTA.Q_RES(CHIPS)':
 'A': CDS_PINID='A';
NODE_NAME     U18 N22
 '@T6G_MB_LIB.T6G(SCH_1):PAGE80_I217@PURE_QUANTA.LCMXO3LF9400C5BG484C(CHIPS)':
 'PR19A': CDS_PINID='PR19A';
NET_NAME
'BMC_FPGA_LED1'
 '@T6G_MB_LIB.T6G(SCH_1):BMC_FPGA_LED1':
 C_SIGNAL='@t6g_mb_lib.t6g(sch_1):bmc_fpga_led1';
NODE_NAME     U18 AB10
 '@T6G_MB_LIB.T6G(SCH_1):PAGE80_I216@PURE_QUANTA.LCMXO3LF9400C5BG484C(CHIPS)':
 'PB22B||PCLKC2_0': CDS_PINID='\pb22b||pclkc2_0\';
NODE_NAME     Q28 2
 '@T6G_MB_LIB.T6G(SCH_1):PAGE84_I48@PURE_QUANTA.MOSFET_DUAL_6P(CHIPS)':
 'G1': CDS_PINID='G1';
NET_NAME
'BMC_FPGA_LED1_N'
 '@T6G_MB_LIB.T6G(SCH_1):BMC_FPGA_LED1_N':
 C_SIGNAL='@t6g_mb_lib.t6g(sch_1):bmc_fpga_led1_n';
NODE_NAME     Q28 6
 '@T6G_MB_LIB.T6G(SCH_1):PAGE84_I48@PURE_QUANTA.MOSFET_DUAL_6P(CHIPS)':
 'D1': CDS_PINID='D1';
NODE_NAME     D8 C
 '@T6G_MB_LIB.T6G(SCH_1):PAGE84_I97@PURE_QUANTA.Q_LED(CHIPS)':
 'C': CDS_PINID='C';
NET_NAME
'BMC_FPGA_LED1_R_N'
 '@T6G_MB_LIB.T6G(SCH_1):BMC_FPGA_LED1_R_N':
 C_SIGNAL='@t6g_mb_lib.t6g(sch_1):bmc_fpga_led1_r_n';
NODE_NAME     R1266 2
 '@T6G_MB_LIB.T6G(SCH_1):PAGE84_I45@PURE_QUANTA.Q_RES(CHIPS)':
 'B': CDS_PINID='B';
NODE_NAME     D8 A
 '@T6G_MB_LIB.T6G(SCH_1):PAGE84_I97@PURE_QUANTA.Q_LED(CHIPS)':
 'A': CDS_PINID='A';
NET_NAME
'BMC_FPGA_LED2'
 '@T6G_MB_LIB.T6G(SCH_1):BMC_FPGA_LED2':
 C_SIGNAL='@t6g_mb_lib.t6g(sch_1):bmc_fpga_led2';
NODE_NAME     U18 Y10
 '@T6G_MB_LIB.T6G(SCH_1):PAGE80_I216@PURE_QUANTA.LCMXO3LF9400C5BG484C(CHIPS)':
 'PB21D': CDS_PINID='PB21D';
NODE_NAME     Q28 5
 '@T6G_MB_LIB.T6G(SCH_1):PAGE84_I48@PURE_QUANTA.MOSFET_DUAL_6P(CHIPS)':
 'G2': CDS_PINID='G2';
NET_NAME
'BMC_FPGA_LED2_N'
 '@T6G_MB_LIB.T6G(SCH_1):BMC_FPGA_LED2_N':
 C_SIGNAL='@t6g_mb_lib.t6g(sch_1):bmc_fpga_led2_n';
NODE_NAME     Q28 3
 '@T6G_MB_LIB.T6G(SCH_1):PAGE84_I48@PURE_QUANTA.MOSFET_DUAL_6P(CHIPS)':
 'D2': CDS_PINID='D2';
NODE_NAME     D7 C
 '@T6G_MB_LIB.T6G(SCH_1):PAGE84_I96@PURE_QUANTA.Q_LED(CHIPS)':
 'C': CDS_PINID='C';
NET_NAME
'BMC_FPGA_LED2_R_N'
 '@T6G_MB_LIB.T6G(SCH_1):BMC_FPGA_LED2_R_N':
 C_SIGNAL='@t6g_mb_lib.t6g(sch_1):bmc_fpga_led2_r_n';
NODE_NAME     R1194 2
 '@T6G_MB_LIB.T6G(SCH_1):PAGE84_I46@PURE_QUANTA.Q_RES(CHIPS)':
 'B': CDS_PINID='B';
NODE_NAME     D7 A
 '@T6G_MB_LIB.T6G(SCH_1):PAGE84_I96@PURE_QUANTA.Q_LED(CHIPS)':
 'A': CDS_PINID='A';
NET_NAME
'BMC_JTAG_SEL'
 '@T6G_MB_LIB.T6G(SCH_1):BMC_JTAG_SEL':
 C_SIGNAL='@t6g_mb_lib.t6g(sch_1):bmc_jtag_sel';
NODE_NAME     R1359 2
 '@T6G_MB_LIB.T6G(SCH_1):PAGE80_I158@PURE_QUANTA.Q_RES(CHIPS)':
 'B': CDS_PINID='B';
NODE_NAME     R1262 2
 '@T6G_MB_LIB.T6G(SCH_1):PAGE144_I30@PURE_QUANTA.Q_RES(CHIPS)':
 'B': CDS_PINID='B';
NODE_NAME     SW1 13
 '@T6G_MB_LIB.T6G(SCH_1):PAGE144_I90@PURE_QUANTA.SW20S_DHNF10FQTR(CHIPS)':
 '13': CDS_PINID='\13\';
NET_NAME
'BMC_JTAG_SEL_R'
 '@T6G_MB_LIB.T6G(SCH_1):BMC_JTAG_SEL_R':
 C_SIGNAL='@t6g_mb_lib.t6g(sch_1):bmc_jtag_sel_r';
NODE_NAME     R1359 1
 '@T6G_MB_LIB.T6G(SCH_1):PAGE80_I158@PURE_QUANTA.Q_RES(CHIPS)':
 'A': CDS_PINID='A';
NODE_NAME     U18 U20
 '@T6G_MB_LIB.T6G(SCH_1):PAGE80_I217@PURE_QUANTA.LCMXO3LF9400C5BG484C(CHIPS)':
 'PR27D': CDS_PINID='PR27D';
NET_NAME
'BMC_MONITER'
 '@T6G_MB_LIB.T6G(SCH_1):BMC_MONITER':
 C_SIGNAL='@t6g_mb_lib.t6g(sch_1):bmc_moniter';
NODE_NAME     U18 AB5
 '@T6G_MB_LIB.T6G(SCH_1):PAGE80_I216@PURE_QUANTA.LCMXO3LF9400C5BG484C(CHIPS)':
 'PB10B': CDS_PINID='PB10B';
NODE_NAME     R2845 2
 '@T6G_MB_LIB.T6G(SCH_1):PAGE80_I293@PURE_QUANTA.Q_RES(CHIPS)':
 'B': CDS_PINID='B';
NET_NAME
'BMC_MONITER_BUF'
 '@T6G_MB_LIB.T6G(SCH_1):BMC_MONITER_BUF':
 C_SIGNAL='@t6g_mb_lib.t6g(sch_1):bmc_moniter_buf';
NODE_NAME     R2917 2
 '@T6G_MB_LIB.T6G(SCH_1):PAGE256_I154@PURE_QUANTA.Q_RES(CHIPS)':
 'B': CDS_PINID='B';
NODE_NAME     J109 A1
 '@T6G_MB_LIB.T6G(SCH_1):PAGE319_I76@PURE_QUANTA.CONN112_10137002101LF(CHIPS)':
 'A1': CDS_PINID='A1';
NET_NAME
'BMC_MONITER_BUF_R'
 '@T6G_MB_LIB.T6G(SCH_1):BMC_MONITER_BUF_R':
 C_SIGNAL='@t6g_mb_lib.t6g(sch_1):bmc_moniter_buf_r';
NODE_NAME     U195 6
 '@T6G_MB_LIB.T6G(SCH_1):PAGE256_I65@PURE_QUANTA.74LVC2G17GW(CHIPS)':
 'B0': CDS_PINID='B0';
NODE_NAME     R2820 2
 '@T6G_MB_LIB.T6G(SCH_1):PAGE256_I78@PURE_QUANTA.Q_RES(CHIPS)':
 'B': CDS_PINID='B';
NODE_NAME     R2926 1
 '@T6G_MB_LIB.T6G(SCH_1):PAGE256_I121@PURE_QUANTA.Q_RES(CHIPS)':
 'A': CDS_PINID='A';
NODE_NAME     R2917 1
 '@T6G_MB_LIB.T6G(SCH_1):PAGE256_I154@PURE_QUANTA.Q_RES(CHIPS)':
 'A': CDS_PINID='A';
NET_NAME
'BMC_MONITER_R'
 '@T6G_MB_LIB.T6G(SCH_1):BMC_MONITER_R':
 C_SIGNAL='@t6g_mb_lib.t6g(sch_1):bmc_moniter_r';
NODE_NAME     U195 1
 '@T6G_MB_LIB.T6G(SCH_1):PAGE256_I65@PURE_QUANTA.74LVC2G17GW(CHIPS)':
 'A0': CDS_PINID='A0';
NODE_NAME     R2815 2
 '@T6G_MB_LIB.T6G(SCH_1):PAGE256_I68@PURE_QUANTA.Q_RES(CHIPS)':
 'B': CDS_PINID='B';
NODE_NAME     R2915 1
 '@T6G_MB_LIB.T6G(SCH_1):PAGE256_I92@PURE_QUANTA.Q_RES(CHIPS)':
 'A': CDS_PINID='A';
NODE_NAME     R2845 1
 '@T6G_MB_LIB.T6G(SCH_1):PAGE80_I293@PURE_QUANTA.Q_RES(CHIPS)':
 'A': CDS_PINID='A';
NET_NAME
'BOOT_RDY_BUF_LED'
 '@T6G_MB_LIB.T6G(SCH_1):BOOT_RDY_BUF_LED':
 C_SIGNAL='@t6g_mb_lib.t6g(sch_1):boot_rdy_buf_led';
NODE_NAME     R944 2
 '@T6G_MB_LIB.T6G(SCH_1):PAGE143_I15@PURE_QUANTA.Q_RES(CHIPS)':
 'B': CDS_PINID='B';
NODE_NAME     Q2 2
 '@T6G_MB_LIB.T6G(SCH_1):PAGE143_I16@PURE_QUANTA.MOSFET_DUAL_6P(CHIPS)':
 'G1': CDS_PINID='G1';
NODE_NAME     R935 2
 '@T6G_MB_LIB.T6G(SCH_1):PAGE143_I21@PURE_QUANTA.Q_RES(CHIPS)':
 'B': CDS_PINID='B';
NET_NAME
'BOOT_RDY_BUF_R_LED'
 '@T6G_MB_LIB.T6G(SCH_1):BOOT_RDY_BUF_R_LED':
 C_SIGNAL='@t6g_mb_lib.t6g(sch_1):boot_rdy_buf_r_led';
NODE_NAME     R935 1
 '@T6G_MB_LIB.T6G(SCH_1):PAGE143_I21@PURE_QUANTA.Q_RES(CHIPS)':
 'A': CDS_PINID='A';
NODE_NAME     U82 4
 '@T6G_MB_LIB.T6G(SCH_1):PAGE143_I26@PURE_QUANTA.SN74LVC1G07DBVR(CHIPS)':
 'Y': CDS_PINID='Y';
NET_NAME
'BOOT_RDY_H'
 '@T6G_MB_LIB.T6G(SCH_1):BOOT_RDY_H':
 C_SIGNAL='@t6g_mb_lib.t6g(sch_1):boot_rdy_h';
NODE_NAME     R941 1
 '@T6G_MB_LIB.T6G(SCH_1):PAGE143_I34@PURE_QUANTA.Q_RES(CHIPS)':
 'A': CDS_PINID='A';
NODE_NAME     R938 1
 '@T6G_MB_LIB.T6G(SCH_1):PAGE28_I69@PURE_QUANTA.Q_RES(CHIPS)':
 'A': CDS_PINID='A';
NODE_NAME     R940 2
 '@T6G_MB_LIB.T6G(SCH_1):PAGE28_I94@PURE_QUANTA.Q_RES(CHIPS)':
 'B': CDS_PINID='B';
NET_NAME
'BOOT_RDY_LED'
 '@T6G_MB_LIB.T6G(SCH_1):BOOT_RDY_LED':
 C_SIGNAL='@t6g_mb_lib.t6g(sch_1):boot_rdy_led';
NODE_NAME     R946 2
 '@T6G_MB_LIB.T6G(SCH_1):PAGE143_I5@PURE_QUANTA.Q_RES(CHIPS)':
 'B': CDS_PINID='B';
NODE_NAME     Q2 6
 '@T6G_MB_LIB.T6G(SCH_1):PAGE143_I16@PURE_QUANTA.MOSFET_DUAL_6P(CHIPS)':
 'D1': CDS_PINID='D1';
NODE_NAME     Q2 5
 '@T6G_MB_LIB.T6G(SCH_1):PAGE143_I16@PURE_QUANTA.MOSFET_DUAL_6P(CHIPS)':
 'G2': CDS_PINID='G2';
NET_NAME
'BOOT_RDY_LED_N'
 '@T6G_MB_LIB.T6G(SCH_1):BOOT_RDY_LED_N':
 C_SIGNAL='@t6g_mb_lib.t6g(sch_1):boot_rdy_led_n';
NODE_NAME     D5 C
 '@T6G_MB_LIB.T6G(SCH_1):PAGE143_I8@PURE_QUANTA.Q_LED(CHIPS)':
 'C': CDS_PINID='C';
NODE_NAME     Q2 3
 '@T6G_MB_LIB.T6G(SCH_1):PAGE143_I16@PURE_QUANTA.MOSFET_DUAL_6P(CHIPS)':
 'D2': CDS_PINID='D2';
NET_NAME
'BOOT_RDY_R1_N'
 '@T6G_MB_LIB.T6G(SCH_1):BOOT_RDY_R1_N':
 C_SIGNAL='@t6g_mb_lib.t6g(sch_1):boot_rdy_r1_n';
NODE_NAME     U82 2
 '@T6G_MB_LIB.T6G(SCH_1):PAGE143_I26@PURE_QUANTA.SN74LVC1G07DBVR(CHIPS)':
 'A': CDS_PINID='A';
NODE_NAME     R934 2
 '@T6G_MB_LIB.T6G(SCH_1):PAGE143_I33@PURE_QUANTA.Q_RES(CHIPS)':
 'B': CDS_PINID='B';
NODE_NAME     R941 2
 '@T6G_MB_LIB.T6G(SCH_1):PAGE143_I34@PURE_QUANTA.Q_RES(CHIPS)':
 'B': CDS_PINID='B';
NET_NAME
'BOOT_RDY_R_H'
 '@T6G_MB_LIB.T6G(SCH_1):BOOT_RDY_R_H':
 C_SIGNAL='@t6g_mb_lib.t6g(sch_1):boot_rdy_r_h';
NODE_NAME     R940 1
 '@T6G_MB_LIB.T6G(SCH_1):PAGE28_I94@PURE_QUANTA.Q_RES(CHIPS)':
 'A': CDS_PINID='A';
NODE_NAME     U25 DH30
 '@T6G_MB_LIB.T6G(SCH_1):PAGE28_I188@PURE_QUANTA.GENOA_SP5(CHIPS)':
 'AGPIO104': CDS_PINID='AGPIO104';
NET_NAME
'BUF2_VDD'
 '@T6G_MB_LIB.T6G(SCH_1):BUF2_VDD':
 C_SIGNAL='@t6g_mb_lib.t6g(sch_1):buf2_vdd';
NODE_NAME     U6000 21
 '@T6G_MB_LIB.T6G(SCH_1):PAGE111_I1@PURE_QUANTA.DS125BR111RTWR(CHIPS)':
 'VDD_21': CDS_PINID='VDD_21';
NODE_NAME     U6000 22
 '@T6G_MB_LIB.T6G(SCH_1):PAGE111_I1@PURE_QUANTA.DS125BR111RTWR(CHIPS)':
 'VDD_22': CDS_PINID='VDD_22';
NODE_NAME     C6011 1
 '@T6G_MB_LIB.T6G(SCH_1):PAGE111_I6@PURE_QUANTA.Q_CAP(CHIPS)':
 'A': CDS_PINID='A';
NODE_NAME     C6012 1
 '@T6G_MB_LIB.T6G(SCH_1):PAGE111_I7@PURE_QUANTA.Q_CAP(CHIPS)':
 'A': CDS_PINID='A';
NET_NAME
'CLKREQ_RT_CPU0_P0_N'
 '@T6G_MB_LIB.T6G(SCH_1):CLKREQ_RT_CPU0_P0_N':
 C_SIGNAL='@t6g_mb_lib.t6g(sch_1):clkreq_rt_cpu0_p0_n';
NODE_NAME     U6010 G35
 '@T6G_MB_LIB.T6G(SCH_1):PAGE385_I53@PURE_QUANTA.PT5161LRS(CHIPS)':
 'CLKREQ_N': CDS_PINID='CLKREQ_N';
NODE_NAME     R1368 1
 '@T6G_MB_LIB.T6G(SCH_1):PAGE385_I119@PURE_QUANTA.Q_RES(CHIPS)':
 'A': CDS_PINID='A';
NET_NAME
'CLKREQ_RT_CPU0_P1_N'
 '@T6G_MB_LIB.T6G(SCH_1):CLKREQ_RT_CPU0_P1_N':
 C_SIGNAL='@t6g_mb_lib.t6g(sch_1):clkreq_rt_cpu0_p1_n';
NODE_NAME     U6011 G35
 '@T6G_MB_LIB.T6G(SCH_1):PAGE408_I83@PURE_QUANTA.PT5161LRS(CHIPS)':
 'CLKREQ_N': CDS_PINID='CLKREQ_N';
NODE_NAME     R1395 1
 '@T6G_MB_LIB.T6G(SCH_1):PAGE408_I94@PURE_QUANTA.Q_RES(CHIPS)':
 'A': CDS_PINID='A';
NET_NAME
'CLKREQ_RT_CPU0_P2_N'
 '@T6G_MB_LIB.T6G(SCH_1):CLKREQ_RT_CPU0_P2_N':
 C_SIGNAL='@t6g_mb_lib.t6g(sch_1):clkreq_rt_cpu0_p2_n';
NODE_NAME     U6012 G35
 '@T6G_MB_LIB.T6G(SCH_1):PAGE419_I83@PURE_QUANTA.PT5161LRS(CHIPS)':
 'CLKREQ_N': CDS_PINID='CLKREQ_N';
NODE_NAME     R1404 1
 '@T6G_MB_LIB.T6G(SCH_1):PAGE419_I99@PURE_QUANTA.Q_RES(CHIPS)':
 'A': CDS_PINID='A';
NET_NAME
'CLKREQ_RT_CPU0_P3_N'
 '@T6G_MB_LIB.T6G(SCH_1):CLKREQ_RT_CPU0_P3_N':
 C_SIGNAL='@t6g_mb_lib.t6g(sch_1):clkreq_rt_cpu0_p3_n';
NODE_NAME     U6013 G35
 '@T6G_MB_LIB.T6G(SCH_1):PAGE430_I83@PURE_QUANTA.PT5161LRS(CHIPS)':
 'CLKREQ_N': CDS_PINID='CLKREQ_N';
NODE_NAME     R1412 1
 '@T6G_MB_LIB.T6G(SCH_1):PAGE430_I101@PURE_QUANTA.Q_RES(CHIPS)':
 'A': CDS_PINID='A';
NET_NAME
'CLKREQ_RT_CPU1_P0_N'
 '@T6G_MB_LIB.T6G(SCH_1):CLKREQ_RT_CPU1_P0_N':
 C_SIGNAL='@t6g_mb_lib.t6g(sch_1):clkreq_rt_cpu1_p0_n';
NODE_NAME     U6014 G35
 '@T6G_MB_LIB.T6G(SCH_1):PAGE401_I1@PURE_QUANTA.PT5161LRS(CHIPS)':
 'CLKREQ_N': CDS_PINID='CLKREQ_N';
NODE_NAME     R1387 1
 '@T6G_MB_LIB.T6G(SCH_1):PAGE401_I108@PURE_QUANTA.Q_RES(CHIPS)':
 'A': CDS_PINID='A';
NET_NAME
'CLKREQ_RT_CPU1_P1_N'
 '@T6G_MB_LIB.T6G(SCH_1):CLKREQ_RT_CPU1_P1_N':
 C_SIGNAL='@t6g_mb_lib.t6g(sch_1):clkreq_rt_cpu1_p1_n';
NODE_NAME     U6015 G35
 '@T6G_MB_LIB.T6G(SCH_1):PAGE392_I47@PURE_QUANTA.PT5161LRS(CHIPS)':
 'CLKREQ_N': CDS_PINID='CLKREQ_N';
NODE_NAME     R1376 1
 '@T6G_MB_LIB.T6G(SCH_1):PAGE392_I111@PURE_QUANTA.Q_RES(CHIPS)':
 'A': CDS_PINID='A';
NET_NAME
'CLKREQ_RT_CPU1_P2_N'
 '@T6G_MB_LIB.T6G(SCH_1):CLKREQ_RT_CPU1_P2_N':
 C_SIGNAL='@t6g_mb_lib.t6g(sch_1):clkreq_rt_cpu1_p2_n';
NODE_NAME     U6016 G35
 '@T6G_MB_LIB.T6G(SCH_1):PAGE451_I97@PURE_QUANTA.PT5161LRS(CHIPS)':
 'CLKREQ_N': CDS_PINID='CLKREQ_N';
NODE_NAME     R1421 1
 '@T6G_MB_LIB.T6G(SCH_1):PAGE451_I98@PURE_QUANTA.Q_RES(CHIPS)':
 'A': CDS_PINID='A';
NET_NAME
'CLKREQ_RT_CPU1_P3_N'
 '@T6G_MB_LIB.T6G(SCH_1):CLKREQ_RT_CPU1_P3_N':
 C_SIGNAL='@t6g_mb_lib.t6g(sch_1):clkreq_rt_cpu1_p3_n';
NODE_NAME     U6017 G35
 '@T6G_MB_LIB.T6G(SCH_1):PAGE462_I97@PURE_QUANTA.PT5161LRS(CHIPS)':
 'CLKREQ_N': CDS_PINID='CLKREQ_N';
NODE_NAME     R1433 1
 '@T6G_MB_LIB.T6G(SCH_1):PAGE462_I98@PURE_QUANTA.Q_RES(CHIPS)':
 'A': CDS_PINID='A';
NET_NAME
'CLK_100M_BMC_RC_DN'
 '@T6G_MB_LIB.T6G(SCH_1):CLK_100M_BMC_RC_DN':
 C_SIGNAL='@t6g_mb_lib.t6g(sch_1):clk_100m_bmc_rc_dn';
NODE_NAME     J41 A69
 '@T6G_MB_LIB.T6G(SCH_1):PAGE348_I176@PURE_QUANTA.SCONN168_ME1016810202011(CHIPS)':
 'USB_DATP': CDS_PINID='USB_DATP';
NODE_NAME     R3336 2
 '@T6G_MB_LIB.T6G(SCH_1):PAGE232_I52@PURE_QUANTA.Q_RES(CHIPS)':
 'B': CDS_PINID='B';
NET_NAME
'CLK_100M_BMC_RC_DN_R'
 '@T6G_MB_LIB.T6G(SCH_1):CLK_100M_BMC_RC_DN_R':
 C_SIGNAL='@t6g_mb_lib.t6g(sch_1):clk_100m_bmc_rc_dn_r';
NODE_NAME     R3336 1
 '@T6G_MB_LIB.T6G(SCH_1):PAGE232_I52@PURE_QUANTA.Q_RES(CHIPS)':
 'A': CDS_PINID='A';
NODE_NAME     U247 14
 '@T6G_MB_LIB.T6G(SCH_1):PAGE232_I77@PURE_QUANTA.9FGL0251DKILFT(CHIPS)':
 'DIF0#': CDS_PINID='\dif0#\';
NET_NAME
'CLK_100M_BMC_RC_DP'
 '@T6G_MB_LIB.T6G(SCH_1):CLK_100M_BMC_RC_DP':
 C_SIGNAL='@t6g_mb_lib.t6g(sch_1):clk_100m_bmc_rc_dp';
NODE_NAME     J41 A68
 '@T6G_MB_LIB.T6G(SCH_1):PAGE348_I176@PURE_QUANTA.SCONN168_ME1016810202011(CHIPS)':
 'USB_DATN': CDS_PINID='USB_DATN';
NODE_NAME     R3335 2
 '@T6G_MB_LIB.T6G(SCH_1):PAGE232_I53@PURE_QUANTA.Q_RES(CHIPS)':
 'B': CDS_PINID='B';
NET_NAME
'CLK_100M_BMC_RC_DP_R'
 '@T6G_MB_LIB.T6G(SCH_1):CLK_100M_BMC_RC_DP_R':
 C_SIGNAL='@t6g_mb_lib.t6g(sch_1):clk_100m_bmc_rc_dp_r';
NODE_NAME     R3335 1
 '@T6G_MB_LIB.T6G(SCH_1):PAGE232_I53@PURE_QUANTA.Q_RES(CHIPS)':
 'A': CDS_PINID='A';
NODE_NAME     U247 13
 '@T6G_MB_LIB.T6G(SCH_1):PAGE232_I77@PURE_QUANTA.9FGL0251DKILFT(CHIPS)':
 'DIF0': CDS_PINID='DIF0';
NET_NAME
'CLK_100M_CPU0_CLK01_DN'
 '@T6G_MB_LIB.T6G(SCH_1):CLK_100M_CPU0_CLK01_DN':
 C_SIGNAL='@t6g_mb_lib.t6g(sch_1):clk_100m_cpu0_clk01_dn';
NODE_NAME     J41 A15
 '@T6G_MB_LIB.T6G(SCH_1):PAGE348_I176@PURE_QUANTA.SCONN168_ME1016810202011(CHIPS)':
 'REFCLKP1': CDS_PINID='REFCLKP1';
NODE_NAME     R4536 2
 '@T6G_MB_LIB.T6G(SCH_1):PAGE28_I161@PURE_QUANTA.Q_RES(CHIPS)':
 'B': CDS_PINID='B';
NET_NAME
'CLK_100M_CPU0_CLK01_DP'
 '@T6G_MB_LIB.T6G(SCH_1):CLK_100M_CPU0_CLK01_DP':
 C_SIGNAL='@t6g_mb_lib.t6g(sch_1):clk_100m_cpu0_clk01_dp';
NODE_NAME     J41 A14
 '@T6G_MB_LIB.T6G(SCH_1):PAGE348_I176@PURE_QUANTA.SCONN168_ME1016810202011(CHIPS)':
 'REFCLKN1': CDS_PINID='REFCLKN1';
NODE_NAME     R4535 2
 '@T6G_MB_LIB.T6G(SCH_1):PAGE28_I160@PURE_QUANTA.Q_RES(CHIPS)':
 'B': CDS_PINID='B';
NET_NAME
'CLK_100M_CPU0_CLK01_R_DN'
 '@T6G_MB_LIB.T6G(SCH_1):CLK_100M_CPU0_CLK01_R_DN':
 C_SIGNAL='@t6g_mb_lib.t6g(sch_1):clk_100m_cpu0_clk01_r_dn';
NODE_NAME     R4536 1
 '@T6G_MB_LIB.T6G(SCH_1):PAGE28_I161@PURE_QUANTA.Q_RES(CHIPS)':
 'A': CDS_PINID='A';
NODE_NAME     U25 A7
 '@T6G_MB_LIB.T6G(SCH_1):PAGE28_I188@PURE_QUANTA.GENOA_SP5(CHIPS)':
 'GPP_CLK01N': CDS_PINID='GPP_CLK01N';
NET_NAME
'CLK_100M_CPU0_CLK01_R_DP'
 '@T6G_MB_LIB.T6G(SCH_1):CLK_100M_CPU0_CLK01_R_DP':
 C_SIGNAL='@t6g_mb_lib.t6g(sch_1):clk_100m_cpu0_clk01_r_dp';
NODE_NAME     R4535 1
 '@T6G_MB_LIB.T6G(SCH_1):PAGE28_I160@PURE_QUANTA.Q_RES(CHIPS)':
 'A': CDS_PINID='A';
NODE_NAME     U25 A8
 '@T6G_MB_LIB.T6G(SCH_1):PAGE28_I188@PURE_QUANTA.GENOA_SP5(CHIPS)':
 'GPP_CLK01P': CDS_PINID='GPP_CLK01P';
NET_NAME
'CLK_100M_CPU0_CLK02_DN'
 '@T6G_MB_LIB.T6G(SCH_1):CLK_100M_CPU0_CLK02_DN':
 C_SIGNAL='@t6g_mb_lib.t6g(sch_1):clk_100m_cpu0_clk02_dn';
NODE_NAME     J38 B14
 '@T6G_MB_LIB.T6G(SCH_1):PAGE335_I168@PURE_QUANTA.SCONN168_ME1016810202011(CHIPS)':
 'REFCLKN0': CDS_PINID='REFCLKN0';
NODE_NAME     R8564 2
 '@T6G_MB_LIB.T6G(SCH_1):PAGE28_I156@PURE_QUANTA.Q_RES(CHIPS)':
 'B': CDS_PINID='B';
NET_NAME
'CLK_100M_CPU0_CLK02_DP'
 '@T6G_MB_LIB.T6G(SCH_1):CLK_100M_CPU0_CLK02_DP':
 C_SIGNAL='@t6g_mb_lib.t6g(sch_1):clk_100m_cpu0_clk02_dp';
NODE_NAME     J38 B15
 '@T6G_MB_LIB.T6G(SCH_1):PAGE335_I168@PURE_QUANTA.SCONN168_ME1016810202011(CHIPS)':
 'REFCLKP0': CDS_PINID='REFCLKP0';
NODE_NAME     R8563 2
 '@T6G_MB_LIB.T6G(SCH_1):PAGE28_I157@PURE_QUANTA.Q_RES(CHIPS)':
 'B': CDS_PINID='B';
NET_NAME
'CLK_100M_CPU0_CLK02_R_DN'
 '@T6G_MB_LIB.T6G(SCH_1):CLK_100M_CPU0_CLK02_R_DN':
 C_SIGNAL='@t6g_mb_lib.t6g(sch_1):clk_100m_cpu0_clk02_r_dn';
NODE_NAME     R8564 1
 '@T6G_MB_LIB.T6G(SCH_1):PAGE28_I156@PURE_QUANTA.Q_RES(CHIPS)':
 'A': CDS_PINID='A';
NODE_NAME     U25 C6
 '@T6G_MB_LIB.T6G(SCH_1):PAGE28_I188@PURE_QUANTA.GENOA_SP5(CHIPS)':
 'GPP_CLK02N': CDS_PINID='GPP_CLK02N';
NET_NAME
'CLK_100M_CPU0_CLK02_R_DP'
 '@T6G_MB_LIB.T6G(SCH_1):CLK_100M_CPU0_CLK02_R_DP':
 C_SIGNAL='@t6g_mb_lib.t6g(sch_1):clk_100m_cpu0_clk02_r_dp';
NODE_NAME     R8563 1
 '@T6G_MB_LIB.T6G(SCH_1):PAGE28_I157@PURE_QUANTA.Q_RES(CHIPS)':
 'A': CDS_PINID='A';
NODE_NAME     U25 B6
 '@T6G_MB_LIB.T6G(SCH_1):PAGE28_I188@PURE_QUANTA.GENOA_SP5(CHIPS)':
 'GPP_CLK02P': CDS_PINID='GPP_CLK02P';
NET_NAME
'CLK_100M_CPU0_CLK03_DN'
 '@T6G_MB_LIB.T6G(SCH_1):CLK_100M_CPU0_CLK03_DN':
 C_SIGNAL='@t6g_mb_lib.t6g(sch_1):clk_100m_cpu0_clk03_dn';
NODE_NAME     J38 A14
 '@T6G_MB_LIB.T6G(SCH_1):PAGE335_I168@PURE_QUANTA.SCONN168_ME1016810202011(CHIPS)':
 'REFCLKN1': CDS_PINID='REFCLKN1';
NODE_NAME     R8566 2
 '@T6G_MB_LIB.T6G(SCH_1):PAGE28_I155@PURE_QUANTA.Q_RES(CHIPS)':
 'B': CDS_PINID='B';
NET_NAME
'CLK_100M_CPU0_CLK03_DP'
 '@T6G_MB_LIB.T6G(SCH_1):CLK_100M_CPU0_CLK03_DP':
 C_SIGNAL='@t6g_mb_lib.t6g(sch_1):clk_100m_cpu0_clk03_dp';
NODE_NAME     J38 A15
 '@T6G_MB_LIB.T6G(SCH_1):PAGE335_I168@PURE_QUANTA.SCONN168_ME1016810202011(CHIPS)':
 'REFCLKP1': CDS_PINID='REFCLKP1';
NODE_NAME     R8565 2
 '@T6G_MB_LIB.T6G(SCH_1):PAGE28_I158@PURE_QUANTA.Q_RES(CHIPS)':
 'B': CDS_PINID='B';
NET_NAME
'CLK_100M_CPU0_CLK03_R_DN'
 '@T6G_MB_LIB.T6G(SCH_1):CLK_100M_CPU0_CLK03_R_DN':
 C_SIGNAL='@t6g_mb_lib.t6g(sch_1):clk_100m_cpu0_clk03_r_dn';
NODE_NAME     R8566 1
 '@T6G_MB_LIB.T6G(SCH_1):PAGE28_I155@PURE_QUANTA.Q_RES(CHIPS)':
 'A': CDS_PINID='A';
NODE_NAME     U25 A11
 '@T6G_MB_LIB.T6G(SCH_1):PAGE28_I188@PURE_QUANTA.GENOA_SP5(CHIPS)':
 'GPP_CLK03N': CDS_PINID='GPP_CLK03N';
NET_NAME
'CLK_100M_CPU0_CLK03_R_DP'
 '@T6G_MB_LIB.T6G(SCH_1):CLK_100M_CPU0_CLK03_R_DP':
 C_SIGNAL='@t6g_mb_lib.t6g(sch_1):clk_100m_cpu0_clk03_r_dp';
NODE_NAME     R8565 1
 '@T6G_MB_LIB.T6G(SCH_1):PAGE28_I158@PURE_QUANTA.Q_RES(CHIPS)':
 'A': CDS_PINID='A';
NODE_NAME     U25 A10
 '@T6G_MB_LIB.T6G(SCH_1):PAGE28_I188@PURE_QUANTA.GENOA_SP5(CHIPS)':
 'GPP_CLK03P': CDS_PINID='GPP_CLK03P';
NET_NAME
'CLK_100M_CPU0_CLK04_DN'
 '@T6G_MB_LIB.T6G(SCH_1):CLK_100M_CPU0_CLK04_DN':
 C_SIGNAL='@t6g_mb_lib.t6g(sch_1):clk_100m_cpu0_clk04_dn';
NODE_NAME     J38 OB11
 '@T6G_MB_LIB.T6G(SCH_1):PAGE335_I168@PURE_QUANTA.SCONN168_ME1016810202011(CHIPS)':
 'REFCLKN2': CDS_PINID='REFCLKN2';
NODE_NAME     R9274 2
 '@T6G_MB_LIB.T6G(SCH_1):PAGE28_I154@PURE_QUANTA.Q_RES(CHIPS)':
 'B': CDS_PINID='B';
NET_NAME
'CLK_100M_CPU0_CLK04_DP'
 '@T6G_MB_LIB.T6G(SCH_1):CLK_100M_CPU0_CLK04_DP':
 C_SIGNAL='@t6g_mb_lib.t6g(sch_1):clk_100m_cpu0_clk04_dp';
NODE_NAME     J38 OB12
 '@T6G_MB_LIB.T6G(SCH_1):PAGE335_I168@PURE_QUANTA.SCONN168_ME1016810202011(CHIPS)':
 'REFCLKP2': CDS_PINID='REFCLKP2';
NODE_NAME     R9273 2
 '@T6G_MB_LIB.T6G(SCH_1):PAGE28_I153@PURE_QUANTA.Q_RES(CHIPS)':
 'B': CDS_PINID='B';
NET_NAME
'CLK_100M_CPU0_CLK04_R_DN'
 '@T6G_MB_LIB.T6G(SCH_1):CLK_100M_CPU0_CLK04_R_DN':
 C_SIGNAL='@t6g_mb_lib.t6g(sch_1):clk_100m_cpu0_clk04_r_dn';
NODE_NAME     R9274 1
 '@T6G_MB_LIB.T6G(SCH_1):PAGE28_I154@PURE_QUANTA.Q_RES(CHIPS)':
 'A': CDS_PINID='A';
NODE_NAME     U25 C12
 '@T6G_MB_LIB.T6G(SCH_1):PAGE28_I188@PURE_QUANTA.GENOA_SP5(CHIPS)':
 'GPP_CLK04N': CDS_PINID='GPP_CLK04N';
NET_NAME
'CLK_100M_CPU0_CLK04_R_DP'
 '@T6G_MB_LIB.T6G(SCH_1):CLK_100M_CPU0_CLK04_R_DP':
 C_SIGNAL='@t6g_mb_lib.t6g(sch_1):clk_100m_cpu0_clk04_r_dp';
NODE_NAME     R9273 1
 '@T6G_MB_LIB.T6G(SCH_1):PAGE28_I153@PURE_QUANTA.Q_RES(CHIPS)':
 'A': CDS_PINID='A';
NODE_NAME     U25 B12
 '@T6G_MB_LIB.T6G(SCH_1):PAGE28_I188@PURE_QUANTA.GENOA_SP5(CHIPS)':
 'GPP_CLK04P': CDS_PINID='GPP_CLK04P';
NET_NAME
'CLK_100M_CPU0_CLK05_DN'
 '@T6G_MB_LIB.T6G(SCH_1):CLK_100M_CPU0_CLK05_DN':
 C_SIGNAL='@t6g_mb_lib.t6g(sch_1):clk_100m_cpu0_clk05_dn';
NODE_NAME     J38 OA11
 '@T6G_MB_LIB.T6G(SCH_1):PAGE335_I168@PURE_QUANTA.SCONN168_ME1016810202011(CHIPS)':
 'REFCLKN3': CDS_PINID='REFCLKN3';
NODE_NAME     R9276 2
 '@T6G_MB_LIB.T6G(SCH_1):PAGE28_I168@PURE_QUANTA.Q_RES(CHIPS)':
 'B': CDS_PINID='B';
NET_NAME
'CLK_100M_CPU0_CLK05_DP'
 '@T6G_MB_LIB.T6G(SCH_1):CLK_100M_CPU0_CLK05_DP':
 C_SIGNAL='@t6g_mb_lib.t6g(sch_1):clk_100m_cpu0_clk05_dp';
NODE_NAME     J38 OA12
 '@T6G_MB_LIB.T6G(SCH_1):PAGE335_I168@PURE_QUANTA.SCONN168_ME1016810202011(CHIPS)':
 'REFCLKP3': CDS_PINID='REFCLKP3';
NODE_NAME     R9275 2
 '@T6G_MB_LIB.T6G(SCH_1):PAGE28_I167@PURE_QUANTA.Q_RES(CHIPS)':
 'B': CDS_PINID='B';
NET_NAME
'CLK_100M_CPU0_CLK05_R_DN'
 '@T6G_MB_LIB.T6G(SCH_1):CLK_100M_CPU0_CLK05_R_DN':
 C_SIGNAL='@t6g_mb_lib.t6g(sch_1):clk_100m_cpu0_clk05_r_dn';
NODE_NAME     R9276 1
 '@T6G_MB_LIB.T6G(SCH_1):PAGE28_I168@PURE_QUANTA.Q_RES(CHIPS)':
 'A': CDS_PINID='A';
NODE_NAME     U25 C9
 '@T6G_MB_LIB.T6G(SCH_1):PAGE28_I188@PURE_QUANTA.GENOA_SP5(CHIPS)':
 'GPP_CLK05N': CDS_PINID='GPP_CLK05N';
NET_NAME
'CLK_100M_CPU0_CLK05_R_DP'
 '@T6G_MB_LIB.T6G(SCH_1):CLK_100M_CPU0_CLK05_R_DP':
 C_SIGNAL='@t6g_mb_lib.t6g(sch_1):clk_100m_cpu0_clk05_r_dp';
NODE_NAME     R9275 1
 '@T6G_MB_LIB.T6G(SCH_1):PAGE28_I167@PURE_QUANTA.Q_RES(CHIPS)':
 'A': CDS_PINID='A';
NODE_NAME     U25 B9
 '@T6G_MB_LIB.T6G(SCH_1):PAGE28_I188@PURE_QUANTA.GENOA_SP5(CHIPS)':
 'GPP_CLK05P': CDS_PINID='GPP_CLK05P';
NET_NAME
'CLK_100M_CPU0_CLK11_DN'
 '@T6G_MB_LIB.T6G(SCH_1):CLK_100M_CPU0_CLK11_DN':
 C_SIGNAL='@t6g_mb_lib.t6g(sch_1):clk_100m_cpu0_clk11_dn';
NODE_NAME     R2660 2
 '@T6G_MB_LIB.T6G(SCH_1):PAGE28_I151@PURE_QUANTA.Q_RES(CHIPS)':
 'B': CDS_PINID='B';
NODE_NAME     J112 N4
 '@T6G_MB_LIB.T6G(SCH_1):PAGE329_I102@PURE_QUANTA.CONN160_10131762101LF(CHIPS)':
 'N4': CDS_PINID='N4';
NET_NAME
'CLK_100M_CPU0_CLK11_DP'
 '@T6G_MB_LIB.T6G(SCH_1):CLK_100M_CPU0_CLK11_DP':
 C_SIGNAL='@t6g_mb_lib.t6g(sch_1):clk_100m_cpu0_clk11_dp';
NODE_NAME     R2659 2
 '@T6G_MB_LIB.T6G(SCH_1):PAGE28_I152@PURE_QUANTA.Q_RES(CHIPS)':
 'B': CDS_PINID='B';
NODE_NAME     J112 O4
 '@T6G_MB_LIB.T6G(SCH_1):PAGE329_I102@PURE_QUANTA.CONN160_10131762101LF(CHIPS)':
 'O4': CDS_PINID='O4';
NET_NAME
'CLK_100M_CPU0_CLK11_R_DN'
 '@T6G_MB_LIB.T6G(SCH_1):CLK_100M_CPU0_CLK11_R_DN':
 C_SIGNAL='@t6g_mb_lib.t6g(sch_1):clk_100m_cpu0_clk11_r_dn';
NODE_NAME     R2660 1
 '@T6G_MB_LIB.T6G(SCH_1):PAGE28_I151@PURE_QUANTA.Q_RES(CHIPS)':
 'A': CDS_PINID='A';
NODE_NAME     U25 DJ42
 '@T6G_MB_LIB.T6G(SCH_1):PAGE28_I188@PURE_QUANTA.GENOA_SP5(CHIPS)':
 'GPP_CLK11N': CDS_PINID='GPP_CLK11N';
NET_NAME
'CLK_100M_CPU0_CLK11_R_DP'
 '@T6G_MB_LIB.T6G(SCH_1):CLK_100M_CPU0_CLK11_R_DP':
 C_SIGNAL='@t6g_mb_lib.t6g(sch_1):clk_100m_cpu0_clk11_r_dp';
NODE_NAME     R2659 1
 '@T6G_MB_LIB.T6G(SCH_1):PAGE28_I152@PURE_QUANTA.Q_RES(CHIPS)':
 'A': CDS_PINID='A';
NODE_NAME     U25 DJ41
 '@T6G_MB_LIB.T6G(SCH_1):PAGE28_I188@PURE_QUANTA.GENOA_SP5(CHIPS)':
 'GPP_CLK11P': CDS_PINID='GPP_CLK11P';
NET_NAME
'CLK_100M_CPU0_CLK12_DN'
 '@T6G_MB_LIB.T6G(SCH_1):CLK_100M_CPU0_CLK12_DN':
 C_SIGNAL='@t6g_mb_lib.t6g(sch_1):clk_100m_cpu0_clk12_dn';
NODE_NAME     J90 B14
 '@T6G_MB_LIB.T6G(SCH_1):PAGE297_I90@PURE_QUANTA.SCONN56_123276793(CHIPS)':
 'REFCLK_N0': CDS_PINID='REFCLK_N0';
NODE_NAME     R4304 2
 '@T6G_MB_LIB.T6G(SCH_1):PAGE28_I192@PURE_QUANTA.Q_RES(CHIPS)':
 'B': CDS_PINID='B';
NET_NAME
'CLK_100M_CPU0_CLK12_DP'
 '@T6G_MB_LIB.T6G(SCH_1):CLK_100M_CPU0_CLK12_DP':
 C_SIGNAL='@t6g_mb_lib.t6g(sch_1):clk_100m_cpu0_clk12_dp';
NODE_NAME     J90 B15
 '@T6G_MB_LIB.T6G(SCH_1):PAGE297_I90@PURE_QUANTA.SCONN56_123276793(CHIPS)':
 'REFCLK_P0': CDS_PINID='REFCLK_P0';
NODE_NAME     R4303 2
 '@T6G_MB_LIB.T6G(SCH_1):PAGE28_I191@PURE_QUANTA.Q_RES(CHIPS)':
 'B': CDS_PINID='B';
NET_NAME
'CLK_100M_CPU0_CLK12_R_DN'
 '@T6G_MB_LIB.T6G(SCH_1):CLK_100M_CPU0_CLK12_R_DN':
 C_SIGNAL='@t6g_mb_lib.t6g(sch_1):clk_100m_cpu0_clk12_r_dn';
NODE_NAME     U25 DJ44
 '@T6G_MB_LIB.T6G(SCH_1):PAGE28_I188@PURE_QUANTA.GENOA_SP5(CHIPS)':
 'GPP_CLK12N': CDS_PINID='GPP_CLK12N';
NODE_NAME     R4304 1
 '@T6G_MB_LIB.T6G(SCH_1):PAGE28_I192@PURE_QUANTA.Q_RES(CHIPS)':
 'A': CDS_PINID='A';
NET_NAME
'CLK_100M_CPU0_CLK12_R_DP'
 '@T6G_MB_LIB.T6G(SCH_1):CLK_100M_CPU0_CLK12_R_DP':
 C_SIGNAL='@t6g_mb_lib.t6g(sch_1):clk_100m_cpu0_clk12_r_dp';
NODE_NAME     U25 DJ45
 '@T6G_MB_LIB.T6G(SCH_1):PAGE28_I188@PURE_QUANTA.GENOA_SP5(CHIPS)':
 'GPP_CLK12P': CDS_PINID='GPP_CLK12P';
NODE_NAME     R4303 1
 '@T6G_MB_LIB.T6G(SCH_1):PAGE28_I191@PURE_QUANTA.Q_RES(CHIPS)':
 'A': CDS_PINID='A';
NET_NAME
'CLK_100M_CPU0_CLK13_DN'
 '@T6G_MB_LIB.T6G(SCH_1):CLK_100M_CPU0_CLK13_DN':
 C_SIGNAL='@t6g_mb_lib.t6g(sch_1):clk_100m_cpu0_clk13_dn';
NODE_NAME     U314 4
 '@T6G_MB_LIB.T6G(SCH_1):PAGE160_I63@PURE_QUANTA.9ZXL0451EKILFT(CHIPS)':
 'DIF_IN#': CDS_PINID='\dif_in#\';
NODE_NAME     R8306 2
 '@T6G_MB_LIB.T6G(SCH_1):PAGE28_I228@PURE_QUANTA.Q_RES(CHIPS)':
 'B': CDS_PINID='B';
NET_NAME
'CLK_100M_CPU0_CLK13_DP'
 '@T6G_MB_LIB.T6G(SCH_1):CLK_100M_CPU0_CLK13_DP':
 C_SIGNAL='@t6g_mb_lib.t6g(sch_1):clk_100m_cpu0_clk13_dp';
NODE_NAME     U314 3
 '@T6G_MB_LIB.T6G(SCH_1):PAGE160_I63@PURE_QUANTA.9ZXL0451EKILFT(CHIPS)':
 'DIF_IN': CDS_PINID='DIF_IN';
NODE_NAME     R8305 2
 '@T6G_MB_LIB.T6G(SCH_1):PAGE28_I229@PURE_QUANTA.Q_RES(CHIPS)':
 'B': CDS_PINID='B';
NET_NAME
'CLK_100M_CPU0_CLK13_R_DN'
 '@T6G_MB_LIB.T6G(SCH_1):CLK_100M_CPU0_CLK13_R_DN':
 C_SIGNAL='@t6g_mb_lib.t6g(sch_1):clk_100m_cpu0_clk13_r_dn';
NODE_NAME     U25 DJ54
 '@T6G_MB_LIB.T6G(SCH_1):PAGE28_I188@PURE_QUANTA.GENOA_SP5(CHIPS)':
 'GPP_CLK13N': CDS_PINID='GPP_CLK13N';
NODE_NAME     R8306 1
 '@T6G_MB_LIB.T6G(SCH_1):PAGE28_I228@PURE_QUANTA.Q_RES(CHIPS)':
 'A': CDS_PINID='A';
NET_NAME
'CLK_100M_CPU0_CLK13_R_DP'
 '@T6G_MB_LIB.T6G(SCH_1):CLK_100M_CPU0_CLK13_R_DP':
 C_SIGNAL='@t6g_mb_lib.t6g(sch_1):clk_100m_cpu0_clk13_r_dp';
NODE_NAME     U25 DJ53
 '@T6G_MB_LIB.T6G(SCH_1):PAGE28_I188@PURE_QUANTA.GENOA_SP5(CHIPS)':
 'GPP_CLK13P': CDS_PINID='GPP_CLK13P';
NODE_NAME     R8305 1
 '@T6G_MB_LIB.T6G(SCH_1):PAGE28_I229@PURE_QUANTA.Q_RES(CHIPS)':
 'A': CDS_PINID='A';
NET_NAME
'CLK_100M_CPU1_CLK01_DN'
 '@T6G_MB_LIB.T6G(SCH_1):CLK_100M_CPU1_CLK01_DN':
 C_SIGNAL='@t6g_mb_lib.t6g(sch_1):clk_100m_cpu1_clk01_dn';
NODE_NAME     R3355 2
 '@T6G_MB_LIB.T6G(SCH_1):PAGE55_I306@PURE_QUANTA.Q_RES(CHIPS)':
 'B': CDS_PINID='B';
NODE_NAME     J112 O1
 '@T6G_MB_LIB.T6G(SCH_1):PAGE329_I102@PURE_QUANTA.CONN160_10131762101LF(CHIPS)':
 'O1': CDS_PINID='O1';
NET_NAME
'CLK_100M_CPU1_CLK01_DP'
 '@T6G_MB_LIB.T6G(SCH_1):CLK_100M_CPU1_CLK01_DP':
 C_SIGNAL='@t6g_mb_lib.t6g(sch_1):clk_100m_cpu1_clk01_dp';
NODE_NAME     R3354 2
 '@T6G_MB_LIB.T6G(SCH_1):PAGE55_I307@PURE_QUANTA.Q_RES(CHIPS)':
 'B': CDS_PINID='B';
NODE_NAME     J112 P1
 '@T6G_MB_LIB.T6G(SCH_1):PAGE329_I102@PURE_QUANTA.CONN160_10131762101LF(CHIPS)':
 'P1': CDS_PINID='P1';
NET_NAME
'CLK_100M_CPU1_CLK01_R_DN'
 '@T6G_MB_LIB.T6G(SCH_1):CLK_100M_CPU1_CLK01_R_DN':
 C_SIGNAL='@t6g_mb_lib.t6g(sch_1):clk_100m_cpu1_clk01_r_dn';
NODE_NAME     U26 A7
 '@T6G_MB_LIB.T6G(SCH_1):PAGE55_I182@PURE_QUANTA.GENOA_SP5(CHIPS)':
 'GPP_CLK01N': CDS_PINID='GPP_CLK01N';
NODE_NAME     R3355 1
 '@T6G_MB_LIB.T6G(SCH_1):PAGE55_I306@PURE_QUANTA.Q_RES(CHIPS)':
 'A': CDS_PINID='A';
NET_NAME
'CLK_100M_CPU1_CLK01_R_DP'
 '@T6G_MB_LIB.T6G(SCH_1):CLK_100M_CPU1_CLK01_R_DP':
 C_SIGNAL='@t6g_mb_lib.t6g(sch_1):clk_100m_cpu1_clk01_r_dp';
NODE_NAME     U26 A8
 '@T6G_MB_LIB.T6G(SCH_1):PAGE55_I182@PURE_QUANTA.GENOA_SP5(CHIPS)':
 'GPP_CLK01P': CDS_PINID='GPP_CLK01P';
NODE_NAME     R3354 1
 '@T6G_MB_LIB.T6G(SCH_1):PAGE55_I307@PURE_QUANTA.Q_RES(CHIPS)':
 'A': CDS_PINID='A';
NET_NAME
'CLK_100M_CPU1_CLK02_DN'
 '@T6G_MB_LIB.T6G(SCH_1):CLK_100M_CPU1_CLK02_DN':
 C_SIGNAL='@t6g_mb_lib.t6g(sch_1):clk_100m_cpu1_clk02_dn';
NODE_NAME     J35 B14
 '@T6G_MB_LIB.T6G(SCH_1):PAGE341_I168@PURE_QUANTA.SCONN168_ME1016810202011(CHIPS)':
 'REFCLKN0': CDS_PINID='REFCLKN0';
NODE_NAME     R3195 2
 '@T6G_MB_LIB.T6G(SCH_1):PAGE55_I309@PURE_QUANTA.Q_RES(CHIPS)':
 'B': CDS_PINID='B';
NET_NAME
'CLK_100M_CPU1_CLK02_DP'
 '@T6G_MB_LIB.T6G(SCH_1):CLK_100M_CPU1_CLK02_DP':
 C_SIGNAL='@t6g_mb_lib.t6g(sch_1):clk_100m_cpu1_clk02_dp';
NODE_NAME     J35 B15
 '@T6G_MB_LIB.T6G(SCH_1):PAGE341_I168@PURE_QUANTA.SCONN168_ME1016810202011(CHIPS)':
 'REFCLKP0': CDS_PINID='REFCLKP0';
NODE_NAME     R3194 2
 '@T6G_MB_LIB.T6G(SCH_1):PAGE55_I308@PURE_QUANTA.Q_RES(CHIPS)':
 'B': CDS_PINID='B';
NET_NAME
'CLK_100M_CPU1_CLK02_R_DN'
 '@T6G_MB_LIB.T6G(SCH_1):CLK_100M_CPU1_CLK02_R_DN':
 C_SIGNAL='@t6g_mb_lib.t6g(sch_1):clk_100m_cpu1_clk02_r_dn';
NODE_NAME     U26 C6
 '@T6G_MB_LIB.T6G(SCH_1):PAGE55_I182@PURE_QUANTA.GENOA_SP5(CHIPS)':
 'GPP_CLK02N': CDS_PINID='GPP_CLK02N';
NODE_NAME     R3195 1
 '@T6G_MB_LIB.T6G(SCH_1):PAGE55_I309@PURE_QUANTA.Q_RES(CHIPS)':
 'A': CDS_PINID='A';
NET_NAME
'CLK_100M_CPU1_CLK02_R_DP'
 '@T6G_MB_LIB.T6G(SCH_1):CLK_100M_CPU1_CLK02_R_DP':
 C_SIGNAL='@t6g_mb_lib.t6g(sch_1):clk_100m_cpu1_clk02_r_dp';
NODE_NAME     U26 B6
 '@T6G_MB_LIB.T6G(SCH_1):PAGE55_I182@PURE_QUANTA.GENOA_SP5(CHIPS)':
 'GPP_CLK02P': CDS_PINID='GPP_CLK02P';
NODE_NAME     R3194 1
 '@T6G_MB_LIB.T6G(SCH_1):PAGE55_I308@PURE_QUANTA.Q_RES(CHIPS)':
 'A': CDS_PINID='A';
NET_NAME
'CLK_100M_CPU1_CLK03_DN'
 '@T6G_MB_LIB.T6G(SCH_1):CLK_100M_CPU1_CLK03_DN':
 C_SIGNAL='@t6g_mb_lib.t6g(sch_1):clk_100m_cpu1_clk03_dn';
NODE_NAME     J35 A14
 '@T6G_MB_LIB.T6G(SCH_1):PAGE341_I168@PURE_QUANTA.SCONN168_ME1016810202011(CHIPS)':
 'REFCLKN1': CDS_PINID='REFCLKN1';
NODE_NAME     R3197 2
 '@T6G_MB_LIB.T6G(SCH_1):PAGE55_I313@PURE_QUANTA.Q_RES(CHIPS)':
 'B': CDS_PINID='B';
NET_NAME
'CLK_100M_CPU1_CLK03_DP'
 '@T6G_MB_LIB.T6G(SCH_1):CLK_100M_CPU1_CLK03_DP':
 C_SIGNAL='@t6g_mb_lib.t6g(sch_1):clk_100m_cpu1_clk03_dp';
NODE_NAME     J35 A15
 '@T6G_MB_LIB.T6G(SCH_1):PAGE341_I168@PURE_QUANTA.SCONN168_ME1016810202011(CHIPS)':
 'REFCLKP1': CDS_PINID='REFCLKP1';
NODE_NAME     R3196 2
 '@T6G_MB_LIB.T6G(SCH_1):PAGE55_I312@PURE_QUANTA.Q_RES(CHIPS)':
 'B': CDS_PINID='B';
NET_NAME
'CLK_100M_CPU1_CLK03_R_DN'
 '@T6G_MB_LIB.T6G(SCH_1):CLK_100M_CPU1_CLK03_R_DN':
 C_SIGNAL='@t6g_mb_lib.t6g(sch_1):clk_100m_cpu1_clk03_r_dn';
NODE_NAME     U26 A11
 '@T6G_MB_LIB.T6G(SCH_1):PAGE55_I182@PURE_QUANTA.GENOA_SP5(CHIPS)':
 'GPP_CLK03N': CDS_PINID='GPP_CLK03N';
NODE_NAME     R3197 1
 '@T6G_MB_LIB.T6G(SCH_1):PAGE55_I313@PURE_QUANTA.Q_RES(CHIPS)':
 'A': CDS_PINID='A';
NET_NAME
'CLK_100M_CPU1_CLK03_R_DP'
 '@T6G_MB_LIB.T6G(SCH_1):CLK_100M_CPU1_CLK03_R_DP':
 C_SIGNAL='@t6g_mb_lib.t6g(sch_1):clk_100m_cpu1_clk03_r_dp';
NODE_NAME     U26 A10
 '@T6G_MB_LIB.T6G(SCH_1):PAGE55_I182@PURE_QUANTA.GENOA_SP5(CHIPS)':
 'GPP_CLK03P': CDS_PINID='GPP_CLK03P';
NODE_NAME     R3196 1
 '@T6G_MB_LIB.T6G(SCH_1):PAGE55_I312@PURE_QUANTA.Q_RES(CHIPS)':
 'A': CDS_PINID='A';
NET_NAME
'CLK_100M_CPU1_CLK04_DN'
 '@T6G_MB_LIB.T6G(SCH_1):CLK_100M_CPU1_CLK04_DN':
 C_SIGNAL='@t6g_mb_lib.t6g(sch_1):clk_100m_cpu1_clk04_dn';
NODE_NAME     J35 OB11
 '@T6G_MB_LIB.T6G(SCH_1):PAGE341_I168@PURE_QUANTA.SCONN168_ME1016810202011(CHIPS)':
 'REFCLKN2': CDS_PINID='REFCLKN2';
NODE_NAME     R3199 2
 '@T6G_MB_LIB.T6G(SCH_1):PAGE55_I317@PURE_QUANTA.Q_RES(CHIPS)':
 'B': CDS_PINID='B';
NET_NAME
'CLK_100M_CPU1_CLK04_DP'
 '@T6G_MB_LIB.T6G(SCH_1):CLK_100M_CPU1_CLK04_DP':
 C_SIGNAL='@t6g_mb_lib.t6g(sch_1):clk_100m_cpu1_clk04_dp';
NODE_NAME     J35 OB12
 '@T6G_MB_LIB.T6G(SCH_1):PAGE341_I168@PURE_QUANTA.SCONN168_ME1016810202011(CHIPS)':
 'REFCLKP2': CDS_PINID='REFCLKP2';
NODE_NAME     R3198 2
 '@T6G_MB_LIB.T6G(SCH_1):PAGE55_I316@PURE_QUANTA.Q_RES(CHIPS)':
 'B': CDS_PINID='B';
NET_NAME
'CLK_100M_CPU1_CLK04_R_DN'
 '@T6G_MB_LIB.T6G(SCH_1):CLK_100M_CPU1_CLK04_R_DN':
 C_SIGNAL='@t6g_mb_lib.t6g(sch_1):clk_100m_cpu1_clk04_r_dn';
NODE_NAME     U26 C12
 '@T6G_MB_LIB.T6G(SCH_1):PAGE55_I182@PURE_QUANTA.GENOA_SP5(CHIPS)':
 'GPP_CLK04N': CDS_PINID='GPP_CLK04N';
NODE_NAME     R3199 1
 '@T6G_MB_LIB.T6G(SCH_1):PAGE55_I317@PURE_QUANTA.Q_RES(CHIPS)':
 'A': CDS_PINID='A';
NET_NAME
'CLK_100M_CPU1_CLK04_R_DP'
 '@T6G_MB_LIB.T6G(SCH_1):CLK_100M_CPU1_CLK04_R_DP':
 C_SIGNAL='@t6g_mb_lib.t6g(sch_1):clk_100m_cpu1_clk04_r_dp';
NODE_NAME     U26 B12
 '@T6G_MB_LIB.T6G(SCH_1):PAGE55_I182@PURE_QUANTA.GENOA_SP5(CHIPS)':
 'GPP_CLK04P': CDS_PINID='GPP_CLK04P';
NODE_NAME     R3198 1
 '@T6G_MB_LIB.T6G(SCH_1):PAGE55_I316@PURE_QUANTA.Q_RES(CHIPS)':
 'A': CDS_PINID='A';
NET_NAME
'CLK_100M_CPU1_CLK05_DN'
 '@T6G_MB_LIB.T6G(SCH_1):CLK_100M_CPU1_CLK05_DN':
 C_SIGNAL='@t6g_mb_lib.t6g(sch_1):clk_100m_cpu1_clk05_dn';
NODE_NAME     J35 OA11
 '@T6G_MB_LIB.T6G(SCH_1):PAGE341_I168@PURE_QUANTA.SCONN168_ME1016810202011(CHIPS)':
 'REFCLKN3': CDS_PINID='REFCLKN3';
NODE_NAME     R3201 2
 '@T6G_MB_LIB.T6G(SCH_1):PAGE55_I321@PURE_QUANTA.Q_RES(CHIPS)':
 'B': CDS_PINID='B';
NET_NAME
'CLK_100M_CPU1_CLK05_DP'
 '@T6G_MB_LIB.T6G(SCH_1):CLK_100M_CPU1_CLK05_DP':
 C_SIGNAL='@t6g_mb_lib.t6g(sch_1):clk_100m_cpu1_clk05_dp';
NODE_NAME     J35 OA12
 '@T6G_MB_LIB.T6G(SCH_1):PAGE341_I168@PURE_QUANTA.SCONN168_ME1016810202011(CHIPS)':
 'REFCLKP3': CDS_PINID='REFCLKP3';
NODE_NAME     R3200 2
 '@T6G_MB_LIB.T6G(SCH_1):PAGE55_I320@PURE_QUANTA.Q_RES(CHIPS)':
 'B': CDS_PINID='B';
NET_NAME
'CLK_100M_CPU1_CLK05_R_DN'
 '@T6G_MB_LIB.T6G(SCH_1):CLK_100M_CPU1_CLK05_R_DN':
 C_SIGNAL='@t6g_mb_lib.t6g(sch_1):clk_100m_cpu1_clk05_r_dn';
NODE_NAME     U26 C9
 '@T6G_MB_LIB.T6G(SCH_1):PAGE55_I182@PURE_QUANTA.GENOA_SP5(CHIPS)':
 'GPP_CLK05N': CDS_PINID='GPP_CLK05N';
NODE_NAME     R3201 1
 '@T6G_MB_LIB.T6G(SCH_1):PAGE55_I321@PURE_QUANTA.Q_RES(CHIPS)':
 'A': CDS_PINID='A';
NET_NAME
'CLK_100M_CPU1_CLK05_R_DP'
 '@T6G_MB_LIB.T6G(SCH_1):CLK_100M_CPU1_CLK05_R_DP':
 C_SIGNAL='@t6g_mb_lib.t6g(sch_1):clk_100m_cpu1_clk05_r_dp';
NODE_NAME     U26 B9
 '@T6G_MB_LIB.T6G(SCH_1):PAGE55_I182@PURE_QUANTA.GENOA_SP5(CHIPS)':
 'GPP_CLK05P': CDS_PINID='GPP_CLK05P';
NODE_NAME     R3200 1
 '@T6G_MB_LIB.T6G(SCH_1):PAGE55_I320@PURE_QUANTA.Q_RES(CHIPS)':
 'A': CDS_PINID='A';
NET_NAME
'CLK_100M_CPU1_CLK11_DN'
 '@T6G_MB_LIB.T6G(SCH_1):CLK_100M_CPU1_CLK11_DN':
 C_SIGNAL='@t6g_mb_lib.t6g(sch_1):clk_100m_cpu1_clk11_dn';
NODE_NAME     R3353 2
 '@T6G_MB_LIB.T6G(SCH_1):PAGE55_I303@PURE_QUANTA.Q_RES(CHIPS)':
 'B': CDS_PINID='B';
NODE_NAME     J112 O3
 '@T6G_MB_LIB.T6G(SCH_1):PAGE329_I102@PURE_QUANTA.CONN160_10131762101LF(CHIPS)':
 'O3': CDS_PINID='O3';
NET_NAME
'CLK_100M_CPU1_CLK11_DP'
 '@T6G_MB_LIB.T6G(SCH_1):CLK_100M_CPU1_CLK11_DP':
 C_SIGNAL='@t6g_mb_lib.t6g(sch_1):clk_100m_cpu1_clk11_dp';
NODE_NAME     R3352 2
 '@T6G_MB_LIB.T6G(SCH_1):PAGE55_I302@PURE_QUANTA.Q_RES(CHIPS)':
 'B': CDS_PINID='B';
NODE_NAME     J112 P3
 '@T6G_MB_LIB.T6G(SCH_1):PAGE329_I102@PURE_QUANTA.CONN160_10131762101LF(CHIPS)':
 'P3': CDS_PINID='P3';
NET_NAME
'CLK_100M_CPU1_CLK11_R_DN'
 '@T6G_MB_LIB.T6G(SCH_1):CLK_100M_CPU1_CLK11_R_DN':
 C_SIGNAL='@t6g_mb_lib.t6g(sch_1):clk_100m_cpu1_clk11_r_dn';
NODE_NAME     U26 DJ42
 '@T6G_MB_LIB.T6G(SCH_1):PAGE55_I182@PURE_QUANTA.GENOA_SP5(CHIPS)':
 'GPP_CLK11N': CDS_PINID='GPP_CLK11N';
NODE_NAME     R3353 1
 '@T6G_MB_LIB.T6G(SCH_1):PAGE55_I303@PURE_QUANTA.Q_RES(CHIPS)':
 'A': CDS_PINID='A';
NET_NAME
'CLK_100M_CPU1_CLK11_R_DP'
 '@T6G_MB_LIB.T6G(SCH_1):CLK_100M_CPU1_CLK11_R_DP':
 C_SIGNAL='@t6g_mb_lib.t6g(sch_1):clk_100m_cpu1_clk11_r_dp';
NODE_NAME     U26 DJ41
 '@T6G_MB_LIB.T6G(SCH_1):PAGE55_I182@PURE_QUANTA.GENOA_SP5(CHIPS)':
 'GPP_CLK11P': CDS_PINID='GPP_CLK11P';
NODE_NAME     R3352 1
 '@T6G_MB_LIB.T6G(SCH_1):PAGE55_I302@PURE_QUANTA.Q_RES(CHIPS)':
 'A': CDS_PINID='A';
NET_NAME
'CLK_100M_CPU1_CLK12_DN'
 '@T6G_MB_LIB.T6G(SCH_1):CLK_100M_CPU1_CLK12_DN':
 C_SIGNAL='@t6g_mb_lib.t6g(sch_1):clk_100m_cpu1_clk12_dn';
NODE_NAME     J59 53
 '@T6G_MB_LIB.T6G(SCH_1):PAGE345_I88@PURE_QUANTA.SCONN75K_APCI0155P004A(CHIPS)':
 'REFCLKN': CDS_PINID='REFCLKN';
NODE_NAME     R4306 2
 '@T6G_MB_LIB.T6G(SCH_1):PAGE55_I326@PURE_QUANTA.Q_RES(CHIPS)':
 'B': CDS_PINID='B';
NET_NAME
'CLK_100M_CPU1_CLK12_DP'
 '@T6G_MB_LIB.T6G(SCH_1):CLK_100M_CPU1_CLK12_DP':
 C_SIGNAL='@t6g_mb_lib.t6g(sch_1):clk_100m_cpu1_clk12_dp';
NODE_NAME     J59 55
 '@T6G_MB_LIB.T6G(SCH_1):PAGE345_I88@PURE_QUANTA.SCONN75K_APCI0155P004A(CHIPS)':
 'REFCLKP': CDS_PINID='REFCLKP';
NODE_NAME     R4305 2
 '@T6G_MB_LIB.T6G(SCH_1):PAGE55_I327@PURE_QUANTA.Q_RES(CHIPS)':
 'B': CDS_PINID='B';
NET_NAME
'CLK_100M_CPU1_CLK12_R_DN'
 '@T6G_MB_LIB.T6G(SCH_1):CLK_100M_CPU1_CLK12_R_DN':
 C_SIGNAL='@t6g_mb_lib.t6g(sch_1):clk_100m_cpu1_clk12_r_dn';
NODE_NAME     U26 DJ44
 '@T6G_MB_LIB.T6G(SCH_1):PAGE55_I182@PURE_QUANTA.GENOA_SP5(CHIPS)':
 'GPP_CLK12N': CDS_PINID='GPP_CLK12N';
NODE_NAME     R4306 1
 '@T6G_MB_LIB.T6G(SCH_1):PAGE55_I326@PURE_QUANTA.Q_RES(CHIPS)':
 'A': CDS_PINID='A';
NET_NAME
'CLK_100M_CPU1_CLK12_R_DP'
 '@T6G_MB_LIB.T6G(SCH_1):CLK_100M_CPU1_CLK12_R_DP':
 C_SIGNAL='@t6g_mb_lib.t6g(sch_1):clk_100m_cpu1_clk12_r_dp';
NODE_NAME     U26 DJ45
 '@T6G_MB_LIB.T6G(SCH_1):PAGE55_I182@PURE_QUANTA.GENOA_SP5(CHIPS)':
 'GPP_CLK12P': CDS_PINID='GPP_CLK12P';
NODE_NAME     R4305 1
 '@T6G_MB_LIB.T6G(SCH_1):PAGE55_I327@PURE_QUANTA.Q_RES(CHIPS)':
 'A': CDS_PINID='A';
NET_NAME
'CLK_100M_CPU1_CLK13_DN'
 '@T6G_MB_LIB.T6G(SCH_1):CLK_100M_CPU1_CLK13_DN':
 C_SIGNAL='@t6g_mb_lib.t6g(sch_1):clk_100m_cpu1_clk13_dn';
NODE_NAME     U10 4
 '@T6G_MB_LIB.T6G(SCH_1):PAGE379_I63@PURE_QUANTA.9ZXL0451EKILFT(CHIPS)':
 'DIF_IN#': CDS_PINID='\dif_in#\';
NODE_NAME     R8351 2
 '@T6G_MB_LIB.T6G(SCH_1):PAGE55_I394@PURE_QUANTA.Q_RES(CHIPS)':
 'B': CDS_PINID='B';
NET_NAME
'CLK_100M_CPU1_CLK13_DP'
 '@T6G_MB_LIB.T6G(SCH_1):CLK_100M_CPU1_CLK13_DP':
 C_SIGNAL='@t6g_mb_lib.t6g(sch_1):clk_100m_cpu1_clk13_dp';
NODE_NAME     U10 3
 '@T6G_MB_LIB.T6G(SCH_1):PAGE379_I63@PURE_QUANTA.9ZXL0451EKILFT(CHIPS)':
 'DIF_IN': CDS_PINID='DIF_IN';
NODE_NAME     R8350 2
 '@T6G_MB_LIB.T6G(SCH_1):PAGE55_I397@PURE_QUANTA.Q_RES(CHIPS)':
 'B': CDS_PINID='B';
NET_NAME
'CLK_100M_CPU1_CLK13_R_DN'
 '@T6G_MB_LIB.T6G(SCH_1):CLK_100M_CPU1_CLK13_R_DN':
 C_SIGNAL='@t6g_mb_lib.t6g(sch_1):clk_100m_cpu1_clk13_r_dn';
NODE_NAME     U26 DJ54
 '@T6G_MB_LIB.T6G(SCH_1):PAGE55_I182@PURE_QUANTA.GENOA_SP5(CHIPS)':
 'GPP_CLK13N': CDS_PINID='GPP_CLK13N';
NODE_NAME     R8351 1
 '@T6G_MB_LIB.T6G(SCH_1):PAGE55_I394@PURE_QUANTA.Q_RES(CHIPS)':
 'A': CDS_PINID='A';
NET_NAME
'CLK_100M_CPU1_CLK13_R_DP'
 '@T6G_MB_LIB.T6G(SCH_1):CLK_100M_CPU1_CLK13_R_DP':
 C_SIGNAL='@t6g_mb_lib.t6g(sch_1):clk_100m_cpu1_clk13_r_dp';
NODE_NAME     U26 DJ53
 '@T6G_MB_LIB.T6G(SCH_1):PAGE55_I182@PURE_QUANTA.GENOA_SP5(CHIPS)':
 'GPP_CLK13P': CDS_PINID='GPP_CLK13P';
NODE_NAME     R8350 1
 '@T6G_MB_LIB.T6G(SCH_1):PAGE55_I397@PURE_QUANTA.Q_RES(CHIPS)':
 'A': CDS_PINID='A';
NET_NAME
'CLK_100M_GPU_FPGA_DN'
 '@T6G_MB_LIB.T6G(SCH_1):CLK_100M_GPU_FPGA_DN':
 C_SIGNAL='@t6g_mb_lib.t6g(sch_1):clk_100m_gpu_fpga_dn';
NODE_NAME     R3338 2
 '@T6G_MB_LIB.T6G(SCH_1):PAGE232_I50@PURE_QUANTA.Q_RES(CHIPS)':
 'B': CDS_PINID='B';
NODE_NAME     J112 Q2
 '@T6G_MB_LIB.T6G(SCH_1):PAGE329_I102@PURE_QUANTA.CONN160_10131762101LF(CHIPS)':
 'Q2': CDS_PINID='Q2';
NET_NAME
'CLK_100M_GPU_FPGA_DN_R'
 '@T6G_MB_LIB.T6G(SCH_1):CLK_100M_GPU_FPGA_DN_R':
 C_SIGNAL='@t6g_mb_lib.t6g(sch_1):clk_100m_gpu_fpga_dn_r';
NODE_NAME     R3338 1
 '@T6G_MB_LIB.T6G(SCH_1):PAGE232_I50@PURE_QUANTA.Q_RES(CHIPS)':
 'A': CDS_PINID='A';
NODE_NAME     U247 18
 '@T6G_MB_LIB.T6G(SCH_1):PAGE232_I77@PURE_QUANTA.9FGL0251DKILFT(CHIPS)':
 'DIF1#': CDS_PINID='\dif1#\';
NET_NAME
'CLK_100M_GPU_FPGA_DP'
 '@T6G_MB_LIB.T6G(SCH_1):CLK_100M_GPU_FPGA_DP':
 C_SIGNAL='@t6g_mb_lib.t6g(sch_1):clk_100m_gpu_fpga_dp';
NODE_NAME     R3337 2
 '@T6G_MB_LIB.T6G(SCH_1):PAGE232_I51@PURE_QUANTA.Q_RES(CHIPS)':
 'B': CDS_PINID='B';
NODE_NAME     J112 R2
 '@T6G_MB_LIB.T6G(SCH_1):PAGE329_I102@PURE_QUANTA.CONN160_10131762101LF(CHIPS)':
 'R2': CDS_PINID='R2';
NET_NAME
'CLK_100M_GPU_FPGA_DP_R'
 '@T6G_MB_LIB.T6G(SCH_1):CLK_100M_GPU_FPGA_DP_R':
 C_SIGNAL='@t6g_mb_lib.t6g(sch_1):clk_100m_gpu_fpga_dp_r';
NODE_NAME     R3337 1
 '@T6G_MB_LIB.T6G(SCH_1):PAGE232_I51@PURE_QUANTA.Q_RES(CHIPS)':
 'A': CDS_PINID='A';
NODE_NAME     U247 17
 '@T6G_MB_LIB.T6G(SCH_1):PAGE232_I77@PURE_QUANTA.9FGL0251DKILFT(CHIPS)':
 'DIF1': CDS_PINID='DIF1';
NET_NAME
'CLK_100M_REF_IN_DN'
 '@T6G_MB_LIB.T6G(SCH_1):CLK_100M_REF_IN_DN':
 C_SIGNAL='@t6g_mb_lib.t6g(sch_1):clk_100m_ref_in_dn';
NODE_NAME     U26 A20
 '@T6G_MB_LIB.T6G(SCH_1):PAGE55_I182@PURE_QUANTA.GENOA_SP5(CHIPS)':
 'REFCLK100SSC_N||GPP_CLK10N': CDS_PINID='\refclk100ssc_n||gpp_clk10n\';
NODE_NAME     R436 2
 '@T6G_MB_LIB.T6G(SCH_1):PAGE28_I172@PURE_QUANTA.Q_RES(CHIPS)':
 'B': CDS_PINID='B';
NET_NAME
'CLK_100M_REF_IN_DP'
 '@T6G_MB_LIB.T6G(SCH_1):CLK_100M_REF_IN_DP':
 C_SIGNAL='@t6g_mb_lib.t6g(sch_1):clk_100m_ref_in_dp';
NODE_NAME     U26 A19
 '@T6G_MB_LIB.T6G(SCH_1):PAGE55_I182@PURE_QUANTA.GENOA_SP5(CHIPS)':
 'REFCLK100SSC_P||GPP_CLK10P': CDS_PINID='\refclk100ssc_p||gpp_clk10p\';
NODE_NAME     R435 2
 '@T6G_MB_LIB.T6G(SCH_1):PAGE28_I171@PURE_QUANTA.Q_RES(CHIPS)':
 'B': CDS_PINID='B';
NET_NAME
'CLK_100M_REF_OUT_DN'
 '@T6G_MB_LIB.T6G(SCH_1):CLK_100M_REF_OUT_DN':
 C_SIGNAL='@t6g_mb_lib.t6g(sch_1):clk_100m_ref_out_dn';
NODE_NAME     R436 1
 '@T6G_MB_LIB.T6G(SCH_1):PAGE28_I172@PURE_QUANTA.Q_RES(CHIPS)':
 'A': CDS_PINID='A';
NODE_NAME     U25 A20
 '@T6G_MB_LIB.T6G(SCH_1):PAGE28_I188@PURE_QUANTA.GENOA_SP5(CHIPS)':
 'REFCLK100SSC_N||GPP_CLK10N': CDS_PINID='\refclk100ssc_n||gpp_clk10n\';
NET_NAME
'CLK_100M_REF_OUT_DP'
 '@T6G_MB_LIB.T6G(SCH_1):CLK_100M_REF_OUT_DP':
 C_SIGNAL='@t6g_mb_lib.t6g(sch_1):clk_100m_ref_out_dp';
NODE_NAME     R435 1
 '@T6G_MB_LIB.T6G(SCH_1):PAGE28_I171@PURE_QUANTA.Q_RES(CHIPS)':
 'A': CDS_PINID='A';
NODE_NAME     U25 A19
 '@T6G_MB_LIB.T6G(SCH_1):PAGE28_I188@PURE_QUANTA.GENOA_SP5(CHIPS)':
 'REFCLK100SSC_P||GPP_CLK10P': CDS_PINID='\refclk100ssc_p||gpp_clk10p\';
NET_NAME
'CLK_100M_RETIMER_CPU0_P0_DN'
 '@T6G_MB_LIB.T6G(SCH_1):CLK_100M_RETIMER_CPU0_P0_DN':
 C_SIGNAL='@t6g_mb_lib.t6g(sch_1):clk_100m_retimer_cpu0_p0_dn';
NODE_NAME     R623 1
 '@T6G_MB_LIB.T6G(SCH_1):PAGE385_I37@PURE_QUANTA.Q_RES(CHIPS)':
 'A': CDS_PINID='A';
NODE_NAME     R596 2
 '@T6G_MB_LIB.T6G(SCH_1):PAGE385_I40@PURE_QUANTA.Q_RES(CHIPS)':
 'B': CDS_PINID='B';
NODE_NAME     U6010 FF18
 '@T6G_MB_LIB.T6G(SCH_1):PAGE385_I53@PURE_QUANTA.PT5161LRS(CHIPS)':
 'REFCLKN': CDS_PINID='REFCLKN';
NET_NAME
'CLK_100M_RETIMER_CPU0_P0_DP'
 '@T6G_MB_LIB.T6G(SCH_1):CLK_100M_RETIMER_CPU0_P0_DP':
 C_SIGNAL='@t6g_mb_lib.t6g(sch_1):clk_100m_retimer_cpu0_p0_dp';
NODE_NAME     R624 1
 '@T6G_MB_LIB.T6G(SCH_1):PAGE385_I38@PURE_QUANTA.Q_RES(CHIPS)':
 'A': CDS_PINID='A';
NODE_NAME     R595 2
 '@T6G_MB_LIB.T6G(SCH_1):PAGE385_I39@PURE_QUANTA.Q_RES(CHIPS)':
 'B': CDS_PINID='B';
NODE_NAME     U6010 FJ16
 '@T6G_MB_LIB.T6G(SCH_1):PAGE385_I53@PURE_QUANTA.PT5161LRS(CHIPS)':
 'REFCLKP': CDS_PINID='REFCLKP';
NET_NAME
'CLK_100M_RETIMER_CPU0_P0_R_DN'
 '@T6G_MB_LIB.T6G(SCH_1):CLK_100M_RETIMER_CPU0_P0_R_DN':
 C_SIGNAL='@t6g_mb_lib.t6g(sch_1):clk_100m_retimer_cpu0_p0_r_dn';
NODE_NAME     U314 14
 '@T6G_MB_LIB.T6G(SCH_1):PAGE160_I63@PURE_QUANTA.9ZXL0451EKILFT(CHIPS)':
 'DIF0#': CDS_PINID='\dif0#\';
NODE_NAME     R596 1
 '@T6G_MB_LIB.T6G(SCH_1):PAGE385_I40@PURE_QUANTA.Q_RES(CHIPS)':
 'A': CDS_PINID='A';
NET_NAME
'CLK_100M_RETIMER_CPU0_P0_R_DP'
 '@T6G_MB_LIB.T6G(SCH_1):CLK_100M_RETIMER_CPU0_P0_R_DP':
 C_SIGNAL='@t6g_mb_lib.t6g(sch_1):clk_100m_retimer_cpu0_p0_r_dp';
NODE_NAME     U314 13
 '@T6G_MB_LIB.T6G(SCH_1):PAGE160_I63@PURE_QUANTA.9ZXL0451EKILFT(CHIPS)':
 'DIF0': CDS_PINID='DIF0';
NODE_NAME     R595 1
 '@T6G_MB_LIB.T6G(SCH_1):PAGE385_I39@PURE_QUANTA.Q_RES(CHIPS)':
 'A': CDS_PINID='A';
NET_NAME
'CLK_100M_RETIMER_CPU0_P1_DN'
 '@T6G_MB_LIB.T6G(SCH_1):CLK_100M_RETIMER_CPU0_P1_DN':
 C_SIGNAL='@t6g_mb_lib.t6g(sch_1):clk_100m_retimer_cpu0_p1_dn';
NODE_NAME     R612 2
 '@T6G_MB_LIB.T6G(SCH_1):PAGE408_I15@PURE_QUANTA.Q_RES(CHIPS)':
 'B': CDS_PINID='B';
NODE_NAME     R629 1
 '@T6G_MB_LIB.T6G(SCH_1):PAGE408_I18@PURE_QUANTA.Q_RES(CHIPS)':
 'A': CDS_PINID='A';
NODE_NAME     U6011 FF18
 '@T6G_MB_LIB.T6G(SCH_1):PAGE408_I83@PURE_QUANTA.PT5161LRS(CHIPS)':
 'REFCLKN': CDS_PINID='REFCLKN';
NET_NAME
'CLK_100M_RETIMER_CPU0_P1_DP'
 '@T6G_MB_LIB.T6G(SCH_1):CLK_100M_RETIMER_CPU0_P1_DP':
 C_SIGNAL='@t6g_mb_lib.t6g(sch_1):clk_100m_retimer_cpu0_p1_dp';
NODE_NAME     R630 1
 '@T6G_MB_LIB.T6G(SCH_1):PAGE408_I19@PURE_QUANTA.Q_RES(CHIPS)':
 'A': CDS_PINID='A';
NODE_NAME     R611 2
 '@T6G_MB_LIB.T6G(SCH_1):PAGE408_I20@PURE_QUANTA.Q_RES(CHIPS)':
 'B': CDS_PINID='B';
NODE_NAME     U6011 FJ16
 '@T6G_MB_LIB.T6G(SCH_1):PAGE408_I83@PURE_QUANTA.PT5161LRS(CHIPS)':
 'REFCLKP': CDS_PINID='REFCLKP';
NET_NAME
'CLK_100M_RETIMER_CPU0_P1_R_DN'
 '@T6G_MB_LIB.T6G(SCH_1):CLK_100M_RETIMER_CPU0_P1_R_DN':
 C_SIGNAL='@t6g_mb_lib.t6g(sch_1):clk_100m_retimer_cpu0_p1_r_dn';
NODE_NAME     U314 20
 '@T6G_MB_LIB.T6G(SCH_1):PAGE160_I63@PURE_QUANTA.9ZXL0451EKILFT(CHIPS)':
 'DIF1#': CDS_PINID='\dif1#\';
NODE_NAME     R612 1
 '@T6G_MB_LIB.T6G(SCH_1):PAGE408_I15@PURE_QUANTA.Q_RES(CHIPS)':
 'A': CDS_PINID='A';
NET_NAME
'CLK_100M_RETIMER_CPU0_P1_R_DP'
 '@T6G_MB_LIB.T6G(SCH_1):CLK_100M_RETIMER_CPU0_P1_R_DP':
 C_SIGNAL='@t6g_mb_lib.t6g(sch_1):clk_100m_retimer_cpu0_p1_r_dp';
NODE_NAME     U314 19
 '@T6G_MB_LIB.T6G(SCH_1):PAGE160_I63@PURE_QUANTA.9ZXL0451EKILFT(CHIPS)':
 'DIF1': CDS_PINID='DIF1';
NODE_NAME     R611 1
 '@T6G_MB_LIB.T6G(SCH_1):PAGE408_I20@PURE_QUANTA.Q_RES(CHIPS)':
 'A': CDS_PINID='A';
NET_NAME
'CLK_100M_RETIMER_CPU0_P2_DN'
 '@T6G_MB_LIB.T6G(SCH_1):CLK_100M_RETIMER_CPU0_P2_DN':
 C_SIGNAL='@t6g_mb_lib.t6g(sch_1):clk_100m_retimer_cpu0_p2_dn';
NODE_NAME     R631 1
 '@T6G_MB_LIB.T6G(SCH_1):PAGE419_I17@PURE_QUANTA.Q_RES(CHIPS)':
 'A': CDS_PINID='A';
NODE_NAME     R614 2
 '@T6G_MB_LIB.T6G(SCH_1):PAGE419_I20@PURE_QUANTA.Q_RES(CHIPS)':
 'B': CDS_PINID='B';
NODE_NAME     U6012 FF18
 '@T6G_MB_LIB.T6G(SCH_1):PAGE419_I83@PURE_QUANTA.PT5161LRS(CHIPS)':
 'REFCLKN': CDS_PINID='REFCLKN';
NET_NAME
'CLK_100M_RETIMER_CPU0_P2_DP'
 '@T6G_MB_LIB.T6G(SCH_1):CLK_100M_RETIMER_CPU0_P2_DP':
 C_SIGNAL='@t6g_mb_lib.t6g(sch_1):clk_100m_retimer_cpu0_p2_dp';
NODE_NAME     R634 1
 '@T6G_MB_LIB.T6G(SCH_1):PAGE419_I18@PURE_QUANTA.Q_RES(CHIPS)':
 'A': CDS_PINID='A';
NODE_NAME     R613 2
 '@T6G_MB_LIB.T6G(SCH_1):PAGE419_I19@PURE_QUANTA.Q_RES(CHIPS)':
 'B': CDS_PINID='B';
NODE_NAME     U6012 FJ16
 '@T6G_MB_LIB.T6G(SCH_1):PAGE419_I83@PURE_QUANTA.PT5161LRS(CHIPS)':
 'REFCLKP': CDS_PINID='REFCLKP';
NET_NAME
'CLK_100M_RETIMER_CPU0_P2_R_DN'
 '@T6G_MB_LIB.T6G(SCH_1):CLK_100M_RETIMER_CPU0_P2_R_DN':
 C_SIGNAL='@t6g_mb_lib.t6g(sch_1):clk_100m_retimer_cpu0_p2_r_dn';
NODE_NAME     U314 23
 '@T6G_MB_LIB.T6G(SCH_1):PAGE160_I63@PURE_QUANTA.9ZXL0451EKILFT(CHIPS)':
 'DIF2#': CDS_PINID='\dif2#\';
NODE_NAME     R614 1
 '@T6G_MB_LIB.T6G(SCH_1):PAGE419_I20@PURE_QUANTA.Q_RES(CHIPS)':
 'A': CDS_PINID='A';
NET_NAME
'CLK_100M_RETIMER_CPU0_P2_R_DP'
 '@T6G_MB_LIB.T6G(SCH_1):CLK_100M_RETIMER_CPU0_P2_R_DP':
 C_SIGNAL='@t6g_mb_lib.t6g(sch_1):clk_100m_retimer_cpu0_p2_r_dp';
NODE_NAME     U314 22
 '@T6G_MB_LIB.T6G(SCH_1):PAGE160_I63@PURE_QUANTA.9ZXL0451EKILFT(CHIPS)':
 'DIF2': CDS_PINID='DIF2';
NODE_NAME     R613 1
 '@T6G_MB_LIB.T6G(SCH_1):PAGE419_I19@PURE_QUANTA.Q_RES(CHIPS)':
 'A': CDS_PINID='A';
NET_NAME
'CLK_100M_RETIMER_CPU0_P3_DN'
 '@T6G_MB_LIB.T6G(SCH_1):CLK_100M_RETIMER_CPU0_P3_DN':
 C_SIGNAL='@t6g_mb_lib.t6g(sch_1):clk_100m_retimer_cpu0_p3_dn';
NODE_NAME     R616 2
 '@T6G_MB_LIB.T6G(SCH_1):PAGE430_I15@PURE_QUANTA.Q_RES(CHIPS)':
 'B': CDS_PINID='B';
NODE_NAME     R635 1
 '@T6G_MB_LIB.T6G(SCH_1):PAGE430_I18@PURE_QUANTA.Q_RES(CHIPS)':
 'A': CDS_PINID='A';
NODE_NAME     U6013 FF18
 '@T6G_MB_LIB.T6G(SCH_1):PAGE430_I83@PURE_QUANTA.PT5161LRS(CHIPS)':
 'REFCLKN': CDS_PINID='REFCLKN';
NET_NAME
'CLK_100M_RETIMER_CPU0_P3_DP'
 '@T6G_MB_LIB.T6G(SCH_1):CLK_100M_RETIMER_CPU0_P3_DP':
 C_SIGNAL='@t6g_mb_lib.t6g(sch_1):clk_100m_retimer_cpu0_p3_dp';
NODE_NAME     R636 1
 '@T6G_MB_LIB.T6G(SCH_1):PAGE430_I19@PURE_QUANTA.Q_RES(CHIPS)':
 'A': CDS_PINID='A';
NODE_NAME     R615 2
 '@T6G_MB_LIB.T6G(SCH_1):PAGE430_I20@PURE_QUANTA.Q_RES(CHIPS)':
 'B': CDS_PINID='B';
NODE_NAME     U6013 FJ16
 '@T6G_MB_LIB.T6G(SCH_1):PAGE430_I83@PURE_QUANTA.PT5161LRS(CHIPS)':
 'REFCLKP': CDS_PINID='REFCLKP';
NET_NAME
'CLK_100M_RETIMER_CPU0_P3_R_DN'
 '@T6G_MB_LIB.T6G(SCH_1):CLK_100M_RETIMER_CPU0_P3_R_DN':
 C_SIGNAL='@t6g_mb_lib.t6g(sch_1):clk_100m_retimer_cpu0_p3_r_dn';
NODE_NAME     U314 28
 '@T6G_MB_LIB.T6G(SCH_1):PAGE160_I63@PURE_QUANTA.9ZXL0451EKILFT(CHIPS)':
 'DIF3#': CDS_PINID='\dif3#\';
NODE_NAME     R616 1
 '@T6G_MB_LIB.T6G(SCH_1):PAGE430_I15@PURE_QUANTA.Q_RES(CHIPS)':
 'A': CDS_PINID='A';
NET_NAME
'CLK_100M_RETIMER_CPU0_P3_R_DP'
 '@T6G_MB_LIB.T6G(SCH_1):CLK_100M_RETIMER_CPU0_P3_R_DP':
 C_SIGNAL='@t6g_mb_lib.t6g(sch_1):clk_100m_retimer_cpu0_p3_r_dp';
NODE_NAME     U314 27
 '@T6G_MB_LIB.T6G(SCH_1):PAGE160_I63@PURE_QUANTA.9ZXL0451EKILFT(CHIPS)':
 'DIF3': CDS_PINID='DIF3';
NODE_NAME     R615 1
 '@T6G_MB_LIB.T6G(SCH_1):PAGE430_I20@PURE_QUANTA.Q_RES(CHIPS)':
 'A': CDS_PINID='A';
NET_NAME
'CLK_100M_RETIMER_CPU1_P0_DN'
 '@T6G_MB_LIB.T6G(SCH_1):CLK_100M_RETIMER_CPU1_P0_DN':
 C_SIGNAL='@t6g_mb_lib.t6g(sch_1):clk_100m_retimer_cpu1_p0_dn';
NODE_NAME     U6014 FF18
 '@T6G_MB_LIB.T6G(SCH_1):PAGE401_I1@PURE_QUANTA.PT5161LRS(CHIPS)':
 'REFCLKN': CDS_PINID='REFCLKN';
NODE_NAME     R609 2
 '@T6G_MB_LIB.T6G(SCH_1):PAGE401_I8@PURE_QUANTA.Q_RES(CHIPS)':
 'B': CDS_PINID='B';
NODE_NAME     R627 1
 '@T6G_MB_LIB.T6G(SCH_1):PAGE401_I23@PURE_QUANTA.Q_RES(CHIPS)':
 'A': CDS_PINID='A';
NET_NAME
'CLK_100M_RETIMER_CPU1_P0_DP'
 '@T6G_MB_LIB.T6G(SCH_1):CLK_100M_RETIMER_CPU1_P0_DP':
 C_SIGNAL='@t6g_mb_lib.t6g(sch_1):clk_100m_retimer_cpu1_p0_dp';
NODE_NAME     U6014 FJ16
 '@T6G_MB_LIB.T6G(SCH_1):PAGE401_I1@PURE_QUANTA.PT5161LRS(CHIPS)':
 'REFCLKP': CDS_PINID='REFCLKP';
NODE_NAME     R599 2
 '@T6G_MB_LIB.T6G(SCH_1):PAGE401_I9@PURE_QUANTA.Q_RES(CHIPS)':
 'B': CDS_PINID='B';
NODE_NAME     R628 1
 '@T6G_MB_LIB.T6G(SCH_1):PAGE401_I24@PURE_QUANTA.Q_RES(CHIPS)':
 'A': CDS_PINID='A';
NET_NAME
'CLK_100M_RETIMER_CPU1_P0_R_DN'
 '@T6G_MB_LIB.T6G(SCH_1):CLK_100M_RETIMER_CPU1_P0_R_DN':
 C_SIGNAL='@t6g_mb_lib.t6g(sch_1):clk_100m_retimer_cpu1_p0_r_dn';
NODE_NAME     U10 14
 '@T6G_MB_LIB.T6G(SCH_1):PAGE379_I63@PURE_QUANTA.9ZXL0451EKILFT(CHIPS)':
 'DIF0#': CDS_PINID='\dif0#\';
NODE_NAME     R609 1
 '@T6G_MB_LIB.T6G(SCH_1):PAGE401_I8@PURE_QUANTA.Q_RES(CHIPS)':
 'A': CDS_PINID='A';
NET_NAME
'CLK_100M_RETIMER_CPU1_P0_R_DP'
 '@T6G_MB_LIB.T6G(SCH_1):CLK_100M_RETIMER_CPU1_P0_R_DP':
 C_SIGNAL='@t6g_mb_lib.t6g(sch_1):clk_100m_retimer_cpu1_p0_r_dp';
NODE_NAME     U10 13
 '@T6G_MB_LIB.T6G(SCH_1):PAGE379_I63@PURE_QUANTA.9ZXL0451EKILFT(CHIPS)':
 'DIF0': CDS_PINID='DIF0';
NODE_NAME     R599 1
 '@T6G_MB_LIB.T6G(SCH_1):PAGE401_I9@PURE_QUANTA.Q_RES(CHIPS)':
 'A': CDS_PINID='A';
NET_NAME
'CLK_100M_RETIMER_CPU1_P1_DN'
 '@T6G_MB_LIB.T6G(SCH_1):CLK_100M_RETIMER_CPU1_P1_DN':
 C_SIGNAL='@t6g_mb_lib.t6g(sch_1):clk_100m_retimer_cpu1_p1_dn';
NODE_NAME     R625 1
 '@T6G_MB_LIB.T6G(SCH_1):PAGE392_I31@PURE_QUANTA.Q_RES(CHIPS)':
 'A': CDS_PINID='A';
NODE_NAME     R598 2
 '@T6G_MB_LIB.T6G(SCH_1):PAGE392_I34@PURE_QUANTA.Q_RES(CHIPS)':
 'B': CDS_PINID='B';
NODE_NAME     U6015 FF18
 '@T6G_MB_LIB.T6G(SCH_1):PAGE392_I47@PURE_QUANTA.PT5161LRS(CHIPS)':
 'REFCLKN': CDS_PINID='REFCLKN';
NET_NAME
'CLK_100M_RETIMER_CPU1_P1_DP'
 '@T6G_MB_LIB.T6G(SCH_1):CLK_100M_RETIMER_CPU1_P1_DP':
 C_SIGNAL='@t6g_mb_lib.t6g(sch_1):clk_100m_retimer_cpu1_p1_dp';
NODE_NAME     R626 1
 '@T6G_MB_LIB.T6G(SCH_1):PAGE392_I32@PURE_QUANTA.Q_RES(CHIPS)':
 'A': CDS_PINID='A';
NODE_NAME     R597 2
 '@T6G_MB_LIB.T6G(SCH_1):PAGE392_I33@PURE_QUANTA.Q_RES(CHIPS)':
 'B': CDS_PINID='B';
NODE_NAME     U6015 FJ16
 '@T6G_MB_LIB.T6G(SCH_1):PAGE392_I47@PURE_QUANTA.PT5161LRS(CHIPS)':
 'REFCLKP': CDS_PINID='REFCLKP';
NET_NAME
'CLK_100M_RETIMER_CPU1_P1_R_DN'
 '@T6G_MB_LIB.T6G(SCH_1):CLK_100M_RETIMER_CPU1_P1_R_DN':
 C_SIGNAL='@t6g_mb_lib.t6g(sch_1):clk_100m_retimer_cpu1_p1_r_dn';
NODE_NAME     U10 20
 '@T6G_MB_LIB.T6G(SCH_1):PAGE379_I63@PURE_QUANTA.9ZXL0451EKILFT(CHIPS)':
 'DIF1#': CDS_PINID='\dif1#\';
NODE_NAME     R598 1
 '@T6G_MB_LIB.T6G(SCH_1):PAGE392_I34@PURE_QUANTA.Q_RES(CHIPS)':
 'A': CDS_PINID='A';
NET_NAME
'CLK_100M_RETIMER_CPU1_P1_R_DP'
 '@T6G_MB_LIB.T6G(SCH_1):CLK_100M_RETIMER_CPU1_P1_R_DP':
 C_SIGNAL='@t6g_mb_lib.t6g(sch_1):clk_100m_retimer_cpu1_p1_r_dp';
NODE_NAME     U10 19
 '@T6G_MB_LIB.T6G(SCH_1):PAGE379_I63@PURE_QUANTA.9ZXL0451EKILFT(CHIPS)':
 'DIF1': CDS_PINID='DIF1';
NODE_NAME     R597 1
 '@T6G_MB_LIB.T6G(SCH_1):PAGE392_I33@PURE_QUANTA.Q_RES(CHIPS)':
 'A': CDS_PINID='A';
NET_NAME
'CLK_100M_RETIMER_CPU1_P2_DN'
 '@T6G_MB_LIB.T6G(SCH_1):CLK_100M_RETIMER_CPU1_P2_DN':
 C_SIGNAL='@t6g_mb_lib.t6g(sch_1):clk_100m_retimer_cpu1_p2_dn';
NODE_NAME     R620 2
 '@T6G_MB_LIB.T6G(SCH_1):PAGE451_I27@PURE_QUANTA.Q_RES(CHIPS)':
 'B': CDS_PINID='B';
NODE_NAME     R637 1
 '@T6G_MB_LIB.T6G(SCH_1):PAGE451_I92@PURE_QUANTA.Q_RES(CHIPS)':
 'A': CDS_PINID='A';
NODE_NAME     U6016 FF18
 '@T6G_MB_LIB.T6G(SCH_1):PAGE451_I97@PURE_QUANTA.PT5161LRS(CHIPS)':
 'REFCLKN': CDS_PINID='REFCLKN';
NET_NAME
'CLK_100M_RETIMER_CPU1_P2_DP'
 '@T6G_MB_LIB.T6G(SCH_1):CLK_100M_RETIMER_CPU1_P2_DP':
 C_SIGNAL='@t6g_mb_lib.t6g(sch_1):clk_100m_retimer_cpu1_p2_dp';
NODE_NAME     R619 2
 '@T6G_MB_LIB.T6G(SCH_1):PAGE451_I28@PURE_QUANTA.Q_RES(CHIPS)':
 'B': CDS_PINID='B';
NODE_NAME     R640 1
 '@T6G_MB_LIB.T6G(SCH_1):PAGE451_I36@PURE_QUANTA.Q_RES(CHIPS)':
 'A': CDS_PINID='A';
NODE_NAME     U6016 FJ16
 '@T6G_MB_LIB.T6G(SCH_1):PAGE451_I97@PURE_QUANTA.PT5161LRS(CHIPS)':
 'REFCLKP': CDS_PINID='REFCLKP';
NET_NAME
'CLK_100M_RETIMER_CPU1_P2_R_DN'
 '@T6G_MB_LIB.T6G(SCH_1):CLK_100M_RETIMER_CPU1_P2_R_DN':
 C_SIGNAL='@t6g_mb_lib.t6g(sch_1):clk_100m_retimer_cpu1_p2_r_dn';
NODE_NAME     U10 23
 '@T6G_MB_LIB.T6G(SCH_1):PAGE379_I63@PURE_QUANTA.9ZXL0451EKILFT(CHIPS)':
 'DIF2#': CDS_PINID='\dif2#\';
NODE_NAME     R620 1
 '@T6G_MB_LIB.T6G(SCH_1):PAGE451_I27@PURE_QUANTA.Q_RES(CHIPS)':
 'A': CDS_PINID='A';
NET_NAME
'CLK_100M_RETIMER_CPU1_P2_R_DP'
 '@T6G_MB_LIB.T6G(SCH_1):CLK_100M_RETIMER_CPU1_P2_R_DP':
 C_SIGNAL='@t6g_mb_lib.t6g(sch_1):clk_100m_retimer_cpu1_p2_r_dp';
NODE_NAME     U10 22
 '@T6G_MB_LIB.T6G(SCH_1):PAGE379_I63@PURE_QUANTA.9ZXL0451EKILFT(CHIPS)':
 'DIF2': CDS_PINID='DIF2';
NODE_NAME     R619 1
 '@T6G_MB_LIB.T6G(SCH_1):PAGE451_I28@PURE_QUANTA.Q_RES(CHIPS)':
 'A': CDS_PINID='A';
NET_NAME
'CLK_100M_RETIMER_CPU1_P3_DN'
 '@T6G_MB_LIB.T6G(SCH_1):CLK_100M_RETIMER_CPU1_P3_DN':
 C_SIGNAL='@t6g_mb_lib.t6g(sch_1):clk_100m_retimer_cpu1_p3_dn';
NODE_NAME     R641 1
 '@T6G_MB_LIB.T6G(SCH_1):PAGE462_I30@PURE_QUANTA.Q_RES(CHIPS)':
 'A': CDS_PINID='A';
NODE_NAME     R622 2
 '@T6G_MB_LIB.T6G(SCH_1):PAGE462_I31@PURE_QUANTA.Q_RES(CHIPS)':
 'B': CDS_PINID='B';
NODE_NAME     U6017 FF18
 '@T6G_MB_LIB.T6G(SCH_1):PAGE462_I97@PURE_QUANTA.PT5161LRS(CHIPS)':
 'REFCLKN': CDS_PINID='REFCLKN';
NET_NAME
'CLK_100M_RETIMER_CPU1_P3_DP'
 '@T6G_MB_LIB.T6G(SCH_1):CLK_100M_RETIMER_CPU1_P3_DP':
 C_SIGNAL='@t6g_mb_lib.t6g(sch_1):clk_100m_retimer_cpu1_p3_dp';
NODE_NAME     R621 2
 '@T6G_MB_LIB.T6G(SCH_1):PAGE462_I32@PURE_QUANTA.Q_RES(CHIPS)':
 'B': CDS_PINID='B';
NODE_NAME     R642 1
 '@T6G_MB_LIB.T6G(SCH_1):PAGE462_I46@PURE_QUANTA.Q_RES(CHIPS)':
 'A': CDS_PINID='A';
NODE_NAME     U6017 FJ16
 '@T6G_MB_LIB.T6G(SCH_1):PAGE462_I97@PURE_QUANTA.PT5161LRS(CHIPS)':
 'REFCLKP': CDS_PINID='REFCLKP';
NET_NAME
'CLK_100M_RETIMER_CPU1_P3_R_DN'
 '@T6G_MB_LIB.T6G(SCH_1):CLK_100M_RETIMER_CPU1_P3_R_DN':
 C_SIGNAL='@t6g_mb_lib.t6g(sch_1):clk_100m_retimer_cpu1_p3_r_dn';
NODE_NAME     U10 28
 '@T6G_MB_LIB.T6G(SCH_1):PAGE379_I63@PURE_QUANTA.9ZXL0451EKILFT(CHIPS)':
 'DIF3#': CDS_PINID='\dif3#\';
NODE_NAME     R622 1
 '@T6G_MB_LIB.T6G(SCH_1):PAGE462_I31@PURE_QUANTA.Q_RES(CHIPS)':
 'A': CDS_PINID='A';
NET_NAME
'CLK_100M_RETIMER_CPU1_P3_R_DP'
 '@T6G_MB_LIB.T6G(SCH_1):CLK_100M_RETIMER_CPU1_P3_R_DP':
 C_SIGNAL='@t6g_mb_lib.t6g(sch_1):clk_100m_retimer_cpu1_p3_r_dp';
NODE_NAME     U10 27
 '@T6G_MB_LIB.T6G(SCH_1):PAGE379_I63@PURE_QUANTA.9ZXL0451EKILFT(CHIPS)':
 'DIF3': CDS_PINID='DIF3';
NODE_NAME     R621 1
 '@T6G_MB_LIB.T6G(SCH_1):PAGE462_I32@PURE_QUANTA.Q_RES(CHIPS)':
 'A': CDS_PINID='A';
NET_NAME
'CLK_50M_BMC_MAC_R'
 '@T6G_MB_LIB.T6G(SCH_1):CLK_50M_BMC_MAC_R':
 C_SIGNAL='@t6g_mb_lib.t6g(sch_1):clk_50m_bmc_mac_r';
NODE_NAME     U90 3
 '@T6G_MB_LIB.T6G(SCH_1):PAGE337_I16@PURE_QUANTA.PI6CV304LE(CHIPS)':
 'Y0': CDS_PINID='Y0';
NODE_NAME     R1140 1
 '@T6G_MB_LIB.T6G(SCH_1):PAGE337_I22@PURE_QUANTA.Q_RES(CHIPS)':
 'A': CDS_PINID='A';
NET_NAME
'CLK_50M_EN'
 '@T6G_MB_LIB.T6G(SCH_1):CLK_50M_EN':
 C_SIGNAL='@t6g_mb_lib.t6g(sch_1):clk_50m_en';
NODE_NAME     R1138 2
 '@T6G_MB_LIB.T6G(SCH_1):PAGE337_I1@PURE_QUANTA.Q_RES(CHIPS)':
 'B': CDS_PINID='B';
NODE_NAME     OSC1 1
 '@T6G_MB_LIB.T6G(SCH_1):PAGE337_I4@PURE_QUANTA.Q_OSC4P(CHIPS)':
 'OE': CDS_PINID='OE';
NODE_NAME     U90 2
 '@T6G_MB_LIB.T6G(SCH_1):PAGE337_I16@PURE_QUANTA.PI6CV304LE(CHIPS)':
 'OE': CDS_PINID='OE';
NET_NAME
'CLK_50M_NCSI_OCP_1'
 '@T6G_MB_LIB.T6G(SCH_1):CLK_50M_NCSI_OCP_1':
 C_SIGNAL='@t6g_mb_lib.t6g(sch_1):clk_50m_ncsi_ocp_1';
NODE_NAME     U90 5
 '@T6G_MB_LIB.T6G(SCH_1):PAGE337_I16@PURE_QUANTA.PI6CV304LE(CHIPS)':
 'Y1': CDS_PINID='Y1';
NODE_NAME     R1141 1
 '@T6G_MB_LIB.T6G(SCH_1):PAGE337_I21@PURE_QUANTA.Q_RES(CHIPS)':
 'A': CDS_PINID='A';
NET_NAME
'CLK_50M_NCSI_OCP_2'
 '@T6G_MB_LIB.T6G(SCH_1):CLK_50M_NCSI_OCP_2':
 C_SIGNAL='@t6g_mb_lib.t6g(sch_1):clk_50m_ncsi_ocp_2';
NODE_NAME     U90 7
 '@T6G_MB_LIB.T6G(SCH_1):PAGE337_I16@PURE_QUANTA.PI6CV304LE(CHIPS)':
 'Y2': CDS_PINID='Y2';
NODE_NAME     R3181 1
 '@T6G_MB_LIB.T6G(SCH_1):PAGE337_I20@PURE_QUANTA.Q_RES(CHIPS)':
 'A': CDS_PINID='A';
NET_NAME
'CLK_50M_NCSI_OCP_SFF'
 '@T6G_MB_LIB.T6G(SCH_1):CLK_50M_NCSI_OCP_SFF':
 C_SIGNAL='@t6g_mb_lib.t6g(sch_1):clk_50m_ncsi_ocp_sff';
NODE_NAME     R1141 2
 '@T6G_MB_LIB.T6G(SCH_1):PAGE337_I21@PURE_QUANTA.Q_RES(CHIPS)':
 'B': CDS_PINID='B';
NODE_NAME     U320 1
 '@T6G_MB_LIB.T6G(SCH_1):PAGE337_I82@PURE_QUANTA.74LVC1G66GV(CHIPS)':
 'Y': CDS_PINID='Y';
NET_NAME
'CLK_50M_NCSI_OCP_SFF_ISO'
 '@T6G_MB_LIB.T6G(SCH_1):CLK_50M_NCSI_OCP_SFF_ISO':
 C_SIGNAL='@t6g_mb_lib.t6g(sch_1):clk_50m_ncsi_ocp_sff_iso';
NODE_NAME     J38 OA14
 '@T6G_MB_LIB.T6G(SCH_1):PAGE335_I168@PURE_QUANTA.SCONN168_ME1016810202011(CHIPS)':
 'RBT_CLK_IN': CDS_PINID='RBT_CLK_IN';
NODE_NAME     R4601 1
 '@T6G_MB_LIB.T6G(SCH_1):PAGE337_I29@PURE_QUANTA.Q_RES(CHIPS)':
 'A': CDS_PINID='A';
NET_NAME
'CLK_50M_NCSI_OCP_SFF_ISO_R'
 '@T6G_MB_LIB.T6G(SCH_1):CLK_50M_NCSI_OCP_SFF_ISO_R':
 C_SIGNAL='@t6g_mb_lib.t6g(sch_1):clk_50m_ncsi_ocp_sff_iso_r';
NODE_NAME     R4601 2
 '@T6G_MB_LIB.T6G(SCH_1):PAGE337_I29@PURE_QUANTA.Q_RES(CHIPS)':
 'B': CDS_PINID='B';
NODE_NAME     U320 2
 '@T6G_MB_LIB.T6G(SCH_1):PAGE337_I82@PURE_QUANTA.74LVC1G66GV(CHIPS)':
 'Z': CDS_PINID='Z';
NET_NAME
'CLK_50M_NCSI_OCP_V3_2'
 '@T6G_MB_LIB.T6G(SCH_1):CLK_50M_NCSI_OCP_V3_2':
 C_SIGNAL='@t6g_mb_lib.t6g(sch_1):clk_50m_ncsi_ocp_v3_2';
NODE_NAME     R3181 2
 '@T6G_MB_LIB.T6G(SCH_1):PAGE337_I20@PURE_QUANTA.Q_RES(CHIPS)':
 'B': CDS_PINID='B';
NODE_NAME     U321 1
 '@T6G_MB_LIB.T6G(SCH_1):PAGE342_I76@PURE_QUANTA.74LVC1G66GV(CHIPS)':
 'Y': CDS_PINID='Y';
NET_NAME
'CLK_50M_NCSI_OCP_V3_2_ISO'
 '@T6G_MB_LIB.T6G(SCH_1):CLK_50M_NCSI_OCP_V3_2_ISO':
 C_SIGNAL='@t6g_mb_lib.t6g(sch_1):clk_50m_ncsi_ocp_v3_2_iso';
NODE_NAME     J35 OA14
 '@T6G_MB_LIB.T6G(SCH_1):PAGE341_I168@PURE_QUANTA.SCONN168_ME1016810202011(CHIPS)':
 'RBT_CLK_IN': CDS_PINID='RBT_CLK_IN';
NODE_NAME     R4602 1
 '@T6G_MB_LIB.T6G(SCH_1):PAGE342_I36@PURE_QUANTA.Q_RES(CHIPS)':
 'A': CDS_PINID='A';
NET_NAME
'CLK_50M_NCSI_OCP_V3_2_ISO_R'
 '@T6G_MB_LIB.T6G(SCH_1):CLK_50M_NCSI_OCP_V3_2_ISO_R':
 C_SIGNAL='@t6g_mb_lib.t6g(sch_1):clk_50m_ncsi_ocp_v3_2_iso_r';
NODE_NAME     R4602 2
 '@T6G_MB_LIB.T6G(SCH_1):PAGE342_I36@PURE_QUANTA.Q_RES(CHIPS)':
 'B': CDS_PINID='B';
NODE_NAME     U321 2
 '@T6G_MB_LIB.T6G(SCH_1):PAGE342_I76@PURE_QUANTA.74LVC1G66GV(CHIPS)':
 'Z': CDS_PINID='Z';
NET_NAME
'CLK_50M_RMII'
 '@T6G_MB_LIB.T6G(SCH_1):CLK_50M_RMII':
 C_SIGNAL='@t6g_mb_lib.t6g(sch_1):clk_50m_rmii';
NODE_NAME     OSC1 3
 '@T6G_MB_LIB.T6G(SCH_1):PAGE337_I4@PURE_QUANTA.Q_OSC4P(CHIPS)':
 'OUT': CDS_PINID='\out\';
NODE_NAME     R1139 1
 '@T6G_MB_LIB.T6G(SCH_1):PAGE337_I7@PURE_QUANTA.Q_RES(CHIPS)':
 'A': CDS_PINID='A';
NET_NAME
'CLK_50M_RMII_BMC_OCP'
 '@T6G_MB_LIB.T6G(SCH_1):CLK_50M_RMII_BMC_OCP':
 C_SIGNAL='@t6g_mb_lib.t6g(sch_1):clk_50m_rmii_bmc_ocp';
NODE_NAME     J41 B18
 '@T6G_MB_LIB.T6G(SCH_1):PAGE348_I176@PURE_QUANTA.SCONN168_ME1016810202011(CHIPS)':
 'PETP0': CDS_PINID='PETP0';
NODE_NAME     R1140 2
 '@T6G_MB_LIB.T6G(SCH_1):PAGE337_I22@PURE_QUANTA.Q_RES(CHIPS)':
 'B': CDS_PINID='B';
NET_NAME
'CLK_50M_RMII_R'
 '@T6G_MB_LIB.T6G(SCH_1):CLK_50M_RMII_R':
 C_SIGNAL='@t6g_mb_lib.t6g(sch_1):clk_50m_rmii_r';
NODE_NAME     R1139 2
 '@T6G_MB_LIB.T6G(SCH_1):PAGE337_I7@PURE_QUANTA.Q_RES(CHIPS)':
 'B': CDS_PINID='B';
NODE_NAME     U90 1
 '@T6G_MB_LIB.T6G(SCH_1):PAGE337_I16@PURE_QUANTA.PI6CV304LE(CHIPS)':
 'CLK_IN': CDS_PINID='CLK_IN';
NET_NAME
'CLK_9ZXL045_P0_HIBW'
 '@T6G_MB_LIB.T6G(SCH_1):CLK_9ZXL045_P0_HIBW':
 C_SIGNAL='@t6g_mb_lib.t6g(sch_1):clk_9zxl045_p0_hibw';
NODE_NAME     R4492 1
 '@T6G_MB_LIB.T6G(SCH_1):PAGE160_I29@PURE_QUANTA.Q_RES(CHIPS)':
 'A': CDS_PINID='A';
NODE_NAME     R4491 2
 '@T6G_MB_LIB.T6G(SCH_1):PAGE160_I31@PURE_QUANTA.Q_RES(CHIPS)':
 'B': CDS_PINID='B';
NODE_NAME     U314 32
 '@T6G_MB_LIB.T6G(SCH_1):PAGE160_I63@PURE_QUANTA.9ZXL0451EKILFT(CHIPS)':
 '^HIBW_BYPM_LOBW#': CDS_PINID='\^hibw_bypm_lobw#\';
NET_NAME
'CLK_9ZXL045_P0_SADR0'
 '@T6G_MB_LIB.T6G(SCH_1):CLK_9ZXL045_P0_SADR0':
 C_SIGNAL='@t6g_mb_lib.t6g(sch_1):clk_9zxl045_p0_sadr0';
NODE_NAME     R4490 1
 '@T6G_MB_LIB.T6G(SCH_1):PAGE160_I2@PURE_QUANTA.Q_RES(CHIPS)':
 'A': CDS_PINID='A';
NODE_NAME     R4489 2
 '@T6G_MB_LIB.T6G(SCH_1):PAGE160_I3@PURE_QUANTA.Q_RES(CHIPS)':
 'B': CDS_PINID='B';
NODE_NAME     U314 5
 '@T6G_MB_LIB.T6G(SCH_1):PAGE160_I63@PURE_QUANTA.9ZXL0451EKILFT(CHIPS)':
 'VSADR0_TRI': CDS_PINID='VSADR0_TRI';
NET_NAME
'CLK_9ZXL045_P1_HIBW'
 '@T6G_MB_LIB.T6G(SCH_1):CLK_9ZXL045_P1_HIBW':
 C_SIGNAL='@t6g_mb_lib.t6g(sch_1):clk_9zxl045_p1_hibw';
NODE_NAME     R585 1
 '@T6G_MB_LIB.T6G(SCH_1):PAGE379_I15@PURE_QUANTA.Q_RES(CHIPS)':
 'A': CDS_PINID='A';
NODE_NAME     R580 2
 '@T6G_MB_LIB.T6G(SCH_1):PAGE379_I17@PURE_QUANTA.Q_RES(CHIPS)':
 'B': CDS_PINID='B';
NODE_NAME     U10 32
 '@T6G_MB_LIB.T6G(SCH_1):PAGE379_I63@PURE_QUANTA.9ZXL0451EKILFT(CHIPS)':
 '^HIBW_BYPM_LOBW#': CDS_PINID='\^hibw_bypm_lobw#\';
NET_NAME
'CLK_9ZXL045_P1_SADR0'
 '@T6G_MB_LIB.T6G(SCH_1):CLK_9ZXL045_P1_SADR0':
 C_SIGNAL='@t6g_mb_lib.t6g(sch_1):clk_9zxl045_p1_sadr0';
NODE_NAME     U10 5
 '@T6G_MB_LIB.T6G(SCH_1):PAGE379_I63@PURE_QUANTA.9ZXL0451EKILFT(CHIPS)':
 'VSADR0_TRI': CDS_PINID='VSADR0_TRI';
NODE_NAME     R579 1
 '@T6G_MB_LIB.T6G(SCH_1):PAGE379_I64@PURE_QUANTA.Q_RES(CHIPS)':
 'A': CDS_PINID='A';
NODE_NAME     R578 2
 '@T6G_MB_LIB.T6G(SCH_1):PAGE379_I65@PURE_QUANTA.Q_RES(CHIPS)':
 'B': CDS_PINID='B';
NET_NAME
'CLK_CPU0_RTCCLK'
 '@T6G_MB_LIB.T6G(SCH_1):CLK_CPU0_RTCCLK':
 C_SIGNAL='@t6g_mb_lib.t6g(sch_1):clk_cpu0_rtcclk';
NODE_NAME     R573 1
 '@T6G_MB_LIB.T6G(SCH_1):PAGE55_I26@PURE_QUANTA.Q_RES(CHIPS)':
 'A': CDS_PINID='A';
NODE_NAME     R751 2
 '@T6G_MB_LIB.T6G(SCH_1):PAGE75_I12@PURE_QUANTA.Q_RES(CHIPS)':
 'B': CDS_PINID='B';
NODE_NAME     R740 2
 '@T6G_MB_LIB.T6G(SCH_1):PAGE75_I44@PURE_QUANTA.Q_RES(CHIPS)':
 'B': CDS_PINID='B';
NODE_NAME     U25 DH9
 '@T6G_MB_LIB.T6G(SCH_1):PAGE28_I188@PURE_QUANTA.GENOA_SP5(CHIPS)':
 'RTCCLK': CDS_PINID='RTCCLK';
NET_NAME
'CLK_CPU1_RTCCLK'
 '@T6G_MB_LIB.T6G(SCH_1):CLK_CPU1_RTCCLK':
 C_SIGNAL='@t6g_mb_lib.t6g(sch_1):clk_cpu1_rtcclk';
NODE_NAME     U26 DH9
 '@T6G_MB_LIB.T6G(SCH_1):PAGE55_I182@PURE_QUANTA.GENOA_SP5(CHIPS)':
 'RTCCLK': CDS_PINID='RTCCLK';
NODE_NAME     R1501 2
 '@T6G_MB_LIB.T6G(SCH_1):PAGE75_I90@PURE_QUANTA.Q_RES(CHIPS)':
 'B': CDS_PINID='B';
NODE_NAME     R1502 2
 '@T6G_MB_LIB.T6G(SCH_1):PAGE75_I94@PURE_QUANTA.Q_RES(CHIPS)':
 'B': CDS_PINID='B';
NET_NAME
'CLK_ESPI_CPU0_CLK1'
 '@T6G_MB_LIB.T6G(SCH_1):CLK_ESPI_CPU0_CLK1':
 C_SIGNAL='@t6g_mb_lib.t6g(sch_1):clk_espi_cpu0_clk1';
NODE_NAME     R739 2
 '@T6G_MB_LIB.T6G(SCH_1):PAGE75_I45@PURE_QUANTA.Q_RES(CHIPS)':
 'B': CDS_PINID='B';
NODE_NAME     R750 2
 '@T6G_MB_LIB.T6G(SCH_1):PAGE75_I74@PURE_QUANTA.Q_RES(CHIPS)':
 'B': CDS_PINID='B';
NODE_NAME     J41 B1
 '@T6G_MB_LIB.T6G(SCH_1):PAGE348_I176@PURE_QUANTA.SCONN168_ME1016810202011(CHIPS)':
 '+12V_EDGE_B1': CDS_PINID='\+12v_edge_b1\';
NODE_NAME     R1556 2
 '@T6G_MB_LIB.T6G(SCH_1):PAGE80_I176@PURE_QUANTA.Q_RES(CHIPS)':
 'B': CDS_PINID='B';
NODE_NAME     R473 1
 '@T6G_MB_LIB.T6G(SCH_1):PAGE29_I430@PURE_QUANTA.Q_RES(CHIPS)':
 'A': CDS_PINID='A';
NET_NAME
'CLK_ESPI_CPU0_R1_CLK1'
 '@T6G_MB_LIB.T6G(SCH_1):CLK_ESPI_CPU0_R1_CLK1':
 C_SIGNAL='@t6g_mb_lib.t6g(sch_1):clk_espi_cpu0_r1_clk1';
NODE_NAME     R1556 1
 '@T6G_MB_LIB.T6G(SCH_1):PAGE80_I176@PURE_QUANTA.Q_RES(CHIPS)':
 'A': CDS_PINID='A';
NODE_NAME     U18 R21
 '@T6G_MB_LIB.T6G(SCH_1):PAGE80_I217@PURE_QUANTA.LCMXO3LF9400C5BG484C(CHIPS)':
 'PR20B': CDS_PINID='PR20B';
NET_NAME
'CLK_ESPI_CPU0_R_CLK1'
 '@T6G_MB_LIB.T6G(SCH_1):CLK_ESPI_CPU0_R_CLK1':
 C_SIGNAL='@t6g_mb_lib.t6g(sch_1):clk_espi_cpu0_r_clk1';
NODE_NAME     U25 DG23
 '@T6G_MB_LIB.T6G(SCH_1):PAGE29_I287@PURE_QUANTA.GENOA_SP5(CHIPS)':
 'ESPI_CLK1||SPI_CLK1||AGPIO75': CDS_PINID='\espi_clk1||spi_clk1||agpio75\';
NODE_NAME     R473 2
 '@T6G_MB_LIB.T6G(SCH_1):PAGE29_I430@PURE_QUANTA.Q_RES(CHIPS)':
 'B': CDS_PINID='B';
NET_NAME
'CLK_GEN2_BMC_RC_OE_N'
 '@T6G_MB_LIB.T6G(SCH_1):CLK_GEN2_BMC_RC_OE_N':
 C_SIGNAL='@t6g_mb_lib.t6g(sch_1):clk_gen2_bmc_rc_oe_n';
NODE_NAME     R4075 1
 '@T6G_MB_LIB.T6G(SCH_1):PAGE232_I22@PURE_QUANTA.Q_RES(CHIPS)':
 'A': CDS_PINID='A';
NODE_NAME     R6029 1
 '@T6G_MB_LIB.T6G(SCH_1):PAGE79_I65@PURE_QUANTA.Q_RES(CHIPS)':
 'A': CDS_PINID='A';
NODE_NAME     R4521 2
 '@T6G_MB_LIB.T6G(SCH_1):PAGE232_I73@PURE_QUANTA.Q_RES(CHIPS)':
 'B': CDS_PINID='B';
NET_NAME
'CLK_GEN2_BMC_RC_OE_R3_N'
 '@T6G_MB_LIB.T6G(SCH_1):CLK_GEN2_BMC_RC_OE_R3_N':
 C_SIGNAL='@t6g_mb_lib.t6g(sch_1):clk_gen2_bmc_rc_oe_r3_n';
NODE_NAME     R4075 2
 '@T6G_MB_LIB.T6G(SCH_1):PAGE232_I22@PURE_QUANTA.Q_RES(CHIPS)':
 'B': CDS_PINID='B';
NODE_NAME     U247 12
 '@T6G_MB_LIB.T6G(SCH_1):PAGE232_I77@PURE_QUANTA.9FGL0251DKILFT(CHIPS)':
 'VOE0#': CDS_PINID='\voe0#\';
NET_NAME
'CLK_GEN2_BMC_RC_OE_R_N'
 '@T6G_MB_LIB.T6G(SCH_1):CLK_GEN2_BMC_RC_OE_R_N':
 C_SIGNAL='@t6g_mb_lib.t6g(sch_1):clk_gen2_bmc_rc_oe_r_n';
NODE_NAME     R6029 2
 '@T6G_MB_LIB.T6G(SCH_1):PAGE79_I65@PURE_QUANTA.Q_RES(CHIPS)':
 'B': CDS_PINID='B';
NODE_NAME     U18 C19
 '@T6G_MB_LIB.T6G(SCH_1):PAGE79_I94@PURE_QUANTA.LCMXO3LF9400C5BG484C(CHIPS)':
 'PT43C': CDS_PINID='PT43C';
NET_NAME
'CLK_GEN2_GPU_FPGA_OE_N'
 '@T6G_MB_LIB.T6G(SCH_1):CLK_GEN2_GPU_FPGA_OE_N':
 C_SIGNAL='@t6g_mb_lib.t6g(sch_1):clk_gen2_gpu_fpga_oe_n';
NODE_NAME     R3327 1
 '@T6G_MB_LIB.T6G(SCH_1):PAGE232_I6@PURE_QUANTA.Q_RES(CHIPS)':
 'A': CDS_PINID='A';
NODE_NAME     R6030 1
 '@T6G_MB_LIB.T6G(SCH_1):PAGE79_I64@PURE_QUANTA.Q_RES(CHIPS)':
 'A': CDS_PINID='A';
NET_NAME
'CLK_GEN2_GPU_FPGA_OE_OR_N'
 '@T6G_MB_LIB.T6G(SCH_1):CLK_GEN2_GPU_FPGA_OE_OR_N':
 C_SIGNAL='@t6g_mb_lib.t6g(sch_1):clk_gen2_gpu_fpga_oe_or_n';
NODE_NAME     R4076 1
 '@T6G_MB_LIB.T6G(SCH_1):PAGE232_I16@PURE_QUANTA.Q_RES(CHIPS)':
 'A': CDS_PINID='A';
NODE_NAME     U248 4
 '@T6G_MB_LIB.T6G(SCH_1):PAGE232_I26@PURE_QUANTA.74LVC1G32GW(CHIPS)':
 'O': CDS_PINID='O';
NODE_NAME     R4537 2
 '@T6G_MB_LIB.T6G(SCH_1):PAGE110_I67@PURE_QUANTA.Q_RES(CHIPS)':
 'B': CDS_PINID='B';
NODE_NAME     R3265 1
 '@T6G_MB_LIB.T6G(SCH_1):PAGE110_I81@PURE_QUANTA.Q_RES(CHIPS)':
 'A': CDS_PINID='A';
NODE_NAME     R3292 2
 '@T6G_MB_LIB.T6G(SCH_1):PAGE110_I89@PURE_QUANTA.Q_RES(CHIPS)':
 'B': CDS_PINID='B';
NODE_NAME     R6162 2
 '@T6G_MB_LIB.T6G(SCH_1):PAGE111_I23@PURE_QUANTA.Q_RES(CHIPS)':
 'B': CDS_PINID='B';
NET_NAME
'CLK_GEN2_GPU_FPGA_OE_R2_N'
 '@T6G_MB_LIB.T6G(SCH_1):CLK_GEN2_GPU_FPGA_OE_R2_N':
 C_SIGNAL='@t6g_mb_lib.t6g(sch_1):clk_gen2_gpu_fpga_oe_r2_n';
NODE_NAME     R3327 2
 '@T6G_MB_LIB.T6G(SCH_1):PAGE232_I6@PURE_QUANTA.Q_RES(CHIPS)':
 'B': CDS_PINID='B';
NODE_NAME     R4514 1
 '@T6G_MB_LIB.T6G(SCH_1):PAGE232_I8@PURE_QUANTA.Q_RES(CHIPS)':
 'A': CDS_PINID='A';
NODE_NAME     U248 2
 '@T6G_MB_LIB.T6G(SCH_1):PAGE232_I26@PURE_QUANTA.74LVC1G32GW(CHIPS)':
 'I1': CDS_PINID='I1';
NODE_NAME     R3322 2
 '@T6G_MB_LIB.T6G(SCH_1):PAGE232_I74@PURE_QUANTA.Q_RES(CHIPS)':
 'B': CDS_PINID='B';
NET_NAME
'CLK_GEN2_GPU_FPGA_OE_R_N'
 '@T6G_MB_LIB.T6G(SCH_1):CLK_GEN2_GPU_FPGA_OE_R_N':
 C_SIGNAL='@t6g_mb_lib.t6g(sch_1):clk_gen2_gpu_fpga_oe_r_n';
NODE_NAME     R6030 2
 '@T6G_MB_LIB.T6G(SCH_1):PAGE79_I64@PURE_QUANTA.Q_RES(CHIPS)':
 'B': CDS_PINID='B';
NODE_NAME     U18 C20
 '@T6G_MB_LIB.T6G(SCH_1):PAGE79_I94@PURE_QUANTA.LCMXO3LF9400C5BG484C(CHIPS)':
 'PT43D': CDS_PINID='PT43D';
NET_NAME
'CLK_GEN2_GPU_OE_N'
 '@T6G_MB_LIB.T6G(SCH_1):CLK_GEN2_GPU_OE_N':
 C_SIGNAL='@t6g_mb_lib.t6g(sch_1):clk_gen2_gpu_oe_n';
NODE_NAME     R4076 2
 '@T6G_MB_LIB.T6G(SCH_1):PAGE232_I16@PURE_QUANTA.Q_RES(CHIPS)':
 'B': CDS_PINID='B';
NODE_NAME     U247 19
 '@T6G_MB_LIB.T6G(SCH_1):PAGE232_I77@PURE_QUANTA.9FGL0251DKILFT(CHIPS)':
 'VOE1#': CDS_PINID='\voe1#\';
NET_NAME
'CLK_GEN2_SMB_SADR'
 '@T6G_MB_LIB.T6G(SCH_1):CLK_GEN2_SMB_SADR':
 C_SIGNAL='@t6g_mb_lib.t6g(sch_1):clk_gen2_smb_sadr';
NODE_NAME     R4082 1
 '@T6G_MB_LIB.T6G(SCH_1):PAGE232_I55@PURE_QUANTA.Q_RES(CHIPS)':
 'A': CDS_PINID='A';
NODE_NAME     R4081 2
 '@T6G_MB_LIB.T6G(SCH_1):PAGE232_I56@PURE_QUANTA.Q_RES(CHIPS)':
 'B': CDS_PINID='B';
NODE_NAME     U247 4
 '@T6G_MB_LIB.T6G(SCH_1):PAGE232_I77@PURE_QUANTA.9FGL0251DKILFT(CHIPS)':
 'VSADR||REF3.3': CDS_PINID='\vsadr||ref3.3\';
NET_NAME
'CLK_GEN2_XTAL_IN'
 '@T6G_MB_LIB.T6G(SCH_1):CLK_GEN2_XTAL_IN':
 C_SIGNAL='@t6g_mb_lib.t6g(sch_1):clk_gen2_xtal_in';
NODE_NAME     R4501 2
 '@T6G_MB_LIB.T6G(SCH_1):PAGE232_I31@PURE_QUANTA.Q_RES(CHIPS)':
 'B': CDS_PINID='B';
NODE_NAME     U247 1
 '@T6G_MB_LIB.T6G(SCH_1):PAGE232_I77@PURE_QUANTA.9FGL0251DKILFT(CHIPS)':
 'XIN||CLKIN_25': CDS_PINID='\xin||clkin_25\';
NET_NAME
'CLK_GEN2_XTAL_IN_R'
 '@T6G_MB_LIB.T6G(SCH_1):CLK_GEN2_XTAL_IN_R':
 C_SIGNAL='@t6g_mb_lib.t6g(sch_1):clk_gen2_xtal_in_r';
NODE_NAME     Y8003 1
 '@T6G_MB_LIB.T6G(SCH_1):PAGE232_I14@PURE_QUANTA.Q_XTAL_4P_13BI_24GND(CHIPS)':
 'X1': CDS_PINID='X1';
NODE_NAME     R4501 1
 '@T6G_MB_LIB.T6G(SCH_1):PAGE232_I31@PURE_QUANTA.Q_RES(CHIPS)':
 'A': CDS_PINID='A';
NODE_NAME     C71 1
 '@T6G_MB_LIB.T6G(SCH_1):PAGE232_I75@PURE_QUANTA.Q_CAP(CHIPS)':
 'A': CDS_PINID='A';
NET_NAME
'CLK_GEN2_XTAL_OUT'
 '@T6G_MB_LIB.T6G(SCH_1):CLK_GEN2_XTAL_OUT':
 C_SIGNAL='@t6g_mb_lib.t6g(sch_1):clk_gen2_xtal_out';
NODE_NAME     Y8003 3
 '@T6G_MB_LIB.T6G(SCH_1):PAGE232_I14@PURE_QUANTA.Q_XTAL_4P_13BI_24GND(CHIPS)':
 'X2': CDS_PINID='X2';
NODE_NAME     C94 1
 '@T6G_MB_LIB.T6G(SCH_1):PAGE232_I76@PURE_QUANTA.Q_CAP(CHIPS)':
 'A': CDS_PINID='A';
NODE_NAME     U247 2
 '@T6G_MB_LIB.T6G(SCH_1):PAGE232_I77@PURE_QUANTA.9FGL0251DKILFT(CHIPS)':
 'X2': CDS_PINID='X2';
NET_NAME
'CLR_CMOS'
 '@T6G_MB_LIB.T6G(SCH_1):CLR_CMOS':
 C_SIGNAL='@t6g_mb_lib.t6g(sch_1):clr_cmos';
NODE_NAME     R275 1
 '@T6G_MB_LIB.T6G(SCH_1):PAGE81_I84@PURE_QUANTA.Q_RES(CHIPS)':
 'A': CDS_PINID='A';
NODE_NAME     R1776 1
 '@T6G_MB_LIB.T6G(SCH_1):PAGE156_I94@PURE_QUANTA.Q_RES(CHIPS)':
 'A': CDS_PINID='A';
NODE_NAME     C1563 1
 '@T6G_MB_LIB.T6G(SCH_1):PAGE156_I95@PURE_QUANTA.Q_CAP(CHIPS)':
 'A': CDS_PINID='A';
NODE_NAME     Q8 2
 '@T6G_MB_LIB.T6G(SCH_1):PAGE156_I104@PURE_QUANTA.MOSFET_DUAL_6P(CHIPS)':
 'G1': CDS_PINID='G1';
NODE_NAME     Q8 5
 '@T6G_MB_LIB.T6G(SCH_1):PAGE156_I104@PURE_QUANTA.MOSFET_DUAL_6P(CHIPS)':
 'G2': CDS_PINID='G2';
NET_NAME
'CLR_CMOS_N'
 '@T6G_MB_LIB.T6G(SCH_1):CLR_CMOS_N':
 C_SIGNAL='@t6g_mb_lib.t6g(sch_1):clr_cmos_n';
NODE_NAME     Q8 6
 '@T6G_MB_LIB.T6G(SCH_1):PAGE156_I104@PURE_QUANTA.MOSFET_DUAL_6P(CHIPS)':
 'D1': CDS_PINID='D1';
NODE_NAME     R1779 1
 '@T6G_MB_LIB.T6G(SCH_1):PAGE156_I116@PURE_QUANTA.Q_RES(CHIPS)':
 'A': CDS_PINID='A';
NET_NAME
'CPLD_JTAG_EN'
 '@T6G_MB_LIB.T6G(SCH_1):CPLD_JTAG_EN':
 C_SIGNAL='@t6g_mb_lib.t6g(sch_1):cpld_jtag_en';
NODE_NAME     R638 1
 '@T6G_MB_LIB.T6G(SCH_1):PAGE82_I35@PURE_QUANTA.Q_RES(CHIPS)':
 'A': CDS_PINID='A';
NODE_NAME     U18 E14
 '@T6G_MB_LIB.T6G(SCH_1):PAGE79_I25@PURE_QUANTA.LCMXO3LF9400C5BG484C(CHIPS)':
 'PT31C||JTAGENB': CDS_PINID='\pt31c||jtagenb\';
NET_NAME
'CPLD_PROGRAMN'
 '@T6G_MB_LIB.T6G(SCH_1):CPLD_PROGRAMN':
 C_SIGNAL='@t6g_mb_lib.t6g(sch_1):cpld_programn';
NODE_NAME     U18 E15
 '@T6G_MB_LIB.T6G(SCH_1):PAGE79_I25@PURE_QUANTA.LCMXO3LF9400C5BG484C(CHIPS)':
 'PT31D||PROGRAMN': CDS_PINID='\pt31d||programn\';
NODE_NAME     R639 1
 '@T6G_MB_LIB.T6G(SCH_1):PAGE82_I33@PURE_QUANTA.Q_RES(CHIPS)':
 'A': CDS_PINID='A';
NET_NAME
'CPU0_BP0'
 '@T6G_MB_LIB.T6G(SCH_1):CPU0_BP0':
 C_SIGNAL='@t6g_mb_lib.t6g(sch_1):cpu0_bp0';
NODE_NAME     U25 C63
 '@T6G_MB_LIB.T6G(SCH_1):PAGE27_I227@PURE_QUANTA.GENOA_SP5(CHIPS)':
 'BP0': CDS_PINID='BP0';
NODE_NAME     R408 1
 '@T6G_MB_LIB.T6G(SCH_1):PAGE27_I380@PURE_QUANTA.Q_RES(CHIPS)':
 'A': CDS_PINID='A';
NODE_NAME     J48 1
 '@T6G_MB_LIB.T6G(SCH_1):PAGE27_I424@PURE_QUANTA.SCONN8_G802M0083150RD3HR(CHIPS)':
 '1': CDS_PINID='\1\';
NET_NAME
'CPU0_BP1'
 '@T6G_MB_LIB.T6G(SCH_1):CPU0_BP1':
 C_SIGNAL='@t6g_mb_lib.t6g(sch_1):cpu0_bp1';
NODE_NAME     U25 C62
 '@T6G_MB_LIB.T6G(SCH_1):PAGE27_I227@PURE_QUANTA.GENOA_SP5(CHIPS)':
 'BP1': CDS_PINID='BP1';
NODE_NAME     R409 1
 '@T6G_MB_LIB.T6G(SCH_1):PAGE27_I381@PURE_QUANTA.Q_RES(CHIPS)':
 'A': CDS_PINID='A';
NODE_NAME     J48 3
 '@T6G_MB_LIB.T6G(SCH_1):PAGE27_I424@PURE_QUANTA.SCONN8_G802M0083150RD3HR(CHIPS)':
 '3': CDS_PINID='\3\';
NET_NAME
'CPU0_BP2'
 '@T6G_MB_LIB.T6G(SCH_1):CPU0_BP2':
 C_SIGNAL='@t6g_mb_lib.t6g(sch_1):cpu0_bp2';
NODE_NAME     U25 A63
 '@T6G_MB_LIB.T6G(SCH_1):PAGE27_I227@PURE_QUANTA.GENOA_SP5(CHIPS)':
 'BP2': CDS_PINID='BP2';
NODE_NAME     R410 1
 '@T6G_MB_LIB.T6G(SCH_1):PAGE27_I382@PURE_QUANTA.Q_RES(CHIPS)':
 'A': CDS_PINID='A';
NODE_NAME     J48 5
 '@T6G_MB_LIB.T6G(SCH_1):PAGE27_I424@PURE_QUANTA.SCONN8_G802M0083150RD3HR(CHIPS)':
 '5': CDS_PINID='\5\';
NET_NAME
'CPU0_BP3'
 '@T6G_MB_LIB.T6G(SCH_1):CPU0_BP3':
 C_SIGNAL='@t6g_mb_lib.t6g(sch_1):cpu0_bp3';
NODE_NAME     U25 A62
 '@T6G_MB_LIB.T6G(SCH_1):PAGE27_I227@PURE_QUANTA.GENOA_SP5(CHIPS)':
 'BP3': CDS_PINID='BP3';
NODE_NAME     R411 1
 '@T6G_MB_LIB.T6G(SCH_1):PAGE27_I383@PURE_QUANTA.Q_RES(CHIPS)':
 'A': CDS_PINID='A';
NODE_NAME     J48 7
 '@T6G_MB_LIB.T6G(SCH_1):PAGE27_I424@PURE_QUANTA.SCONN8_G802M0083150RD3HR(CHIPS)':
 '7': CDS_PINID='\7\';
NET_NAME
'CPU0_CORETYPE0'
 '@T6G_MB_LIB.T6G(SCH_1):CPU0_CORETYPE0':
 C_SIGNAL='@t6g_mb_lib.t6g(sch_1):cpu0_coretype0';
NODE_NAME     U25 C70
 '@T6G_MB_LIB.T6G(SCH_1):PAGE27_I227@PURE_QUANTA.GENOA_SP5(CHIPS)':
 'CORETYPE0': CDS_PINID='CORETYPE0';
NODE_NAME     R390 2
 '@T6G_MB_LIB.T6G(SCH_1):PAGE27_I390@PURE_QUANTA.Q_RES(CHIPS)':
 'B': CDS_PINID='B';
NODE_NAME     R183 1
 '@T6G_MB_LIB.T6G(SCH_1):PAGE81_I82@PURE_QUANTA.Q_RES(CHIPS)':
 'A': CDS_PINID='A';
NET_NAME
'CPU0_CORETYPE1'
 '@T6G_MB_LIB.T6G(SCH_1):CPU0_CORETYPE1':
 C_SIGNAL='@t6g_mb_lib.t6g(sch_1):cpu0_coretype1';
NODE_NAME     U25 B69
 '@T6G_MB_LIB.T6G(SCH_1):PAGE27_I227@PURE_QUANTA.GENOA_SP5(CHIPS)':
 'CORETYPE1': CDS_PINID='CORETYPE1';
NODE_NAME     R388 2
 '@T6G_MB_LIB.T6G(SCH_1):PAGE27_I389@PURE_QUANTA.Q_RES(CHIPS)':
 'B': CDS_PINID='B';
NODE_NAME     R184 1
 '@T6G_MB_LIB.T6G(SCH_1):PAGE81_I48@PURE_QUANTA.Q_RES(CHIPS)':
 'A': CDS_PINID='A';
NET_NAME
'CPU0_CORETYPE2'
 '@T6G_MB_LIB.T6G(SCH_1):CPU0_CORETYPE2':
 C_SIGNAL='@t6g_mb_lib.t6g(sch_1):cpu0_coretype2';
NODE_NAME     U25 D68
 '@T6G_MB_LIB.T6G(SCH_1):PAGE27_I227@PURE_QUANTA.GENOA_SP5(CHIPS)':
 'CORETYPE2': CDS_PINID='CORETYPE2';
NODE_NAME     R387 2
 '@T6G_MB_LIB.T6G(SCH_1):PAGE27_I388@PURE_QUANTA.Q_RES(CHIPS)':
 'B': CDS_PINID='B';
NODE_NAME     R185 1
 '@T6G_MB_LIB.T6G(SCH_1):PAGE81_I80@PURE_QUANTA.Q_RES(CHIPS)':
 'A': CDS_PINID='A';
NET_NAME
'CPU0_ESPI0_ALERT_N'
 '@T6G_MB_LIB.T6G(SCH_1):CPU0_ESPI0_ALERT_N':
 C_SIGNAL='@t6g_mb_lib.t6g(sch_1):cpu0_espi0_alert_n';
NODE_NAME     U25 DJ22
 '@T6G_MB_LIB.T6G(SCH_1):PAGE29_I287@PURE_QUANTA.GENOA_SP5(CHIPS)':
 'ESPI0_ALERT_L||AGPIO108': CDS_PINID='\espi0_alert_l||agpio108\';
NODE_NAME     R1593 2
 '@T6G_MB_LIB.T6G(SCH_1):PAGE29_I427@PURE_QUANTA.Q_RES(CHIPS)':
 'B': CDS_PINID='B';
NET_NAME
'CPU0_ESPI_CS0_N'
 '@T6G_MB_LIB.T6G(SCH_1):CPU0_ESPI_CS0_N':
 C_SIGNAL='@t6g_mb_lib.t6g(sch_1):cpu0_espi_cs0_n';
NODE_NAME     U25 DG28
 '@T6G_MB_LIB.T6G(SCH_1):PAGE29_I287@PURE_QUANTA.GENOA_SP5(CHIPS)':
 'ESPI_CS0_L||AGPIO124': CDS_PINID='\espi_cs0_l||agpio124\';
NODE_NAME     R1592 2
 '@T6G_MB_LIB.T6G(SCH_1):PAGE29_I426@PURE_QUANTA.Q_RES(CHIPS)':
 'B': CDS_PINID='B';
NET_NAME
'CPU0_FORCE_SELFREFRESH'
 '@T6G_MB_LIB.T6G(SCH_1):CPU0_FORCE_SELFREFRESH':
 C_SIGNAL='@t6g_mb_lib.t6g(sch_1):cpu0_force_selfrefresh';
NODE_NAME     R186 2
 '@T6G_MB_LIB.T6G(SCH_1):PAGE80_I129@PURE_QUANTA.Q_RES(CHIPS)':
 'B': CDS_PINID='B';
NODE_NAME     U25 B63
 '@T6G_MB_LIB.T6G(SCH_1):PAGE28_I188@PURE_QUANTA.GENOA_SP5(CHIPS)':
 'FORCE_SELFREFRESH': CDS_PINID='FORCE_SELFREFRESH';
NODE_NAME     R438 1
 '@T6G_MB_LIB.T6G(SCH_1):PAGE28_I222@PURE_QUANTA.Q_RES(CHIPS)':
 'A': CDS_PINID='A';
NODE_NAME     R6502 1
 '@T6G_MB_LIB.T6G(SCH_1):PAGE28_I224@PURE_QUANTA.Q_RES(CHIPS)':
 'A': CDS_PINID='A';
NET_NAME
'CPU0_HDT_BYPASS_SEL'
 '@T6G_MB_LIB.T6G(SCH_1):CPU0_HDT_BYPASS_SEL':
 C_SIGNAL='@t6g_mb_lib.t6g(sch_1):cpu0_hdt_bypass_sel';
NODE_NAME     U153 7
 '@T6G_MB_LIB.T6G(SCH_1):PAGE151_I1@PURE_QUANTA.SN74AUC2G66DCTR(CHIPS)':
 '1C': CDS_PINID='\1c\';
NODE_NAME     R1646 2
 '@T6G_MB_LIB.T6G(SCH_1):PAGE151_I10@PURE_QUANTA.Q_RES(CHIPS)':
 'B': CDS_PINID='B';
NODE_NAME     U13 7
 '@T6G_MB_LIB.T6G(SCH_1):PAGE151_I17@PURE_QUANTA.SN74AUC2G66DCTR(CHIPS)':
 '1C': CDS_PINID='\1c\';
NODE_NAME     Q63 G
 '@T6G_MB_LIB.T6G(SCH_1):PAGE151_I45@PURE_QUANTA.MOSFET_N(CHIPS)':
 'GATE': CDS_PINID='GATE';
NODE_NAME     R158 2
 '@T6G_MB_LIB.T6G(SCH_1):PAGE80_I154@PURE_QUANTA.Q_RES(CHIPS)':
 'B': CDS_PINID='B';
NET_NAME
'CPU0_HDT_CONN_TESTEN'
 '@T6G_MB_LIB.T6G(SCH_1):CPU0_HDT_CONN_TESTEN':
 C_SIGNAL='@t6g_mb_lib.t6g(sch_1):cpu0_hdt_conn_testen';
NODE_NAME     R1632 2
 '@T6G_MB_LIB.T6G(SCH_1):PAGE149_I114@PURE_QUANTA.Q_RES(CHIPS)':
 'B': CDS_PINID='B';
NODE_NAME     C551 1
 '@T6G_MB_LIB.T6G(SCH_1):PAGE149_I123@PURE_QUANTA.Q_CAP(CHIPS)':
 'A': CDS_PINID='A';
NODE_NAME     R258 2
 '@T6G_MB_LIB.T6G(SCH_1):PAGE80_I177@PURE_QUANTA.Q_RES(CHIPS)':
 'B': CDS_PINID='B';
NET_NAME
'CPU0_JTAG_BUF_OE'
 '@T6G_MB_LIB.T6G(SCH_1):CPU0_JTAG_BUF_OE':
 C_SIGNAL='@t6g_mb_lib.t6g(sch_1):cpu0_jtag_buf_oe';
NODE_NAME     U150 9
 '@T6G_MB_LIB.T6G(SCH_1):PAGE150_I8@PURE_QUANTA.SN74AVC4T774PWR(CHIPS)':
 'OE': CDS_PINID='OE';
NODE_NAME     R159 1
 '@T6G_MB_LIB.T6G(SCH_1):PAGE80_I111@PURE_QUANTA.Q_RES(CHIPS)':
 'A': CDS_PINID='A';
NET_NAME
'CPU0_JTAG_BUF_R_OE'
 '@T6G_MB_LIB.T6G(SCH_1):CPU0_JTAG_BUF_R_OE':
 C_SIGNAL='@t6g_mb_lib.t6g(sch_1):cpu0_jtag_buf_r_oe';
NODE_NAME     R159 2
 '@T6G_MB_LIB.T6G(SCH_1):PAGE80_I111@PURE_QUANTA.Q_RES(CHIPS)':
 'B': CDS_PINID='B';
NODE_NAME     U18 H20
 '@T6G_MB_LIB.T6G(SCH_1):PAGE80_I217@PURE_QUANTA.LCMXO3LF9400C5BG484C(CHIPS)':
 'PR7D': CDS_PINID='PR7D';
NET_NAME
'CPU0_NMI_SYNC_FLOOD_N'
 '@T6G_MB_LIB.T6G(SCH_1):CPU0_NMI_SYNC_FLOOD_N':
 C_SIGNAL='@t6g_mb_lib.t6g(sch_1):cpu0_nmi_sync_flood_n';
NODE_NAME     R219 1
 '@T6G_MB_LIB.T6G(SCH_1):PAGE80_I108@PURE_QUANTA.Q_RES(CHIPS)':
 'A': CDS_PINID='A';
NODE_NAME     R441 1
 '@T6G_MB_LIB.T6G(SCH_1):PAGE28_I55@PURE_QUANTA.Q_RES(CHIPS)':
 'A': CDS_PINID='A';
NODE_NAME     U25 DJ31
 '@T6G_MB_LIB.T6G(SCH_1):PAGE28_I188@PURE_QUANTA.GENOA_SP5(CHIPS)':
 'NMI_SYNC_FLOOD_L': CDS_PINID='NMI_SYNC_FLOOD_L';
NET_NAME
'CPU0_NV_SAVE_N'
 '@T6G_MB_LIB.T6G(SCH_1):CPU0_NV_SAVE_N':
 C_SIGNAL='@t6g_mb_lib.t6g(sch_1):cpu0_nv_save_n';
NODE_NAME     R253 1
 '@T6G_MB_LIB.T6G(SCH_1):PAGE80_I116@PURE_QUANTA.Q_RES(CHIPS)':
 'A': CDS_PINID='A';
NODE_NAME     R452 1
 '@T6G_MB_LIB.T6G(SCH_1):PAGE28_I45@PURE_QUANTA.Q_RES(CHIPS)':
 'A': CDS_PINID='A';
NODE_NAME     U25 B64
 '@T6G_MB_LIB.T6G(SCH_1):PAGE28_I188@PURE_QUANTA.GENOA_SP5(CHIPS)':
 'NV_SAVE_L': CDS_PINID='NV_SAVE_L';
NET_NAME
'CPU0_PROCHOT_N'
 '@T6G_MB_LIB.T6G(SCH_1):CPU0_PROCHOT_N':
 C_SIGNAL='@t6g_mb_lib.t6g(sch_1):cpu0_prochot_n';
NODE_NAME     U25 A69
 '@T6G_MB_LIB.T6G(SCH_1):PAGE27_I227@PURE_QUANTA.GENOA_SP5(CHIPS)':
 'PROCHOT_L': CDS_PINID='PROCHOT_L';
NODE_NAME     R412 1
 '@T6G_MB_LIB.T6G(SCH_1):PAGE27_I377@PURE_QUANTA.Q_RES(CHIPS)':
 'A': CDS_PINID='A';
NODE_NAME     R179 2
 '@T6G_MB_LIB.T6G(SCH_1):PAGE81_I110@PURE_QUANTA.Q_RES(CHIPS)':
 'B': CDS_PINID='B';
NET_NAME
'CPU0_PWR_BTN_N'
 '@T6G_MB_LIB.T6G(SCH_1):CPU0_PWR_BTN_N':
 C_SIGNAL='@t6g_mb_lib.t6g(sch_1):cpu0_pwr_btn_n';
NODE_NAME     R215 1
 '@T6G_MB_LIB.T6G(SCH_1):PAGE80_I104@PURE_QUANTA.Q_RES(CHIPS)':
 'A': CDS_PINID='A';
NODE_NAME     J6 1
 '@T6G_MB_LIB.T6G(SCH_1):PAGE28_I28@PURE_QUANTA.CONN6_HBC1031L200D8H(CHIPS)':
 '1': CDS_PINID='\1\';
NODE_NAME     R424 2
 '@T6G_MB_LIB.T6G(SCH_1):PAGE28_I30@PURE_QUANTA.Q_RES(CHIPS)':
 'B': CDS_PINID='B';
NODE_NAME     U25 DH7
 '@T6G_MB_LIB.T6G(SCH_1):PAGE28_I188@PURE_QUANTA.GENOA_SP5(CHIPS)':
 'PWR_BTN_L||AGPIO0': CDS_PINID='\pwr_btn_l||agpio0\';
NET_NAME
'CPU0_PWR_GD_OUT'
 '@T6G_MB_LIB.T6G(SCH_1):CPU0_PWR_GD_OUT':
 C_SIGNAL='@t6g_mb_lib.t6g(sch_1):cpu0_pwr_gd_out';
NODE_NAME     R440 2
 '@T6G_MB_LIB.T6G(SCH_1):PAGE28_I37@PURE_QUANTA.Q_RES(CHIPS)':
 'B': CDS_PINID='B';
NODE_NAME     R288 1
 '@T6G_MB_LIB.T6G(SCH_1):PAGE28_I42@PURE_QUANTA.Q_RES(CHIPS)':
 'A': CDS_PINID='A';
NODE_NAME     R434 1
 '@T6G_MB_LIB.T6G(SCH_1):PAGE28_I165@PURE_QUANTA.Q_RES(CHIPS)':
 'A': CDS_PINID='A';
NODE_NAME     U25 DH36
 '@T6G_MB_LIB.T6G(SCH_1):PAGE28_I188@PURE_QUANTA.GENOA_SP5(CHIPS)':
 'PWRGD_OUT||AGPIO12': CDS_PINID='\pwrgd_out||agpio12\';
NET_NAME
'CPU0_PWR_GOOD'
 '@T6G_MB_LIB.T6G(SCH_1):CPU0_PWR_GOOD':
 C_SIGNAL='@t6g_mb_lib.t6g(sch_1):cpu0_pwr_good';
NODE_NAME     R218 1
 '@T6G_MB_LIB.T6G(SCH_1):PAGE80_I32@PURE_QUANTA.Q_RES(CHIPS)':
 'A': CDS_PINID='A';
NODE_NAME     R287 2
 '@T6G_MB_LIB.T6G(SCH_1):PAGE28_I36@PURE_QUANTA.Q_RES(CHIPS)':
 'B': CDS_PINID='B';
NODE_NAME     R276 1
 '@T6G_MB_LIB.T6G(SCH_1):PAGE28_I41@PURE_QUANTA.Q_RES(CHIPS)':
 'A': CDS_PINID='A';
NODE_NAME     U25 DJ8
 '@T6G_MB_LIB.T6G(SCH_1):PAGE28_I188@PURE_QUANTA.GENOA_SP5(CHIPS)':
 'PWR_GOOD': CDS_PINID='PWR_GOOD';
NET_NAME
'CPU0_ROM_TYPE_SELECT'
 '@T6G_MB_LIB.T6G(SCH_1):CPU0_ROM_TYPE_SELECT':
 C_SIGNAL='@t6g_mb_lib.t6g(sch_1):cpu0_rom_type_select';
NODE_NAME     R748 2
 '@T6G_MB_LIB.T6G(SCH_1):PAGE75_I9@PURE_QUANTA.Q_RES(CHIPS)':
 'B': CDS_PINID='B';
NODE_NAME     R737 2
 '@T6G_MB_LIB.T6G(SCH_1):PAGE75_I43@PURE_QUANTA.Q_RES(CHIPS)':
 'B': CDS_PINID='B';
NODE_NAME     U25 DG32
 '@T6G_MB_LIB.T6G(SCH_1):PAGE28_I188@PURE_QUANTA.GENOA_SP5(CHIPS)':
 'AGPIO109': CDS_PINID='AGPIO109';
NET_NAME
'CPU0_RTC_LDO_SELECT'
 '@T6G_MB_LIB.T6G(SCH_1):CPU0_RTC_LDO_SELECT':
 C_SIGNAL='@t6g_mb_lib.t6g(sch_1):cpu0_rtc_ldo_select';
NODE_NAME     U25 DH8
 '@T6G_MB_LIB.T6G(SCH_1):PAGE27_I227@PURE_QUANTA.GENOA_SP5(CHIPS)':
 'RTC_LDO_SELECT': CDS_PINID='RTC_LDO_SELECT';
NODE_NAME     R5055 2
 '@T6G_MB_LIB.T6G(SCH_1):PAGE27_I427@PURE_QUANTA.Q_RES(CHIPS)':
 'B': CDS_PINID='B';
NODE_NAME     R5056 1
 '@T6G_MB_LIB.T6G(SCH_1):PAGE27_I428@PURE_QUANTA.Q_RES(CHIPS)':
 'A': CDS_PINID='A';
NET_NAME
'CPU0_SA0'
 '@T6G_MB_LIB.T6G(SCH_1):CPU0_SA0':
 C_SIGNAL='@t6g_mb_lib.t6g(sch_1):cpu0_sa0';
NODE_NAME     U25 DJ55
 '@T6G_MB_LIB.T6G(SCH_1):PAGE27_I227@PURE_QUANTA.GENOA_SP5(CHIPS)':
 'SA0': CDS_PINID='SA0';
NODE_NAME     R392 2
 '@T6G_MB_LIB.T6G(SCH_1):PAGE27_I395@PURE_QUANTA.Q_RES(CHIPS)':
 'B': CDS_PINID='B';
NODE_NAME     R393 1
 '@T6G_MB_LIB.T6G(SCH_1):PAGE27_I396@PURE_QUANTA.Q_RES(CHIPS)':
 'A': CDS_PINID='A';
NODE_NAME     R220 2
 '@T6G_MB_LIB.T6G(SCH_1):PAGE81_I109@PURE_QUANTA.Q_RES(CHIPS)':
 'B': CDS_PINID='B';
NET_NAME
'CPU0_SA1'
 '@T6G_MB_LIB.T6G(SCH_1):CPU0_SA1':
 C_SIGNAL='@t6g_mb_lib.t6g(sch_1):cpu0_sa1';
NODE_NAME     U25 DJ56
 '@T6G_MB_LIB.T6G(SCH_1):PAGE27_I227@PURE_QUANTA.GENOA_SP5(CHIPS)':
 'SA1': CDS_PINID='SA1';
NODE_NAME     R394 1
 '@T6G_MB_LIB.T6G(SCH_1):PAGE27_I397@PURE_QUANTA.Q_RES(CHIPS)':
 'A': CDS_PINID='A';
NODE_NAME     R221 2
 '@T6G_MB_LIB.T6G(SCH_1):PAGE81_I107@PURE_QUANTA.Q_RES(CHIPS)':
 'B': CDS_PINID='B';
NET_NAME
'CPU0_SLP_S3_N'
 '@T6G_MB_LIB.T6G(SCH_1):CPU0_SLP_S3_N':
 C_SIGNAL='@t6g_mb_lib.t6g(sch_1):cpu0_slp_s3_n';
NODE_NAME     R449 1
 '@T6G_MB_LIB.T6G(SCH_1):PAGE28_I48@PURE_QUANTA.Q_RES(CHIPS)':
 'A': CDS_PINID='A';
NODE_NAME     R249 2
 '@T6G_MB_LIB.T6G(SCH_1):PAGE28_I135@PURE_QUANTA.Q_RES(CHIPS)':
 'B': CDS_PINID='B';
NODE_NAME     U25 DJ5
 '@T6G_MB_LIB.T6G(SCH_1):PAGE28_I188@PURE_QUANTA.GENOA_SP5(CHIPS)':
 'SLP_S3_L': CDS_PINID='SLP_S3_L';
NET_NAME
'CPU0_SLP_S5_N'
 '@T6G_MB_LIB.T6G(SCH_1):CPU0_SLP_S5_N':
 C_SIGNAL='@t6g_mb_lib.t6g(sch_1):cpu0_slp_s5_n';
NODE_NAME     R248 2
 '@T6G_MB_LIB.T6G(SCH_1):PAGE28_I136@PURE_QUANTA.Q_RES(CHIPS)':
 'B': CDS_PINID='B';
NODE_NAME     R448 1
 '@T6G_MB_LIB.T6G(SCH_1):PAGE28_I49@PURE_QUANTA.Q_RES(CHIPS)':
 'A': CDS_PINID='A';
NODE_NAME     U25 DG4
 '@T6G_MB_LIB.T6G(SCH_1):PAGE28_I188@PURE_QUANTA.GENOA_SP5(CHIPS)':
 'SLP_S5_L': CDS_PINID='SLP_S5_L';
NET_NAME
'CPU0_SMERR_N'
 '@T6G_MB_LIB.T6G(SCH_1):CPU0_SMERR_N':
 C_SIGNAL='@t6g_mb_lib.t6g(sch_1):cpu0_smerr_n';
NODE_NAME     R250 2
 '@T6G_MB_LIB.T6G(SCH_1):PAGE80_I180@PURE_QUANTA.Q_RES(CHIPS)':
 'B': CDS_PINID='B';
NODE_NAME     R450 1
 '@T6G_MB_LIB.T6G(SCH_1):PAGE28_I47@PURE_QUANTA.Q_RES(CHIPS)':
 'A': CDS_PINID='A';
NODE_NAME     U25 DJ11
 '@T6G_MB_LIB.T6G(SCH_1):PAGE28_I188@PURE_QUANTA.GENOA_SP5(CHIPS)':
 'SMERR_L||AGPIO24': CDS_PINID='\smerr_l||agpio24\';
NET_NAME
'CPU0_SP5R1'
 '@T6G_MB_LIB.T6G(SCH_1):CPU0_SP5R1':
 C_SIGNAL='@t6g_mb_lib.t6g(sch_1):cpu0_sp5r1';
NODE_NAME     U25 C19
 '@T6G_MB_LIB.T6G(SCH_1):PAGE27_I227@PURE_QUANTA.GENOA_SP5(CHIPS)':
 'SP5R1': CDS_PINID='SP5R1';
NODE_NAME     R397 2
 '@T6G_MB_LIB.T6G(SCH_1):PAGE27_I394@PURE_QUANTA.Q_RES(CHIPS)':
 'B': CDS_PINID='B';
NODE_NAME     R180 1
 '@T6G_MB_LIB.T6G(SCH_1):PAGE81_I45@PURE_QUANTA.Q_RES(CHIPS)':
 'A': CDS_PINID='A';
NET_NAME
'CPU0_SP5R2'
 '@T6G_MB_LIB.T6G(SCH_1):CPU0_SP5R2':
 C_SIGNAL='@t6g_mb_lib.t6g(sch_1):cpu0_sp5r2';
NODE_NAME     U25 C68
 '@T6G_MB_LIB.T6G(SCH_1):PAGE27_I227@PURE_QUANTA.GENOA_SP5(CHIPS)':
 'SP5R2': CDS_PINID='SP5R2';
NODE_NAME     R396 2
 '@T6G_MB_LIB.T6G(SCH_1):PAGE27_I393@PURE_QUANTA.Q_RES(CHIPS)':
 'B': CDS_PINID='B';
NODE_NAME     R181 1
 '@T6G_MB_LIB.T6G(SCH_1):PAGE81_I46@PURE_QUANTA.Q_RES(CHIPS)':
 'A': CDS_PINID='A';
NET_NAME
'CPU0_SP5R3'
 '@T6G_MB_LIB.T6G(SCH_1):CPU0_SP5R3':
 C_SIGNAL='@t6g_mb_lib.t6g(sch_1):cpu0_sp5r3';
NODE_NAME     U25 DH73
 '@T6G_MB_LIB.T6G(SCH_1):PAGE27_I227@PURE_QUANTA.GENOA_SP5(CHIPS)':
 'SP5R3': CDS_PINID='SP5R3';
NODE_NAME     R391 2
 '@T6G_MB_LIB.T6G(SCH_1):PAGE27_I392@PURE_QUANTA.Q_RES(CHIPS)':
 'B': CDS_PINID='B';
NODE_NAME     R222 1
 '@T6G_MB_LIB.T6G(SCH_1):PAGE81_I52@PURE_QUANTA.Q_RES(CHIPS)':
 'A': CDS_PINID='A';
NET_NAME
'CPU0_SP5R4'
 '@T6G_MB_LIB.T6G(SCH_1):CPU0_SP5R4':
 C_SIGNAL='@t6g_mb_lib.t6g(sch_1):cpu0_sp5r4';
NODE_NAME     U25 DH10
 '@T6G_MB_LIB.T6G(SCH_1):PAGE27_I227@PURE_QUANTA.GENOA_SP5(CHIPS)':
 'SP5R4': CDS_PINID='SP5R4';
NODE_NAME     R389 2
 '@T6G_MB_LIB.T6G(SCH_1):PAGE27_I391@PURE_QUANTA.Q_RES(CHIPS)':
 'B': CDS_PINID='B';
NODE_NAME     R223 2
 '@T6G_MB_LIB.T6G(SCH_1):PAGE81_I100@PURE_QUANTA.Q_RES(CHIPS)':
 'B': CDS_PINID='B';
NET_NAME
'CPU0_SPD_HOST_CTRL_N'
 '@T6G_MB_LIB.T6G(SCH_1):CPU0_SPD_HOST_CTRL_N':
 C_SIGNAL='@t6g_mb_lib.t6g(sch_1):cpu0_spd_host_ctrl_n';
NODE_NAME     R251 2
 '@T6G_MB_LIB.T6G(SCH_1):PAGE80_I162@PURE_QUANTA.Q_RES(CHIPS)':
 'B': CDS_PINID='B';
NODE_NAME     R451 1
 '@T6G_MB_LIB.T6G(SCH_1):PAGE28_I46@PURE_QUANTA.Q_RES(CHIPS)':
 'A': CDS_PINID='A';
NODE_NAME     U25 DE36
 '@T6G_MB_LIB.T6G(SCH_1):PAGE28_I188@PURE_QUANTA.GENOA_SP5(CHIPS)':
 'AGPIO3||SPD_HOST_CTRL_L': CDS_PINID='\agpio3||spd_host_ctrl_l\';
NET_NAME
'CPU0_SPD_HOST_CTRL_R1_N'
 '@T6G_MB_LIB.T6G(SCH_1):CPU0_SPD_HOST_CTRL_R1_N':
 C_SIGNAL='@t6g_mb_lib.t6g(sch_1):cpu0_spd_host_ctrl_r1_n';
NODE_NAME     R251 1
 '@T6G_MB_LIB.T6G(SCH_1):PAGE80_I162@PURE_QUANTA.Q_RES(CHIPS)':
 'A': CDS_PINID='A';
NODE_NAME     U18 R18
 '@T6G_MB_LIB.T6G(SCH_1):PAGE80_I217@PURE_QUANTA.LCMXO3LF9400C5BG484C(CHIPS)':
 'PR26A': CDS_PINID='PR26A';
NET_NAME
'CPU0_THERMTRIP_N'
 '@T6G_MB_LIB.T6G(SCH_1):CPU0_THERMTRIP_N':
 C_SIGNAL='@t6g_mb_lib.t6g(sch_1):cpu0_thermtrip_n';
NODE_NAME     U25 DJ9
 '@T6G_MB_LIB.T6G(SCH_1):PAGE27_I227@PURE_QUANTA.GENOA_SP5(CHIPS)':
 'THERMTRIP_L': CDS_PINID='THERMTRIP_L';
NODE_NAME     R417 1
 '@T6G_MB_LIB.T6G(SCH_1):PAGE27_I379@PURE_QUANTA.Q_RES(CHIPS)':
 'A': CDS_PINID='A';
NODE_NAME     R489 1
 '@T6G_MB_LIB.T6G(SCH_1):PAGE27_I399@PURE_QUANTA.Q_RES(CHIPS)':
 'A': CDS_PINID='A';
NET_NAME
'CPU0_THERMTRIP_R_N'
 '@T6G_MB_LIB.T6G(SCH_1):CPU0_THERMTRIP_R_N':
 C_SIGNAL='@t6g_mb_lib.t6g(sch_1):cpu0_thermtrip_r_n';
NODE_NAME     R489 2
 '@T6G_MB_LIB.T6G(SCH_1):PAGE27_I399@PURE_QUANTA.Q_RES(CHIPS)':
 'B': CDS_PINID='B';
NODE_NAME     U18 H2
 '@T6G_MB_LIB.T6G(SCH_1):PAGE81_I143@PURE_QUANTA.LCMXO3LF9400C5BG484C(CHIPS)':
 'PL10A': CDS_PINID='PL10A';
NODE_NAME     R1533 1
 '@T6G_MB_LIB.T6G(SCH_1):PAGE27_I429@PURE_QUANTA.Q_RES(CHIPS)':
 'A': CDS_PINID='A';
NET_NAME
'CPU0_XTRIG_L4'
 '@T6G_MB_LIB.T6G(SCH_1):CPU0_XTRIG_L4':
 C_SIGNAL='@t6g_mb_lib.t6g(sch_1):cpu0_xtrig_l4';
NODE_NAME     R481 1
 '@T6G_MB_LIB.T6G(SCH_1):PAGE27_I335@PURE_QUANTA.Q_RES(CHIPS)':
 'A': CDS_PINID='A';
NODE_NAME     R156 2
 '@T6G_MB_LIB.T6G(SCH_1):PAGE27_I346@PURE_QUANTA.Q_RES(CHIPS)':
 'B': CDS_PINID='B';
NODE_NAME     R413 1
 '@T6G_MB_LIB.T6G(SCH_1):PAGE27_I384@PURE_QUANTA.Q_RES(CHIPS)':
 'A': CDS_PINID='A';
NODE_NAME     R236 1
 '@T6G_MB_LIB.T6G(SCH_1):PAGE81_I66@PURE_QUANTA.Q_RES(CHIPS)':
 'A': CDS_PINID='A';
NODE_NAME     J212 1
 '@T6G_MB_LIB.T6G(SCH_1):PAGE27_I423@PURE_QUANTA.CONN10_HBC1051L300D8H(CHIPS)':
 '1': CDS_PINID='\1\';
NET_NAME
'CPU0_XTRIG_L5'
 '@T6G_MB_LIB.T6G(SCH_1):CPU0_XTRIG_L5':
 C_SIGNAL='@t6g_mb_lib.t6g(sch_1):cpu0_xtrig_l5';
NODE_NAME     R483 1
 '@T6G_MB_LIB.T6G(SCH_1):PAGE27_I334@PURE_QUANTA.Q_RES(CHIPS)':
 'A': CDS_PINID='A';
NODE_NAME     R157 2
 '@T6G_MB_LIB.T6G(SCH_1):PAGE27_I347@PURE_QUANTA.Q_RES(CHIPS)':
 'B': CDS_PINID='B';
NODE_NAME     R414 1
 '@T6G_MB_LIB.T6G(SCH_1):PAGE27_I385@PURE_QUANTA.Q_RES(CHIPS)':
 'A': CDS_PINID='A';
NODE_NAME     R478 1
 '@T6G_MB_LIB.T6G(SCH_1):PAGE149_I150@PURE_QUANTA.Q_RES(CHIPS)':
 'A': CDS_PINID='A';
NODE_NAME     R237 1
 '@T6G_MB_LIB.T6G(SCH_1):PAGE81_I69@PURE_QUANTA.Q_RES(CHIPS)':
 'A': CDS_PINID='A';
NODE_NAME     J212 3
 '@T6G_MB_LIB.T6G(SCH_1):PAGE27_I423@PURE_QUANTA.CONN10_HBC1051L300D8H(CHIPS)':
 '3': CDS_PINID='\3\';
NET_NAME
'CPU0_XTRIG_L6'
 '@T6G_MB_LIB.T6G(SCH_1):CPU0_XTRIG_L6':
 C_SIGNAL='@t6g_mb_lib.t6g(sch_1):cpu0_xtrig_l6';
NODE_NAME     R484 1
 '@T6G_MB_LIB.T6G(SCH_1):PAGE27_I336@PURE_QUANTA.Q_RES(CHIPS)':
 'A': CDS_PINID='A';
NODE_NAME     R356 2
 '@T6G_MB_LIB.T6G(SCH_1):PAGE27_I349@PURE_QUANTA.Q_RES(CHIPS)':
 'B': CDS_PINID='B';
NODE_NAME     R415 1
 '@T6G_MB_LIB.T6G(SCH_1):PAGE27_I386@PURE_QUANTA.Q_RES(CHIPS)':
 'A': CDS_PINID='A';
NODE_NAME     R476 1
 '@T6G_MB_LIB.T6G(SCH_1):PAGE149_I148@PURE_QUANTA.Q_RES(CHIPS)':
 'A': CDS_PINID='A';
NODE_NAME     R238 1
 '@T6G_MB_LIB.T6G(SCH_1):PAGE81_I71@PURE_QUANTA.Q_RES(CHIPS)':
 'A': CDS_PINID='A';
NODE_NAME     J212 5
 '@T6G_MB_LIB.T6G(SCH_1):PAGE27_I423@PURE_QUANTA.CONN10_HBC1051L300D8H(CHIPS)':
 '5': CDS_PINID='\5\';
NET_NAME
'CPU0_XTRIG_L7'
 '@T6G_MB_LIB.T6G(SCH_1):CPU0_XTRIG_L7':
 C_SIGNAL='@t6g_mb_lib.t6g(sch_1):cpu0_xtrig_l7';
NODE_NAME     R485 1
 '@T6G_MB_LIB.T6G(SCH_1):PAGE27_I337@PURE_QUANTA.Q_RES(CHIPS)':
 'A': CDS_PINID='A';
NODE_NAME     R357 2
 '@T6G_MB_LIB.T6G(SCH_1):PAGE27_I348@PURE_QUANTA.Q_RES(CHIPS)':
 'B': CDS_PINID='B';
NODE_NAME     R416 1
 '@T6G_MB_LIB.T6G(SCH_1):PAGE27_I387@PURE_QUANTA.Q_RES(CHIPS)':
 'A': CDS_PINID='A';
NODE_NAME     R477 1
 '@T6G_MB_LIB.T6G(SCH_1):PAGE149_I147@PURE_QUANTA.Q_RES(CHIPS)':
 'A': CDS_PINID='A';
NODE_NAME     R239 1
 '@T6G_MB_LIB.T6G(SCH_1):PAGE81_I62@PURE_QUANTA.Q_RES(CHIPS)':
 'A': CDS_PINID='A';
NODE_NAME     J212 7
 '@T6G_MB_LIB.T6G(SCH_1):PAGE27_I423@PURE_QUANTA.CONN10_HBC1051L300D8H(CHIPS)':
 '7': CDS_PINID='\7\';
NET_NAME
'CPU0_XTRIG_R1_L4'
 '@T6G_MB_LIB.T6G(SCH_1):CPU0_XTRIG_R1_L4':
 C_SIGNAL='@t6g_mb_lib.t6g(sch_1):cpu0_xtrig_r1_l4';
NODE_NAME     R481 2
 '@T6G_MB_LIB.T6G(SCH_1):PAGE27_I335@PURE_QUANTA.Q_RES(CHIPS)':
 'B': CDS_PINID='B';
NODE_NAME     J5 1
 '@T6G_MB_LIB.T6G(SCH_1):PAGE27_I425@PURE_QUANTA.SCONN8_G802M0083150RD3HR(CHIPS)':
 '1': CDS_PINID='\1\';
NET_NAME
'CPU0_XTRIG_R1_L5'
 '@T6G_MB_LIB.T6G(SCH_1):CPU0_XTRIG_R1_L5':
 C_SIGNAL='@t6g_mb_lib.t6g(sch_1):cpu0_xtrig_r1_l5';
NODE_NAME     R483 2
 '@T6G_MB_LIB.T6G(SCH_1):PAGE27_I334@PURE_QUANTA.Q_RES(CHIPS)':
 'B': CDS_PINID='B';
NODE_NAME     J5 3
 '@T6G_MB_LIB.T6G(SCH_1):PAGE27_I425@PURE_QUANTA.SCONN8_G802M0083150RD3HR(CHIPS)':
 '3': CDS_PINID='\3\';
NET_NAME
'CPU0_XTRIG_R1_L6'
 '@T6G_MB_LIB.T6G(SCH_1):CPU0_XTRIG_R1_L6':
 C_SIGNAL='@t6g_mb_lib.t6g(sch_1):cpu0_xtrig_r1_l6';
NODE_NAME     R484 2
 '@T6G_MB_LIB.T6G(SCH_1):PAGE27_I336@PURE_QUANTA.Q_RES(CHIPS)':
 'B': CDS_PINID='B';
NODE_NAME     J5 5
 '@T6G_MB_LIB.T6G(SCH_1):PAGE27_I425@PURE_QUANTA.SCONN8_G802M0083150RD3HR(CHIPS)':
 '5': CDS_PINID='\5\';
NET_NAME
'CPU0_XTRIG_R1_L7'
 '@T6G_MB_LIB.T6G(SCH_1):CPU0_XTRIG_R1_L7':
 C_SIGNAL='@t6g_mb_lib.t6g(sch_1):cpu0_xtrig_r1_l7';
NODE_NAME     R485 2
 '@T6G_MB_LIB.T6G(SCH_1):PAGE27_I337@PURE_QUANTA.Q_RES(CHIPS)':
 'B': CDS_PINID='B';
NODE_NAME     J5 7
 '@T6G_MB_LIB.T6G(SCH_1):PAGE27_I425@PURE_QUANTA.SCONN8_G802M0083150RD3HR(CHIPS)':
 '7': CDS_PINID='\7\';
NET_NAME
'CPU0_XTRIG_R2_L4'
 '@T6G_MB_LIB.T6G(SCH_1):CPU0_XTRIG_R2_L4':
 C_SIGNAL='@t6g_mb_lib.t6g(sch_1):cpu0_xtrig_r2_l4';
NODE_NAME     U25 C66
 '@T6G_MB_LIB.T6G(SCH_1):PAGE27_I227@PURE_QUANTA.GENOA_SP5(CHIPS)':
 'XTRIG_L4': CDS_PINID='XTRIG_L4';
NODE_NAME     R156 1
 '@T6G_MB_LIB.T6G(SCH_1):PAGE27_I346@PURE_QUANTA.Q_RES(CHIPS)':
 'A': CDS_PINID='A';
NET_NAME
'CPU0_XTRIG_R2_L5'
 '@T6G_MB_LIB.T6G(SCH_1):CPU0_XTRIG_R2_L5':
 C_SIGNAL='@t6g_mb_lib.t6g(sch_1):cpu0_xtrig_r2_l5';
NODE_NAME     U25 C65
 '@T6G_MB_LIB.T6G(SCH_1):PAGE27_I227@PURE_QUANTA.GENOA_SP5(CHIPS)':
 'XTRIG_L5': CDS_PINID='XTRIG_L5';
NODE_NAME     R157 1
 '@T6G_MB_LIB.T6G(SCH_1):PAGE27_I347@PURE_QUANTA.Q_RES(CHIPS)':
 'A': CDS_PINID='A';
NET_NAME
'CPU0_XTRIG_R2_L6'
 '@T6G_MB_LIB.T6G(SCH_1):CPU0_XTRIG_R2_L6':
 C_SIGNAL='@t6g_mb_lib.t6g(sch_1):cpu0_xtrig_r2_l6';
NODE_NAME     U25 A66
 '@T6G_MB_LIB.T6G(SCH_1):PAGE27_I227@PURE_QUANTA.GENOA_SP5(CHIPS)':
 'XTRIG_L6': CDS_PINID='XTRIG_L6';
NODE_NAME     R356 1
 '@T6G_MB_LIB.T6G(SCH_1):PAGE27_I349@PURE_QUANTA.Q_RES(CHIPS)':
 'A': CDS_PINID='A';
NET_NAME
'CPU0_XTRIG_R2_L7'
 '@T6G_MB_LIB.T6G(SCH_1):CPU0_XTRIG_R2_L7':
 C_SIGNAL='@t6g_mb_lib.t6g(sch_1):cpu0_xtrig_r2_l7';
NODE_NAME     U25 A65
 '@T6G_MB_LIB.T6G(SCH_1):PAGE27_I227@PURE_QUANTA.GENOA_SP5(CHIPS)':
 'XTRIG_L7': CDS_PINID='XTRIG_L7';
NODE_NAME     R357 1
 '@T6G_MB_LIB.T6G(SCH_1):PAGE27_I348@PURE_QUANTA.Q_RES(CHIPS)':
 'A': CDS_PINID='A';
NET_NAME
'CPU1_BP0'
 '@T6G_MB_LIB.T6G(SCH_1):CPU1_BP0':
 C_SIGNAL='@t6g_mb_lib.t6g(sch_1):cpu1_bp0';
NODE_NAME     U26 C63
 '@T6G_MB_LIB.T6G(SCH_1):PAGE54_I190@PURE_QUANTA.GENOA_SP5(CHIPS)':
 'BP0': CDS_PINID='BP0';
NODE_NAME     R531 1
 '@T6G_MB_LIB.T6G(SCH_1):PAGE54_I406@PURE_QUANTA.Q_RES(CHIPS)':
 'A': CDS_PINID='A';
NODE_NAME     J49 1
 '@T6G_MB_LIB.T6G(SCH_1):PAGE54_I419@PURE_QUANTA.SCONN8_G802M0083150RD3HR(CHIPS)':
 '1': CDS_PINID='\1\';
NET_NAME
'CPU1_BP1'
 '@T6G_MB_LIB.T6G(SCH_1):CPU1_BP1':
 C_SIGNAL='@t6g_mb_lib.t6g(sch_1):cpu1_bp1';
NODE_NAME     U26 C62
 '@T6G_MB_LIB.T6G(SCH_1):PAGE54_I190@PURE_QUANTA.GENOA_SP5(CHIPS)':
 'BP1': CDS_PINID='BP1';
NODE_NAME     R532 1
 '@T6G_MB_LIB.T6G(SCH_1):PAGE54_I407@PURE_QUANTA.Q_RES(CHIPS)':
 'A': CDS_PINID='A';
NODE_NAME     J49 3
 '@T6G_MB_LIB.T6G(SCH_1):PAGE54_I419@PURE_QUANTA.SCONN8_G802M0083150RD3HR(CHIPS)':
 '3': CDS_PINID='\3\';
NET_NAME
'CPU1_BP2'
 '@T6G_MB_LIB.T6G(SCH_1):CPU1_BP2':
 C_SIGNAL='@t6g_mb_lib.t6g(sch_1):cpu1_bp2';
NODE_NAME     U26 A63
 '@T6G_MB_LIB.T6G(SCH_1):PAGE54_I190@PURE_QUANTA.GENOA_SP5(CHIPS)':
 'BP2': CDS_PINID='BP2';
NODE_NAME     R533 1
 '@T6G_MB_LIB.T6G(SCH_1):PAGE54_I408@PURE_QUANTA.Q_RES(CHIPS)':
 'A': CDS_PINID='A';
NODE_NAME     J49 5
 '@T6G_MB_LIB.T6G(SCH_1):PAGE54_I419@PURE_QUANTA.SCONN8_G802M0083150RD3HR(CHIPS)':
 '5': CDS_PINID='\5\';
NET_NAME
'CPU1_BP3'
 '@T6G_MB_LIB.T6G(SCH_1):CPU1_BP3':
 C_SIGNAL='@t6g_mb_lib.t6g(sch_1):cpu1_bp3';
NODE_NAME     U26 A62
 '@T6G_MB_LIB.T6G(SCH_1):PAGE54_I190@PURE_QUANTA.GENOA_SP5(CHIPS)':
 'BP3': CDS_PINID='BP3';
NODE_NAME     R534 1
 '@T6G_MB_LIB.T6G(SCH_1):PAGE54_I409@PURE_QUANTA.Q_RES(CHIPS)':
 'A': CDS_PINID='A';
NODE_NAME     J49 7
 '@T6G_MB_LIB.T6G(SCH_1):PAGE54_I419@PURE_QUANTA.SCONN8_G802M0083150RD3HR(CHIPS)':
 '7': CDS_PINID='\7\';
NET_NAME
'CPU1_CORETYPE0'
 '@T6G_MB_LIB.T6G(SCH_1):CPU1_CORETYPE0':
 C_SIGNAL='@t6g_mb_lib.t6g(sch_1):cpu1_coretype0';
NODE_NAME     U26 C70
 '@T6G_MB_LIB.T6G(SCH_1):PAGE54_I190@PURE_QUANTA.GENOA_SP5(CHIPS)':
 'CORETYPE0': CDS_PINID='CORETYPE0';
NODE_NAME     R516 2
 '@T6G_MB_LIB.T6G(SCH_1):PAGE54_I402@PURE_QUANTA.Q_RES(CHIPS)':
 'B': CDS_PINID='B';
NODE_NAME     R262 1
 '@T6G_MB_LIB.T6G(SCH_1):PAGE81_I44@PURE_QUANTA.Q_RES(CHIPS)':
 'A': CDS_PINID='A';
NET_NAME
'CPU1_CORETYPE1'
 '@T6G_MB_LIB.T6G(SCH_1):CPU1_CORETYPE1':
 C_SIGNAL='@t6g_mb_lib.t6g(sch_1):cpu1_coretype1';
NODE_NAME     U26 B69
 '@T6G_MB_LIB.T6G(SCH_1):PAGE54_I190@PURE_QUANTA.GENOA_SP5(CHIPS)':
 'CORETYPE1': CDS_PINID='CORETYPE1';
NODE_NAME     R514 2
 '@T6G_MB_LIB.T6G(SCH_1):PAGE54_I401@PURE_QUANTA.Q_RES(CHIPS)':
 'B': CDS_PINID='B';
NODE_NAME     R263 1
 '@T6G_MB_LIB.T6G(SCH_1):PAGE81_I47@PURE_QUANTA.Q_RES(CHIPS)':
 'A': CDS_PINID='A';
NET_NAME
'CPU1_CORETYPE2'
 '@T6G_MB_LIB.T6G(SCH_1):CPU1_CORETYPE2':
 C_SIGNAL='@t6g_mb_lib.t6g(sch_1):cpu1_coretype2';
NODE_NAME     U26 D68
 '@T6G_MB_LIB.T6G(SCH_1):PAGE54_I190@PURE_QUANTA.GENOA_SP5(CHIPS)':
 'CORETYPE2': CDS_PINID='CORETYPE2';
NODE_NAME     R512 2
 '@T6G_MB_LIB.T6G(SCH_1):PAGE54_I400@PURE_QUANTA.Q_RES(CHIPS)':
 'B': CDS_PINID='B';
NODE_NAME     R264 1
 '@T6G_MB_LIB.T6G(SCH_1):PAGE81_I53@PURE_QUANTA.Q_RES(CHIPS)':
 'A': CDS_PINID='A';
NET_NAME
'CPU1_FORCE_SELFREFRESH'
 '@T6G_MB_LIB.T6G(SCH_1):CPU1_FORCE_SELFREFRESH':
 C_SIGNAL='@t6g_mb_lib.t6g(sch_1):cpu1_force_selfrefresh';
NODE_NAME     U26 B63
 '@T6G_MB_LIB.T6G(SCH_1):PAGE55_I182@PURE_QUANTA.GENOA_SP5(CHIPS)':
 'FORCE_SELFREFRESH': CDS_PINID='FORCE_SELFREFRESH';
NODE_NAME     R265 2
 '@T6G_MB_LIB.T6G(SCH_1):PAGE80_I126@PURE_QUANTA.Q_RES(CHIPS)':
 'B': CDS_PINID='B';
NODE_NAME     R558 1
 '@T6G_MB_LIB.T6G(SCH_1):PAGE55_I390@PURE_QUANTA.Q_RES(CHIPS)':
 'A': CDS_PINID='A';
NODE_NAME     R6503 1
 '@T6G_MB_LIB.T6G(SCH_1):PAGE55_I392@PURE_QUANTA.Q_RES(CHIPS)':
 'A': CDS_PINID='A';
NET_NAME
'CPU1_HDT_BYPASS_SEL'
 '@T6G_MB_LIB.T6G(SCH_1):CPU1_HDT_BYPASS_SEL':
 C_SIGNAL='@t6g_mb_lib.t6g(sch_1):cpu1_hdt_bypass_sel';
NODE_NAME     U14 7
 '@T6G_MB_LIB.T6G(SCH_1):PAGE151_I23@PURE_QUANTA.SN74AUC2G66DCTR(CHIPS)':
 '1C': CDS_PINID='\1c\';
NODE_NAME     R1649 2
 '@T6G_MB_LIB.T6G(SCH_1):PAGE151_I25@PURE_QUANTA.Q_RES(CHIPS)':
 'B': CDS_PINID='B';
NODE_NAME     U154 7
 '@T6G_MB_LIB.T6G(SCH_1):PAGE151_I31@PURE_QUANTA.SN74AUC2G66DCTR(CHIPS)':
 '1C': CDS_PINID='\1c\';
NODE_NAME     Q64 G
 '@T6G_MB_LIB.T6G(SCH_1):PAGE151_I46@PURE_QUANTA.MOSFET_N(CHIPS)':
 'GATE': CDS_PINID='GATE';
NODE_NAME     R173 2
 '@T6G_MB_LIB.T6G(SCH_1):PAGE80_I163@PURE_QUANTA.Q_RES(CHIPS)':
 'B': CDS_PINID='B';
NET_NAME
'CPU1_JTAG_BUF_OE'
 '@T6G_MB_LIB.T6G(SCH_1):CPU1_JTAG_BUF_OE':
 C_SIGNAL='@t6g_mb_lib.t6g(sch_1):cpu1_jtag_buf_oe';
NODE_NAME     U151 9
 '@T6G_MB_LIB.T6G(SCH_1):PAGE150_I28@PURE_QUANTA.SN74AVC4T774PWR(CHIPS)':
 'OE': CDS_PINID='OE';
NODE_NAME     R161 2
 '@T6G_MB_LIB.T6G(SCH_1):PAGE80_I161@PURE_QUANTA.Q_RES(CHIPS)':
 'B': CDS_PINID='B';
NET_NAME
'CPU1_JTAG_BUF_R_OE'
 '@T6G_MB_LIB.T6G(SCH_1):CPU1_JTAG_BUF_R_OE':
 C_SIGNAL='@t6g_mb_lib.t6g(sch_1):cpu1_jtag_buf_r_oe';
NODE_NAME     R161 1
 '@T6G_MB_LIB.T6G(SCH_1):PAGE80_I161@PURE_QUANTA.Q_RES(CHIPS)':
 'A': CDS_PINID='A';
NODE_NAME     U18 R16
 '@T6G_MB_LIB.T6G(SCH_1):PAGE80_I217@PURE_QUANTA.LCMXO3LF9400C5BG484C(CHIPS)':
 'PR26C': CDS_PINID='PR26C';
NET_NAME
'CPU1_NMI_SYNC_FLOOD_N'
 '@T6G_MB_LIB.T6G(SCH_1):CPU1_NMI_SYNC_FLOOD_N':
 C_SIGNAL='@t6g_mb_lib.t6g(sch_1):cpu1_nmi_sync_flood_n';
NODE_NAME     U26 DJ31
 '@T6G_MB_LIB.T6G(SCH_1):PAGE55_I182@PURE_QUANTA.GENOA_SP5(CHIPS)':
 'NMI_SYNC_FLOOD_L': CDS_PINID='NMI_SYNC_FLOOD_L';
NODE_NAME     R277 2
 '@T6G_MB_LIB.T6G(SCH_1):PAGE80_I165@PURE_QUANTA.Q_RES(CHIPS)':
 'B': CDS_PINID='B';
NODE_NAME     R562 2
 '@T6G_MB_LIB.T6G(SCH_1):PAGE55_I355@PURE_QUANTA.Q_RES(CHIPS)':
 'B': CDS_PINID='B';
NET_NAME
'CPU1_NV_SAVE_N'
 '@T6G_MB_LIB.T6G(SCH_1):CPU1_NV_SAVE_N':
 C_SIGNAL='@t6g_mb_lib.t6g(sch_1):cpu1_nv_save_n';
NODE_NAME     U26 B64
 '@T6G_MB_LIB.T6G(SCH_1):PAGE55_I182@PURE_QUANTA.GENOA_SP5(CHIPS)':
 'NV_SAVE_L': CDS_PINID='NV_SAVE_L';
NODE_NAME     R196 1
 '@T6G_MB_LIB.T6G(SCH_1):PAGE80_I109@PURE_QUANTA.Q_RES(CHIPS)':
 'A': CDS_PINID='A';
NODE_NAME     R553 1
 '@T6G_MB_LIB.T6G(SCH_1):PAGE55_I359@PURE_QUANTA.Q_RES(CHIPS)':
 'A': CDS_PINID='A';
NET_NAME
'CPU1_PROCHOT_N'
 '@T6G_MB_LIB.T6G(SCH_1):CPU1_PROCHOT_N':
 C_SIGNAL='@t6g_mb_lib.t6g(sch_1):cpu1_prochot_n';
NODE_NAME     U26 A69
 '@T6G_MB_LIB.T6G(SCH_1):PAGE54_I190@PURE_QUANTA.GENOA_SP5(CHIPS)':
 'PROCHOT_L': CDS_PINID='PROCHOT_L';
NODE_NAME     R520 1
 '@T6G_MB_LIB.T6G(SCH_1):PAGE54_I396@PURE_QUANTA.Q_RES(CHIPS)':
 'A': CDS_PINID='A';
NODE_NAME     R270 2
 '@T6G_MB_LIB.T6G(SCH_1):PAGE81_I112@PURE_QUANTA.Q_RES(CHIPS)':
 'B': CDS_PINID='B';
NET_NAME
'CPU1_PWRGD_OUT'
 '@T6G_MB_LIB.T6G(SCH_1):CPU1_PWRGD_OUT':
 C_SIGNAL='@t6g_mb_lib.t6g(sch_1):cpu1_pwrgd_out';
NODE_NAME     U26 DH36
 '@T6G_MB_LIB.T6G(SCH_1):PAGE55_I182@PURE_QUANTA.GENOA_SP5(CHIPS)':
 'PWRGD_OUT||AGPIO12': CDS_PINID='\pwrgd_out||agpio12\';
NODE_NAME     R491 2
 '@T6G_MB_LIB.T6G(SCH_1):PAGE55_I335@PURE_QUANTA.Q_RES(CHIPS)':
 'B': CDS_PINID='B';
NODE_NAME     R456 1
 '@T6G_MB_LIB.T6G(SCH_1):PAGE55_I339@PURE_QUANTA.Q_RES(CHIPS)':
 'A': CDS_PINID='A';
NODE_NAME     R195 2
 '@T6G_MB_LIB.T6G(SCH_1):PAGE80_I303@PURE_QUANTA.Q_RES(CHIPS)':
 'B': CDS_PINID='B';
NET_NAME
'CPU1_PWR_GD_IN'
 '@T6G_MB_LIB.T6G(SCH_1):CPU1_PWR_GD_IN':
 C_SIGNAL='@t6g_mb_lib.t6g(sch_1):cpu1_pwr_gd_in';
NODE_NAME     U26 DJ8
 '@T6G_MB_LIB.T6G(SCH_1):PAGE55_I182@PURE_QUANTA.GENOA_SP5(CHIPS)':
 'PWR_GOOD': CDS_PINID='PWR_GOOD';
NODE_NAME     R252 2
 '@T6G_MB_LIB.T6G(SCH_1):PAGE80_I128@PURE_QUANTA.Q_RES(CHIPS)':
 'B': CDS_PINID='B';
NODE_NAME     R434 2
 '@T6G_MB_LIB.T6G(SCH_1):PAGE28_I165@PURE_QUANTA.Q_RES(CHIPS)':
 'B': CDS_PINID='B';
NET_NAME
'CPU1_SA0'
 '@T6G_MB_LIB.T6G(SCH_1):CPU1_SA0':
 C_SIGNAL='@t6g_mb_lib.t6g(sch_1):cpu1_sa0';
NODE_NAME     U26 DJ55
 '@T6G_MB_LIB.T6G(SCH_1):PAGE54_I190@PURE_QUANTA.GENOA_SP5(CHIPS)':
 'SA0': CDS_PINID='SA0';
NODE_NAME     R518 2
 '@T6G_MB_LIB.T6G(SCH_1):PAGE54_I403@PURE_QUANTA.Q_RES(CHIPS)':
 'B': CDS_PINID='B';
NODE_NAME     R519 1
 '@T6G_MB_LIB.T6G(SCH_1):PAGE54_I404@PURE_QUANTA.Q_RES(CHIPS)':
 'A': CDS_PINID='A';
NODE_NAME     R266 2
 '@T6G_MB_LIB.T6G(SCH_1):PAGE81_I108@PURE_QUANTA.Q_RES(CHIPS)':
 'B': CDS_PINID='B';
NET_NAME
'CPU1_SA1'
 '@T6G_MB_LIB.T6G(SCH_1):CPU1_SA1':
 C_SIGNAL='@t6g_mb_lib.t6g(sch_1):cpu1_sa1';
NODE_NAME     U26 DJ56
 '@T6G_MB_LIB.T6G(SCH_1):PAGE54_I190@PURE_QUANTA.GENOA_SP5(CHIPS)':
 'SA1': CDS_PINID='SA1';
NODE_NAME     R521 1
 '@T6G_MB_LIB.T6G(SCH_1):PAGE54_I405@PURE_QUANTA.Q_RES(CHIPS)':
 'A': CDS_PINID='A';
NODE_NAME     R267 1
 '@T6G_MB_LIB.T6G(SCH_1):PAGE81_I73@PURE_QUANTA.Q_RES(CHIPS)':
 'A': CDS_PINID='A';
NET_NAME
'CPU1_SLP_S3_N'
 '@T6G_MB_LIB.T6G(SCH_1):CPU1_SLP_S3_N':
 C_SIGNAL='@t6g_mb_lib.t6g(sch_1):cpu1_slp_s3_n';
NODE_NAME     U26 DJ5
 '@T6G_MB_LIB.T6G(SCH_1):PAGE55_I182@PURE_QUANTA.GENOA_SP5(CHIPS)':
 'SLP_S3_L': CDS_PINID='SLP_S3_L';
NODE_NAME     R192 2
 '@T6G_MB_LIB.T6G(SCH_1):PAGE55_I298@PURE_QUANTA.Q_RES(CHIPS)':
 'B': CDS_PINID='B';
NODE_NAME     R549 1
 '@T6G_MB_LIB.T6G(SCH_1):PAGE55_I353@PURE_QUANTA.Q_RES(CHIPS)':
 'A': CDS_PINID='A';
NET_NAME
'CPU1_SLP_S5_N'
 '@T6G_MB_LIB.T6G(SCH_1):CPU1_SLP_S5_N':
 C_SIGNAL='@t6g_mb_lib.t6g(sch_1):cpu1_slp_s5_n';
NODE_NAME     U26 DG4
 '@T6G_MB_LIB.T6G(SCH_1):PAGE55_I182@PURE_QUANTA.GENOA_SP5(CHIPS)':
 'SLP_S5_L': CDS_PINID='SLP_S5_L';
NODE_NAME     R191 2
 '@T6G_MB_LIB.T6G(SCH_1):PAGE55_I297@PURE_QUANTA.Q_RES(CHIPS)':
 'B': CDS_PINID='B';
NODE_NAME     R548 1
 '@T6G_MB_LIB.T6G(SCH_1):PAGE55_I352@PURE_QUANTA.Q_RES(CHIPS)':
 'A': CDS_PINID='A';
NET_NAME
'CPU1_SMERR_N'
 '@T6G_MB_LIB.T6G(SCH_1):CPU1_SMERR_N':
 C_SIGNAL='@t6g_mb_lib.t6g(sch_1):cpu1_smerr_n';
NODE_NAME     U26 DJ11
 '@T6G_MB_LIB.T6G(SCH_1):PAGE55_I182@PURE_QUANTA.GENOA_SP5(CHIPS)':
 'SMERR_L||AGPIO24': CDS_PINID='\smerr_l||agpio24\';
NODE_NAME     R550 1
 '@T6G_MB_LIB.T6G(SCH_1):PAGE55_I363@PURE_QUANTA.Q_RES(CHIPS)':
 'A': CDS_PINID='A';
NODE_NAME     R193 2
 '@T6G_MB_LIB.T6G(SCH_1):PAGE80_I179@PURE_QUANTA.Q_RES(CHIPS)':
 'B': CDS_PINID='B';
NET_NAME
'CPU1_SP5R1'
 '@T6G_MB_LIB.T6G(SCH_1):CPU1_SP5R1':
 C_SIGNAL='@t6g_mb_lib.t6g(sch_1):cpu1_sp5r1';
NODE_NAME     U26 C19
 '@T6G_MB_LIB.T6G(SCH_1):PAGE54_I190@PURE_QUANTA.GENOA_SP5(CHIPS)':
 'SP5R1': CDS_PINID='SP5R1';
NODE_NAME     R522 2
 '@T6G_MB_LIB.T6G(SCH_1):PAGE54_I388@PURE_QUANTA.Q_RES(CHIPS)':
 'B': CDS_PINID='B';
NODE_NAME     R260 1
 '@T6G_MB_LIB.T6G(SCH_1):PAGE81_I49@PURE_QUANTA.Q_RES(CHIPS)':
 'A': CDS_PINID='A';
NET_NAME
'CPU1_SP5R2'
 '@T6G_MB_LIB.T6G(SCH_1):CPU1_SP5R2':
 C_SIGNAL='@t6g_mb_lib.t6g(sch_1):cpu1_sp5r2';
NODE_NAME     U26 C68
 '@T6G_MB_LIB.T6G(SCH_1):PAGE54_I190@PURE_QUANTA.GENOA_SP5(CHIPS)':
 'SP5R2': CDS_PINID='SP5R2';
NODE_NAME     R517 2
 '@T6G_MB_LIB.T6G(SCH_1):PAGE54_I387@PURE_QUANTA.Q_RES(CHIPS)':
 'B': CDS_PINID='B';
NODE_NAME     R261 1
 '@T6G_MB_LIB.T6G(SCH_1):PAGE81_I50@PURE_QUANTA.Q_RES(CHIPS)':
 'A': CDS_PINID='A';
NET_NAME
'CPU1_SP5R3'
 '@T6G_MB_LIB.T6G(SCH_1):CPU1_SP5R3':
 C_SIGNAL='@t6g_mb_lib.t6g(sch_1):cpu1_sp5r3';
NODE_NAME     U26 DH73
 '@T6G_MB_LIB.T6G(SCH_1):PAGE54_I190@PURE_QUANTA.GENOA_SP5(CHIPS)':
 'SP5R3': CDS_PINID='SP5R3';
NODE_NAME     R515 2
 '@T6G_MB_LIB.T6G(SCH_1):PAGE54_I391@PURE_QUANTA.Q_RES(CHIPS)':
 'B': CDS_PINID='B';
NODE_NAME     R268 1
 '@T6G_MB_LIB.T6G(SCH_1):PAGE81_I55@PURE_QUANTA.Q_RES(CHIPS)':
 'A': CDS_PINID='A';
NET_NAME
'CPU1_SP5R4'
 '@T6G_MB_LIB.T6G(SCH_1):CPU1_SP5R4':
 C_SIGNAL='@t6g_mb_lib.t6g(sch_1):cpu1_sp5r4';
NODE_NAME     U26 DH10
 '@T6G_MB_LIB.T6G(SCH_1):PAGE54_I190@PURE_QUANTA.GENOA_SP5(CHIPS)':
 'SP5R4': CDS_PINID='SP5R4';
NODE_NAME     R513 2
 '@T6G_MB_LIB.T6G(SCH_1):PAGE54_I390@PURE_QUANTA.Q_RES(CHIPS)':
 'B': CDS_PINID='B';
NODE_NAME     R269 1
 '@T6G_MB_LIB.T6G(SCH_1):PAGE81_I56@PURE_QUANTA.Q_RES(CHIPS)':
 'A': CDS_PINID='A';
NET_NAME
'CPU1_SPD_HOST_CTRL_N'
 '@T6G_MB_LIB.T6G(SCH_1):CPU1_SPD_HOST_CTRL_N':
 C_SIGNAL='@t6g_mb_lib.t6g(sch_1):cpu1_spd_host_ctrl_n';
NODE_NAME     R570 1
 '@T6G_MB_LIB.T6G(SCH_1):PAGE55_I236@PURE_QUANTA.Q_RES(CHIPS)':
 'A': CDS_PINID='A';
NODE_NAME     R194 1
 '@T6G_MB_LIB.T6G(SCH_1):PAGE80_I100@PURE_QUANTA.Q_RES(CHIPS)':
 'A': CDS_PINID='A';
NODE_NAME     R551 1
 '@T6G_MB_LIB.T6G(SCH_1):PAGE55_I360@PURE_QUANTA.Q_RES(CHIPS)':
 'A': CDS_PINID='A';
NET_NAME
'CPU1_SPD_HOST_CTRL_R1_N'
 '@T6G_MB_LIB.T6G(SCH_1):CPU1_SPD_HOST_CTRL_R1_N':
 C_SIGNAL='@t6g_mb_lib.t6g(sch_1):cpu1_spd_host_ctrl_r1_n';
NODE_NAME     R194 2
 '@T6G_MB_LIB.T6G(SCH_1):PAGE80_I100@PURE_QUANTA.Q_RES(CHIPS)':
 'B': CDS_PINID='B';
NODE_NAME     U18 L16
 '@T6G_MB_LIB.T6G(SCH_1):PAGE80_I217@PURE_QUANTA.LCMXO3LF9400C5BG484C(CHIPS)':
 'PR14B': CDS_PINID='PR14B';
NET_NAME
'CPU1_SPD_HOST_CTRL_R_N'
 '@T6G_MB_LIB.T6G(SCH_1):CPU1_SPD_HOST_CTRL_R_N':
 C_SIGNAL='@t6g_mb_lib.t6g(sch_1):cpu1_spd_host_ctrl_r_n';
NODE_NAME     U26 DE36
 '@T6G_MB_LIB.T6G(SCH_1):PAGE55_I182@PURE_QUANTA.GENOA_SP5(CHIPS)':
 'AGPIO3||SPD_HOST_CTRL_L': CDS_PINID='\agpio3||spd_host_ctrl_l\';
NODE_NAME     R570 2
 '@T6G_MB_LIB.T6G(SCH_1):PAGE55_I236@PURE_QUANTA.Q_RES(CHIPS)':
 'B': CDS_PINID='B';
NET_NAME
'CPU1_THERMTRIP_N'
 '@T6G_MB_LIB.T6G(SCH_1):CPU1_THERMTRIP_N':
 C_SIGNAL='@t6g_mb_lib.t6g(sch_1):cpu1_thermtrip_n';
NODE_NAME     U26 DJ9
 '@T6G_MB_LIB.T6G(SCH_1):PAGE54_I190@PURE_QUANTA.GENOA_SP5(CHIPS)':
 'THERMTRIP_L': CDS_PINID='THERMTRIP_L';
NODE_NAME     R488 1
 '@T6G_MB_LIB.T6G(SCH_1):PAGE54_I415@PURE_QUANTA.Q_RES(CHIPS)':
 'A': CDS_PINID='A';
NODE_NAME     R536 1
 '@T6G_MB_LIB.T6G(SCH_1):PAGE54_I421@PURE_QUANTA.Q_RES(CHIPS)':
 'A': CDS_PINID='A';
NET_NAME
'CPU1_THERMTRIP_R_N'
 '@T6G_MB_LIB.T6G(SCH_1):CPU1_THERMTRIP_R_N':
 C_SIGNAL='@t6g_mb_lib.t6g(sch_1):cpu1_thermtrip_r_n';
NODE_NAME     R488 2
 '@T6G_MB_LIB.T6G(SCH_1):PAGE54_I415@PURE_QUANTA.Q_RES(CHIPS)':
 'B': CDS_PINID='B';
NODE_NAME     U18 J5
 '@T6G_MB_LIB.T6G(SCH_1):PAGE81_I143@PURE_QUANTA.LCMXO3LF9400C5BG484C(CHIPS)':
 'PL11B': CDS_PINID='PL11B';
NODE_NAME     R1533 2
 '@T6G_MB_LIB.T6G(SCH_1):PAGE27_I429@PURE_QUANTA.Q_RES(CHIPS)':
 'B': CDS_PINID='B';
NET_NAME
'CPU1_VDDBT_RTC_G'
 '@T6G_MB_LIB.T6G(SCH_1):CPU1_VDDBT_RTC_G':
 C_SIGNAL='@t6g_mb_lib.t6g(sch_1):cpu1_vddbt_rtc_g';
NODE_NAME     U26 BN23
 '@T6G_MB_LIB.T6G(SCH_1):PAGE57_I45@PURE_QUANTA.GENOA_SP5(CHIPS)':
 'VDDBT_RTC_G': CDS_PINID='VDDBT_RTC_G';
NODE_NAME     R374 2
 '@T6G_MB_LIB.T6G(SCH_1):PAGE57_I51@PURE_QUANTA.Q_RES(CHIPS)':
 'B': CDS_PINID='B';
NODE_NAME     R373 2
 '@T6G_MB_LIB.T6G(SCH_1):PAGE57_I52@PURE_QUANTA.Q_RES(CHIPS)':
 'B': CDS_PINID='B';
NET_NAME
'CPU1_XTRIG_L4'
 '@T6G_MB_LIB.T6G(SCH_1):CPU1_XTRIG_L4':
 C_SIGNAL='@t6g_mb_lib.t6g(sch_1):cpu1_xtrig_l4';
NODE_NAME     R486 2
 '@T6G_MB_LIB.T6G(SCH_1):PAGE54_I362@PURE_QUANTA.Q_RES(CHIPS)':
 'B': CDS_PINID='B';
NODE_NAME     R929 1
 '@T6G_MB_LIB.T6G(SCH_1):PAGE54_I371@PURE_QUANTA.Q_RES(CHIPS)':
 'A': CDS_PINID='A';
NODE_NAME     R537 1
 '@T6G_MB_LIB.T6G(SCH_1):PAGE54_I410@PURE_QUANTA.Q_RES(CHIPS)':
 'A': CDS_PINID='A';
NODE_NAME     R204 1
 '@T6G_MB_LIB.T6G(SCH_1):PAGE81_I77@PURE_QUANTA.Q_RES(CHIPS)':
 'A': CDS_PINID='A';
NODE_NAME     J212 2
 '@T6G_MB_LIB.T6G(SCH_1):PAGE27_I423@PURE_QUANTA.CONN10_HBC1051L300D8H(CHIPS)':
 '2': CDS_PINID='\2\';
NET_NAME
'CPU1_XTRIG_L5'
 '@T6G_MB_LIB.T6G(SCH_1):CPU1_XTRIG_L5':
 C_SIGNAL='@t6g_mb_lib.t6g(sch_1):cpu1_xtrig_l5';
NODE_NAME     R618 2
 '@T6G_MB_LIB.T6G(SCH_1):PAGE54_I361@PURE_QUANTA.Q_RES(CHIPS)':
 'B': CDS_PINID='B';
NODE_NAME     R930 1
 '@T6G_MB_LIB.T6G(SCH_1):PAGE54_I372@PURE_QUANTA.Q_RES(CHIPS)':
 'A': CDS_PINID='A';
NODE_NAME     R538 1
 '@T6G_MB_LIB.T6G(SCH_1):PAGE54_I411@PURE_QUANTA.Q_RES(CHIPS)':
 'A': CDS_PINID='A';
NODE_NAME     R205 1
 '@T6G_MB_LIB.T6G(SCH_1):PAGE81_I74@PURE_QUANTA.Q_RES(CHIPS)':
 'A': CDS_PINID='A';
NODE_NAME     J212 4
 '@T6G_MB_LIB.T6G(SCH_1):PAGE27_I423@PURE_QUANTA.CONN10_HBC1051L300D8H(CHIPS)':
 '4': CDS_PINID='\4\';
NET_NAME
'CPU1_XTRIG_L6'
 '@T6G_MB_LIB.T6G(SCH_1):CPU1_XTRIG_L6':
 C_SIGNAL='@t6g_mb_lib.t6g(sch_1):cpu1_xtrig_l6';
NODE_NAME     R862 2
 '@T6G_MB_LIB.T6G(SCH_1):PAGE54_I364@PURE_QUANTA.Q_RES(CHIPS)':
 'B': CDS_PINID='B';
NODE_NAME     R931 1
 '@T6G_MB_LIB.T6G(SCH_1):PAGE54_I374@PURE_QUANTA.Q_RES(CHIPS)':
 'A': CDS_PINID='A';
NODE_NAME     R539 1
 '@T6G_MB_LIB.T6G(SCH_1):PAGE54_I412@PURE_QUANTA.Q_RES(CHIPS)':
 'A': CDS_PINID='A';
NODE_NAME     R234 1
 '@T6G_MB_LIB.T6G(SCH_1):PAGE81_I75@PURE_QUANTA.Q_RES(CHIPS)':
 'A': CDS_PINID='A';
NODE_NAME     J212 6
 '@T6G_MB_LIB.T6G(SCH_1):PAGE27_I423@PURE_QUANTA.CONN10_HBC1051L300D8H(CHIPS)':
 '6': CDS_PINID='\6\';
NET_NAME
'CPU1_XTRIG_L7'
 '@T6G_MB_LIB.T6G(SCH_1):CPU1_XTRIG_L7':
 C_SIGNAL='@t6g_mb_lib.t6g(sch_1):cpu1_xtrig_l7';
NODE_NAME     R928 2
 '@T6G_MB_LIB.T6G(SCH_1):PAGE54_I363@PURE_QUANTA.Q_RES(CHIPS)':
 'B': CDS_PINID='B';
NODE_NAME     R932 1
 '@T6G_MB_LIB.T6G(SCH_1):PAGE54_I373@PURE_QUANTA.Q_RES(CHIPS)':
 'A': CDS_PINID='A';
NODE_NAME     R540 1
 '@T6G_MB_LIB.T6G(SCH_1):PAGE54_I413@PURE_QUANTA.Q_RES(CHIPS)':
 'A': CDS_PINID='A';
NODE_NAME     R235 1
 '@T6G_MB_LIB.T6G(SCH_1):PAGE81_I70@PURE_QUANTA.Q_RES(CHIPS)':
 'A': CDS_PINID='A';
NODE_NAME     J212 8
 '@T6G_MB_LIB.T6G(SCH_1):PAGE27_I423@PURE_QUANTA.CONN10_HBC1051L300D8H(CHIPS)':
 '8': CDS_PINID='\8\';
NET_NAME
'CPU1_XTRIG_R1_L4'
 '@T6G_MB_LIB.T6G(SCH_1):CPU1_XTRIG_R1_L4':
 C_SIGNAL='@t6g_mb_lib.t6g(sch_1):cpu1_xtrig_r1_l4';
NODE_NAME     R929 2
 '@T6G_MB_LIB.T6G(SCH_1):PAGE54_I371@PURE_QUANTA.Q_RES(CHIPS)':
 'B': CDS_PINID='B';
NODE_NAME     J7 1
 '@T6G_MB_LIB.T6G(SCH_1):PAGE54_I418@PURE_QUANTA.SCONN8_G802M0083150RD3HR(CHIPS)':
 '1': CDS_PINID='\1\';
NET_NAME
'CPU1_XTRIG_R1_L5'
 '@T6G_MB_LIB.T6G(SCH_1):CPU1_XTRIG_R1_L5':
 C_SIGNAL='@t6g_mb_lib.t6g(sch_1):cpu1_xtrig_r1_l5';
NODE_NAME     R930 2
 '@T6G_MB_LIB.T6G(SCH_1):PAGE54_I372@PURE_QUANTA.Q_RES(CHIPS)':
 'B': CDS_PINID='B';
NODE_NAME     J7 3
 '@T6G_MB_LIB.T6G(SCH_1):PAGE54_I418@PURE_QUANTA.SCONN8_G802M0083150RD3HR(CHIPS)':
 '3': CDS_PINID='\3\';
NET_NAME
'CPU1_XTRIG_R1_L6'
 '@T6G_MB_LIB.T6G(SCH_1):CPU1_XTRIG_R1_L6':
 C_SIGNAL='@t6g_mb_lib.t6g(sch_1):cpu1_xtrig_r1_l6';
NODE_NAME     R931 2
 '@T6G_MB_LIB.T6G(SCH_1):PAGE54_I374@PURE_QUANTA.Q_RES(CHIPS)':
 'B': CDS_PINID='B';
NODE_NAME     J7 5
 '@T6G_MB_LIB.T6G(SCH_1):PAGE54_I418@PURE_QUANTA.SCONN8_G802M0083150RD3HR(CHIPS)':
 '5': CDS_PINID='\5\';
NET_NAME
'CPU1_XTRIG_R1_L7'
 '@T6G_MB_LIB.T6G(SCH_1):CPU1_XTRIG_R1_L7':
 C_SIGNAL='@t6g_mb_lib.t6g(sch_1):cpu1_xtrig_r1_l7';
NODE_NAME     R932 2
 '@T6G_MB_LIB.T6G(SCH_1):PAGE54_I373@PURE_QUANTA.Q_RES(CHIPS)':
 'B': CDS_PINID='B';
NODE_NAME     J7 7
 '@T6G_MB_LIB.T6G(SCH_1):PAGE54_I418@PURE_QUANTA.SCONN8_G802M0083150RD3HR(CHIPS)':
 '7': CDS_PINID='\7\';
NET_NAME
'CPU1_XTRIG_R2_L4'
 '@T6G_MB_LIB.T6G(SCH_1):CPU1_XTRIG_R2_L4':
 C_SIGNAL='@t6g_mb_lib.t6g(sch_1):cpu1_xtrig_r2_l4';
NODE_NAME     U26 C66
 '@T6G_MB_LIB.T6G(SCH_1):PAGE54_I190@PURE_QUANTA.GENOA_SP5(CHIPS)':
 'XTRIG_L4': CDS_PINID='XTRIG_L4';
NODE_NAME     R486 1
 '@T6G_MB_LIB.T6G(SCH_1):PAGE54_I362@PURE_QUANTA.Q_RES(CHIPS)':
 'A': CDS_PINID='A';
NET_NAME
'CPU1_XTRIG_R2_L5'
 '@T6G_MB_LIB.T6G(SCH_1):CPU1_XTRIG_R2_L5':
 C_SIGNAL='@t6g_mb_lib.t6g(sch_1):cpu1_xtrig_r2_l5';
NODE_NAME     U26 C65
 '@T6G_MB_LIB.T6G(SCH_1):PAGE54_I190@PURE_QUANTA.GENOA_SP5(CHIPS)':
 'XTRIG_L5': CDS_PINID='XTRIG_L5';
NODE_NAME     R618 1
 '@T6G_MB_LIB.T6G(SCH_1):PAGE54_I361@PURE_QUANTA.Q_RES(CHIPS)':
 'A': CDS_PINID='A';
NET_NAME
'CPU1_XTRIG_R2_L6'
 '@T6G_MB_LIB.T6G(SCH_1):CPU1_XTRIG_R2_L6':
 C_SIGNAL='@t6g_mb_lib.t6g(sch_1):cpu1_xtrig_r2_l6';
NODE_NAME     U26 A66
 '@T6G_MB_LIB.T6G(SCH_1):PAGE54_I190@PURE_QUANTA.GENOA_SP5(CHIPS)':
 'XTRIG_L6': CDS_PINID='XTRIG_L6';
NODE_NAME     R862 1
 '@T6G_MB_LIB.T6G(SCH_1):PAGE54_I364@PURE_QUANTA.Q_RES(CHIPS)':
 'A': CDS_PINID='A';
NET_NAME
'CPU1_XTRIG_R2_L7'
 '@T6G_MB_LIB.T6G(SCH_1):CPU1_XTRIG_R2_L7':
 C_SIGNAL='@t6g_mb_lib.t6g(sch_1):cpu1_xtrig_r2_l7';
NODE_NAME     U26 A65
 '@T6G_MB_LIB.T6G(SCH_1):PAGE54_I190@PURE_QUANTA.GENOA_SP5(CHIPS)':
 'XTRIG_L7': CDS_PINID='XTRIG_L7';
NODE_NAME     R928 1
 '@T6G_MB_LIB.T6G(SCH_1):PAGE54_I363@PURE_QUANTA.Q_RES(CHIPS)':
 'A': CDS_PINID='A';
NET_NAME
'CPU_FRU_ADDR0'
 '@T6G_MB_LIB.T6G(SCH_1):CPU_FRU_ADDR0':
 C_SIGNAL='@t6g_mb_lib.t6g(sch_1):cpu_fru_addr0';
NODE_NAME     U1 1
 '@T6G_MB_LIB.T6G(SCH_1):PAGE361_I97@PURE_QUANTA.M24128BWMN6TP(CHIPS)':
 'E0': CDS_PINID='E0';
NODE_NAME     R68 2
 '@T6G_MB_LIB.T6G(SCH_1):PAGE361_I120@PURE_QUANTA.Q_RES(CHIPS)':
 'B': CDS_PINID='B';
NODE_NAME     R69 1
 '@T6G_MB_LIB.T6G(SCH_1):PAGE361_I121@PURE_QUANTA.Q_RES(CHIPS)':
 'A': CDS_PINID='A';
NET_NAME
'CPU_FRU_ADDR1'
 '@T6G_MB_LIB.T6G(SCH_1):CPU_FRU_ADDR1':
 C_SIGNAL='@t6g_mb_lib.t6g(sch_1):cpu_fru_addr1';
NODE_NAME     U1 2
 '@T6G_MB_LIB.T6G(SCH_1):PAGE361_I97@PURE_QUANTA.M24128BWMN6TP(CHIPS)':
 'E1': CDS_PINID='E1';
NODE_NAME     R60 2
 '@T6G_MB_LIB.T6G(SCH_1):PAGE361_I101@PURE_QUANTA.Q_RES(CHIPS)':
 'B': CDS_PINID='B';
NODE_NAME     R62 1
 '@T6G_MB_LIB.T6G(SCH_1):PAGE361_I104@PURE_QUANTA.Q_RES(CHIPS)':
 'A': CDS_PINID='A';
NET_NAME
'CPU_FRU_ADDR2'
 '@T6G_MB_LIB.T6G(SCH_1):CPU_FRU_ADDR2':
 C_SIGNAL='@t6g_mb_lib.t6g(sch_1):cpu_fru_addr2';
NODE_NAME     R52 2
 '@T6G_MB_LIB.T6G(SCH_1):PAGE361_I103@PURE_QUANTA.Q_RES(CHIPS)':
 'B': CDS_PINID='B';
NODE_NAME     U1 3
 '@T6G_MB_LIB.T6G(SCH_1):PAGE361_I97@PURE_QUANTA.M24128BWMN6TP(CHIPS)':
 'E2': CDS_PINID='E2';
NODE_NAME     R54 1
 '@T6G_MB_LIB.T6G(SCH_1):PAGE361_I107@PURE_QUANTA.Q_RES(CHIPS)':
 'A': CDS_PINID='A';
NET_NAME
'DELTA_L_85_10INCH_BOT_DN'
 '@T6G_MB_LIB.T6G(SCH_1):DELTA_L_85_10INCH_BOT_DN':
 C_SIGNAL='@t6g_mb_lib.t6g(sch_1):delta_l_85_10inch_bot_dn';
NODE_NAME     J76 2
 '@T6G_MB_LIB.T6G(SCH_1):PAGE211_I83@PURE_QUANTA.PICOPROBE_BXA(CHIPS)':
 '2_N': CDS_PINID='\2_n\';
NODE_NAME     J82 1
 '@T6G_MB_LIB.T6G(SCH_1):PAGE211_I84@PURE_QUANTA.PICOPROBE_BXA(CHIPS)':
 '1_P': CDS_PINID='\1_p\';
NET_NAME
'DELTA_L_85_10INCH_BOT_DP'
 '@T6G_MB_LIB.T6G(SCH_1):DELTA_L_85_10INCH_BOT_DP':
 C_SIGNAL='@t6g_mb_lib.t6g(sch_1):delta_l_85_10inch_bot_dp';
NODE_NAME     J76 1
 '@T6G_MB_LIB.T6G(SCH_1):PAGE211_I83@PURE_QUANTA.PICOPROBE_BXA(CHIPS)':
 '1_P': CDS_PINID='\1_p\';
NODE_NAME     J82 2
 '@T6G_MB_LIB.T6G(SCH_1):PAGE211_I84@PURE_QUANTA.PICOPROBE_BXA(CHIPS)':
 '2_N': CDS_PINID='\2_n\';
NET_NAME
'DELTA_L_85_10INCH_IN1_DN'
 '@T6G_MB_LIB.T6G(SCH_1):DELTA_L_85_10INCH_IN1_DN':
 C_SIGNAL='@t6g_mb_lib.t6g(sch_1):delta_l_85_10inch_in1_dn';
NODE_NAME     J77 2
 '@T6G_MB_LIB.T6G(SCH_1):PAGE211_I85@PURE_QUANTA.PICOPROBE_BXA(CHIPS)':
 '2_N': CDS_PINID='\2_n\';
NODE_NAME     J83 1
 '@T6G_MB_LIB.T6G(SCH_1):PAGE211_I86@PURE_QUANTA.PICOPROBE_BXA(CHIPS)':
 '1_P': CDS_PINID='\1_p\';
NET_NAME
'DELTA_L_85_10INCH_IN1_DP'
 '@T6G_MB_LIB.T6G(SCH_1):DELTA_L_85_10INCH_IN1_DP':
 C_SIGNAL='@t6g_mb_lib.t6g(sch_1):delta_l_85_10inch_in1_dp';
NODE_NAME     J77 1
 '@T6G_MB_LIB.T6G(SCH_1):PAGE211_I85@PURE_QUANTA.PICOPROBE_BXA(CHIPS)':
 '1_P': CDS_PINID='\1_p\';
NODE_NAME     J83 2
 '@T6G_MB_LIB.T6G(SCH_1):PAGE211_I86@PURE_QUANTA.PICOPROBE_BXA(CHIPS)':
 '2_N': CDS_PINID='\2_n\';
NET_NAME
'DELTA_L_85_10INCH_IN2_DN'
 '@T6G_MB_LIB.T6G(SCH_1):DELTA_L_85_10INCH_IN2_DN':
 C_SIGNAL='@t6g_mb_lib.t6g(sch_1):delta_l_85_10inch_in2_dn';
NODE_NAME     J78 2
 '@T6G_MB_LIB.T6G(SCH_1):PAGE211_I87@PURE_QUANTA.PICOPROBE_BXA(CHIPS)':
 '2_N': CDS_PINID='\2_n\';
NODE_NAME     J84 1
 '@T6G_MB_LIB.T6G(SCH_1):PAGE211_I88@PURE_QUANTA.PICOPROBE_BXA(CHIPS)':
 '1_P': CDS_PINID='\1_p\';
NET_NAME
'DELTA_L_85_10INCH_IN2_DP'
 '@T6G_MB_LIB.T6G(SCH_1):DELTA_L_85_10INCH_IN2_DP':
 C_SIGNAL='@t6g_mb_lib.t6g(sch_1):delta_l_85_10inch_in2_dp';
NODE_NAME     J78 1
 '@T6G_MB_LIB.T6G(SCH_1):PAGE211_I87@PURE_QUANTA.PICOPROBE_BXA(CHIPS)':
 '1_P': CDS_PINID='\1_p\';
NODE_NAME     J84 2
 '@T6G_MB_LIB.T6G(SCH_1):PAGE211_I88@PURE_QUANTA.PICOPROBE_BXA(CHIPS)':
 '2_N': CDS_PINID='\2_n\';
NET_NAME
'DELTA_L_85_10INCH_IN3_DN'
 '@T6G_MB_LIB.T6G(SCH_1):DELTA_L_85_10INCH_IN3_DN':
 C_SIGNAL='@t6g_mb_lib.t6g(sch_1):delta_l_85_10inch_in3_dn';
NODE_NAME     J79 2
 '@T6G_MB_LIB.T6G(SCH_1):PAGE211_I89@PURE_QUANTA.PICOPROBE_BXA(CHIPS)':
 '2_N': CDS_PINID='\2_n\';
NODE_NAME     J85 1
 '@T6G_MB_LIB.T6G(SCH_1):PAGE211_I90@PURE_QUANTA.PICOPROBE_BXA(CHIPS)':
 '1_P': CDS_PINID='\1_p\';
NET_NAME
'DELTA_L_85_10INCH_IN3_DP'
 '@T6G_MB_LIB.T6G(SCH_1):DELTA_L_85_10INCH_IN3_DP':
 C_SIGNAL='@t6g_mb_lib.t6g(sch_1):delta_l_85_10inch_in3_dp';
NODE_NAME     J79 1
 '@T6G_MB_LIB.T6G(SCH_1):PAGE211_I89@PURE_QUANTA.PICOPROBE_BXA(CHIPS)':
 '1_P': CDS_PINID='\1_p\';
NODE_NAME     J85 2
 '@T6G_MB_LIB.T6G(SCH_1):PAGE211_I90@PURE_QUANTA.PICOPROBE_BXA(CHIPS)':
 '2_N': CDS_PINID='\2_n\';
NET_NAME
'DELTA_L_85_10INCH_IN4_DN'
 '@T6G_MB_LIB.T6G(SCH_1):DELTA_L_85_10INCH_IN4_DN':
 C_SIGNAL='@t6g_mb_lib.t6g(sch_1):delta_l_85_10inch_in4_dn';
NODE_NAME     J80 2
 '@T6G_MB_LIB.T6G(SCH_1):PAGE211_I91@PURE_QUANTA.PICOPROBE_BXA(CHIPS)':
 '2_N': CDS_PINID='\2_n\';
NODE_NAME     J86 1
 '@T6G_MB_LIB.T6G(SCH_1):PAGE211_I92@PURE_QUANTA.PICOPROBE_BXA(CHIPS)':
 '1_P': CDS_PINID='\1_p\';
NET_NAME
'DELTA_L_85_10INCH_IN4_DP'
 '@T6G_MB_LIB.T6G(SCH_1):DELTA_L_85_10INCH_IN4_DP':
 C_SIGNAL='@t6g_mb_lib.t6g(sch_1):delta_l_85_10inch_in4_dp';
NODE_NAME     J80 1
 '@T6G_MB_LIB.T6G(SCH_1):PAGE211_I91@PURE_QUANTA.PICOPROBE_BXA(CHIPS)':
 '1_P': CDS_PINID='\1_p\';
NODE_NAME     J86 2
 '@T6G_MB_LIB.T6G(SCH_1):PAGE211_I92@PURE_QUANTA.PICOPROBE_BXA(CHIPS)':
 '2_N': CDS_PINID='\2_n\';
NET_NAME
'DELTA_L_85_10INCH_IN5_DN'
 '@T6G_MB_LIB.T6G(SCH_1):DELTA_L_85_10INCH_IN5_DN':
 C_SIGNAL='@t6g_mb_lib.t6g(sch_1):delta_l_85_10inch_in5_dn';
NODE_NAME     J118 2
 '@T6G_MB_LIB.T6G(SCH_1):PAGE211_I93@PURE_QUANTA.PICOPROBE_BXA(CHIPS)':
 '2_N': CDS_PINID='\2_n\';
NODE_NAME     J120 1
 '@T6G_MB_LIB.T6G(SCH_1):PAGE211_I94@PURE_QUANTA.PICOPROBE_BXA(CHIPS)':
 '1_P': CDS_PINID='\1_p\';
NET_NAME
'DELTA_L_85_10INCH_IN5_DP'
 '@T6G_MB_LIB.T6G(SCH_1):DELTA_L_85_10INCH_IN5_DP':
 C_SIGNAL='@t6g_mb_lib.t6g(sch_1):delta_l_85_10inch_in5_dp';
NODE_NAME     J118 1
 '@T6G_MB_LIB.T6G(SCH_1):PAGE211_I93@PURE_QUANTA.PICOPROBE_BXA(CHIPS)':
 '1_P': CDS_PINID='\1_p\';
NODE_NAME     J120 2
 '@T6G_MB_LIB.T6G(SCH_1):PAGE211_I94@PURE_QUANTA.PICOPROBE_BXA(CHIPS)':
 '2_N': CDS_PINID='\2_n\';
NET_NAME
'DELTA_L_85_10INCH_IN6_DN'
 '@T6G_MB_LIB.T6G(SCH_1):DELTA_L_85_10INCH_IN6_DN':
 C_SIGNAL='@t6g_mb_lib.t6g(sch_1):delta_l_85_10inch_in6_dn';
NODE_NAME     J119 2
 '@T6G_MB_LIB.T6G(SCH_1):PAGE211_I95@PURE_QUANTA.PICOPROBE_BXA(CHIPS)':
 '2_N': CDS_PINID='\2_n\';
NODE_NAME     J121 1
 '@T6G_MB_LIB.T6G(SCH_1):PAGE211_I96@PURE_QUANTA.PICOPROBE_BXA(CHIPS)':
 '1_P': CDS_PINID='\1_p\';
NET_NAME
'DELTA_L_85_10INCH_IN6_DP'
 '@T6G_MB_LIB.T6G(SCH_1):DELTA_L_85_10INCH_IN6_DP':
 C_SIGNAL='@t6g_mb_lib.t6g(sch_1):delta_l_85_10inch_in6_dp';
NODE_NAME     J119 1
 '@T6G_MB_LIB.T6G(SCH_1):PAGE211_I95@PURE_QUANTA.PICOPROBE_BXA(CHIPS)':
 '1_P': CDS_PINID='\1_p\';
NODE_NAME     J121 2
 '@T6G_MB_LIB.T6G(SCH_1):PAGE211_I96@PURE_QUANTA.PICOPROBE_BXA(CHIPS)':
 '2_N': CDS_PINID='\2_n\';
NET_NAME
'DELTA_L_85_10INCH_TOP_DN'
 '@T6G_MB_LIB.T6G(SCH_1):DELTA_L_85_10INCH_TOP_DN':
 C_SIGNAL='@t6g_mb_lib.t6g(sch_1):delta_l_85_10inch_top_dn';
NODE_NAME     J75 2
 '@T6G_MB_LIB.T6G(SCH_1):PAGE211_I81@PURE_QUANTA.PICOPROBE_BXA(CHIPS)':
 '2_N': CDS_PINID='\2_n\';
NODE_NAME     J81 1
 '@T6G_MB_LIB.T6G(SCH_1):PAGE211_I82@PURE_QUANTA.PICOPROBE_BXA(CHIPS)':
 '1_P': CDS_PINID='\1_p\';
NET_NAME
'DELTA_L_85_10INCH_TOP_DP'
 '@T6G_MB_LIB.T6G(SCH_1):DELTA_L_85_10INCH_TOP_DP':
 C_SIGNAL='@t6g_mb_lib.t6g(sch_1):delta_l_85_10inch_top_dp';
NODE_NAME     J75 1
 '@T6G_MB_LIB.T6G(SCH_1):PAGE211_I81@PURE_QUANTA.PICOPROBE_BXA(CHIPS)':
 '1_P': CDS_PINID='\1_p\';
NODE_NAME     J81 2
 '@T6G_MB_LIB.T6G(SCH_1):PAGE211_I82@PURE_QUANTA.PICOPROBE_BXA(CHIPS)':
 '2_N': CDS_PINID='\2_n\';
NET_NAME
'DELTA_L_85_5INCH_BOT_DN'
 '@T6G_MB_LIB.T6G(SCH_1):DELTA_L_85_5INCH_BOT_DN':
 C_SIGNAL='@t6g_mb_lib.t6g(sch_1):delta_l_85_5inch_bot_dn';
NODE_NAME     J64 2
 '@T6G_MB_LIB.T6G(SCH_1):PAGE211_I67@PURE_QUANTA.PICOPROBE_BXA(CHIPS)':
 '2_N': CDS_PINID='\2_n\';
NODE_NAME     J70 1
 '@T6G_MB_LIB.T6G(SCH_1):PAGE211_I68@PURE_QUANTA.PICOPROBE_BXA(CHIPS)':
 '1_P': CDS_PINID='\1_p\';
NET_NAME
'DELTA_L_85_5INCH_BOT_DP'
 '@T6G_MB_LIB.T6G(SCH_1):DELTA_L_85_5INCH_BOT_DP':
 C_SIGNAL='@t6g_mb_lib.t6g(sch_1):delta_l_85_5inch_bot_dp';
NODE_NAME     J64 1
 '@T6G_MB_LIB.T6G(SCH_1):PAGE211_I67@PURE_QUANTA.PICOPROBE_BXA(CHIPS)':
 '1_P': CDS_PINID='\1_p\';
NODE_NAME     J70 2
 '@T6G_MB_LIB.T6G(SCH_1):PAGE211_I68@PURE_QUANTA.PICOPROBE_BXA(CHIPS)':
 '2_N': CDS_PINID='\2_n\';
NET_NAME
'DELTA_L_85_5INCH_IN1_DN'
 '@T6G_MB_LIB.T6G(SCH_1):DELTA_L_85_5INCH_IN1_DN':
 C_SIGNAL='@t6g_mb_lib.t6g(sch_1):delta_l_85_5inch_in1_dn';
NODE_NAME     J65 2
 '@T6G_MB_LIB.T6G(SCH_1):PAGE211_I69@PURE_QUANTA.PICOPROBE_BXA(CHIPS)':
 '2_N': CDS_PINID='\2_n\';
NODE_NAME     J71 1
 '@T6G_MB_LIB.T6G(SCH_1):PAGE211_I70@PURE_QUANTA.PICOPROBE_BXA(CHIPS)':
 '1_P': CDS_PINID='\1_p\';
NET_NAME
'DELTA_L_85_5INCH_IN1_DP'
 '@T6G_MB_LIB.T6G(SCH_1):DELTA_L_85_5INCH_IN1_DP':
 C_SIGNAL='@t6g_mb_lib.t6g(sch_1):delta_l_85_5inch_in1_dp';
NODE_NAME     J65 1
 '@T6G_MB_LIB.T6G(SCH_1):PAGE211_I69@PURE_QUANTA.PICOPROBE_BXA(CHIPS)':
 '1_P': CDS_PINID='\1_p\';
NODE_NAME     J71 2
 '@T6G_MB_LIB.T6G(SCH_1):PAGE211_I70@PURE_QUANTA.PICOPROBE_BXA(CHIPS)':
 '2_N': CDS_PINID='\2_n\';
NET_NAME
'DELTA_L_85_5INCH_IN2_DN'
 '@T6G_MB_LIB.T6G(SCH_1):DELTA_L_85_5INCH_IN2_DN':
 C_SIGNAL='@t6g_mb_lib.t6g(sch_1):delta_l_85_5inch_in2_dn';
NODE_NAME     J66 2
 '@T6G_MB_LIB.T6G(SCH_1):PAGE211_I71@PURE_QUANTA.PICOPROBE_BXA(CHIPS)':
 '2_N': CDS_PINID='\2_n\';
NODE_NAME     J72 1
 '@T6G_MB_LIB.T6G(SCH_1):PAGE211_I72@PURE_QUANTA.PICOPROBE_BXA(CHIPS)':
 '1_P': CDS_PINID='\1_p\';
NET_NAME
'DELTA_L_85_5INCH_IN2_DP'
 '@T6G_MB_LIB.T6G(SCH_1):DELTA_L_85_5INCH_IN2_DP':
 C_SIGNAL='@t6g_mb_lib.t6g(sch_1):delta_l_85_5inch_in2_dp';
NODE_NAME     J66 1
 '@T6G_MB_LIB.T6G(SCH_1):PAGE211_I71@PURE_QUANTA.PICOPROBE_BXA(CHIPS)':
 '1_P': CDS_PINID='\1_p\';
NODE_NAME     J72 2
 '@T6G_MB_LIB.T6G(SCH_1):PAGE211_I72@PURE_QUANTA.PICOPROBE_BXA(CHIPS)':
 '2_N': CDS_PINID='\2_n\';
NET_NAME
'DELTA_L_85_5INCH_IN3_DN'
 '@T6G_MB_LIB.T6G(SCH_1):DELTA_L_85_5INCH_IN3_DN':
 C_SIGNAL='@t6g_mb_lib.t6g(sch_1):delta_l_85_5inch_in3_dn';
NODE_NAME     J8067 2
 '@T6G_MB_LIB.T6G(SCH_1):PAGE211_I73@PURE_QUANTA.PICOPROBE_BXA(CHIPS)':
 '2_N': CDS_PINID='\2_n\';
NODE_NAME     J73 1
 '@T6G_MB_LIB.T6G(SCH_1):PAGE211_I74@PURE_QUANTA.PICOPROBE_BXA(CHIPS)':
 '1_P': CDS_PINID='\1_p\';
NET_NAME
'DELTA_L_85_5INCH_IN3_DP'
 '@T6G_MB_LIB.T6G(SCH_1):DELTA_L_85_5INCH_IN3_DP':
 C_SIGNAL='@t6g_mb_lib.t6g(sch_1):delta_l_85_5inch_in3_dp';
NODE_NAME     J8067 1
 '@T6G_MB_LIB.T6G(SCH_1):PAGE211_I73@PURE_QUANTA.PICOPROBE_BXA(CHIPS)':
 '1_P': CDS_PINID='\1_p\';
NODE_NAME     J73 2
 '@T6G_MB_LIB.T6G(SCH_1):PAGE211_I74@PURE_QUANTA.PICOPROBE_BXA(CHIPS)':
 '2_N': CDS_PINID='\2_n\';
NET_NAME
'DELTA_L_85_5INCH_IN4_DN'
 '@T6G_MB_LIB.T6G(SCH_1):DELTA_L_85_5INCH_IN4_DN':
 C_SIGNAL='@t6g_mb_lib.t6g(sch_1):delta_l_85_5inch_in4_dn';
NODE_NAME     J8068 2
 '@T6G_MB_LIB.T6G(SCH_1):PAGE211_I75@PURE_QUANTA.PICOPROBE_BXA(CHIPS)':
 '2_N': CDS_PINID='\2_n\';
NODE_NAME     J74 1
 '@T6G_MB_LIB.T6G(SCH_1):PAGE211_I76@PURE_QUANTA.PICOPROBE_BXA(CHIPS)':
 '1_P': CDS_PINID='\1_p\';
NET_NAME
'DELTA_L_85_5INCH_IN4_DP'
 '@T6G_MB_LIB.T6G(SCH_1):DELTA_L_85_5INCH_IN4_DP':
 C_SIGNAL='@t6g_mb_lib.t6g(sch_1):delta_l_85_5inch_in4_dp';
NODE_NAME     J8068 1
 '@T6G_MB_LIB.T6G(SCH_1):PAGE211_I75@PURE_QUANTA.PICOPROBE_BXA(CHIPS)':
 '1_P': CDS_PINID='\1_p\';
NODE_NAME     J74 2
 '@T6G_MB_LIB.T6G(SCH_1):PAGE211_I76@PURE_QUANTA.PICOPROBE_BXA(CHIPS)':
 '2_N': CDS_PINID='\2_n\';
NET_NAME
'DELTA_L_85_5INCH_IN5_DN'
 '@T6G_MB_LIB.T6G(SCH_1):DELTA_L_85_5INCH_IN5_DN':
 C_SIGNAL='@t6g_mb_lib.t6g(sch_1):delta_l_85_5inch_in5_dn';
NODE_NAME     J114 2
 '@T6G_MB_LIB.T6G(SCH_1):PAGE211_I77@PURE_QUANTA.PICOPROBE_BXA(CHIPS)':
 '2_N': CDS_PINID='\2_n\';
NODE_NAME     J116 1
 '@T6G_MB_LIB.T6G(SCH_1):PAGE211_I78@PURE_QUANTA.PICOPROBE_BXA(CHIPS)':
 '1_P': CDS_PINID='\1_p\';
NET_NAME
'DELTA_L_85_5INCH_IN5_DP'
 '@T6G_MB_LIB.T6G(SCH_1):DELTA_L_85_5INCH_IN5_DP':
 C_SIGNAL='@t6g_mb_lib.t6g(sch_1):delta_l_85_5inch_in5_dp';
NODE_NAME     J114 1
 '@T6G_MB_LIB.T6G(SCH_1):PAGE211_I77@PURE_QUANTA.PICOPROBE_BXA(CHIPS)':
 '1_P': CDS_PINID='\1_p\';
NODE_NAME     J116 2
 '@T6G_MB_LIB.T6G(SCH_1):PAGE211_I78@PURE_QUANTA.PICOPROBE_BXA(CHIPS)':
 '2_N': CDS_PINID='\2_n\';
NET_NAME
'DELTA_L_85_5INCH_IN6_DN'
 '@T6G_MB_LIB.T6G(SCH_1):DELTA_L_85_5INCH_IN6_DN':
 C_SIGNAL='@t6g_mb_lib.t6g(sch_1):delta_l_85_5inch_in6_dn';
NODE_NAME     J115 2
 '@T6G_MB_LIB.T6G(SCH_1):PAGE211_I79@PURE_QUANTA.PICOPROBE_BXA(CHIPS)':
 '2_N': CDS_PINID='\2_n\';
NODE_NAME     J117 1
 '@T6G_MB_LIB.T6G(SCH_1):PAGE211_I80@PURE_QUANTA.PICOPROBE_BXA(CHIPS)':
 '1_P': CDS_PINID='\1_p\';
NET_NAME
'DELTA_L_85_5INCH_IN6_DP'
 '@T6G_MB_LIB.T6G(SCH_1):DELTA_L_85_5INCH_IN6_DP':
 C_SIGNAL='@t6g_mb_lib.t6g(sch_1):delta_l_85_5inch_in6_dp';
NODE_NAME     J115 1
 '@T6G_MB_LIB.T6G(SCH_1):PAGE211_I79@PURE_QUANTA.PICOPROBE_BXA(CHIPS)':
 '1_P': CDS_PINID='\1_p\';
NODE_NAME     J117 2
 '@T6G_MB_LIB.T6G(SCH_1):PAGE211_I80@PURE_QUANTA.PICOPROBE_BXA(CHIPS)':
 '2_N': CDS_PINID='\2_n\';
NET_NAME
'DELTA_L_85_5INCH_TOP_DN'
 '@T6G_MB_LIB.T6G(SCH_1):DELTA_L_85_5INCH_TOP_DN':
 C_SIGNAL='@t6g_mb_lib.t6g(sch_1):delta_l_85_5inch_top_dn';
NODE_NAME     J63 2
 '@T6G_MB_LIB.T6G(SCH_1):PAGE211_I65@PURE_QUANTA.PICOPROBE_BXA(CHIPS)':
 '2_N': CDS_PINID='\2_n\';
NODE_NAME     J8069 1
 '@T6G_MB_LIB.T6G(SCH_1):PAGE211_I66@PURE_QUANTA.PICOPROBE_BXA(CHIPS)':
 '1_P': CDS_PINID='\1_p\';
NET_NAME
'DELTA_L_85_5INCH_TOP_DP'
 '@T6G_MB_LIB.T6G(SCH_1):DELTA_L_85_5INCH_TOP_DP':
 C_SIGNAL='@t6g_mb_lib.t6g(sch_1):delta_l_85_5inch_top_dp';
NODE_NAME     J63 1
 '@T6G_MB_LIB.T6G(SCH_1):PAGE211_I65@PURE_QUANTA.PICOPROBE_BXA(CHIPS)':
 '1_P': CDS_PINID='\1_p\';
NODE_NAME     J8069 2
 '@T6G_MB_LIB.T6G(SCH_1):PAGE211_I66@PURE_QUANTA.PICOPROBE_BXA(CHIPS)':
 '2_N': CDS_PINID='\2_n\';
NET_NAME
'DELTA_L_GND_1'
 '@T6G_MB_LIB.T6G(SCH_1):DELTA_L_GND_1':
 C_SIGNAL='@t6g_mb_lib.t6g(sch_1):delta_l_gnd_1',
 CDS_GLOBAL_NET='TRUE';
NODE_NAME     J63 3
 '@T6G_MB_LIB.T6G(SCH_1):PAGE211_I65@PURE_QUANTA.PICOPROBE_BXA(CHIPS)':
 '3_G': CDS_PINID='\3_g\';
NODE_NAME     J8069 3
 '@T6G_MB_LIB.T6G(SCH_1):PAGE211_I66@PURE_QUANTA.PICOPROBE_BXA(CHIPS)':
 '3_G': CDS_PINID='\3_g\';
NODE_NAME     J64 3
 '@T6G_MB_LIB.T6G(SCH_1):PAGE211_I67@PURE_QUANTA.PICOPROBE_BXA(CHIPS)':
 '3_G': CDS_PINID='\3_g\';
NODE_NAME     J70 3
 '@T6G_MB_LIB.T6G(SCH_1):PAGE211_I68@PURE_QUANTA.PICOPROBE_BXA(CHIPS)':
 '3_G': CDS_PINID='\3_g\';
NODE_NAME     J65 3
 '@T6G_MB_LIB.T6G(SCH_1):PAGE211_I69@PURE_QUANTA.PICOPROBE_BXA(CHIPS)':
 '3_G': CDS_PINID='\3_g\';
NODE_NAME     J71 3
 '@T6G_MB_LIB.T6G(SCH_1):PAGE211_I70@PURE_QUANTA.PICOPROBE_BXA(CHIPS)':
 '3_G': CDS_PINID='\3_g\';
NODE_NAME     J66 3
 '@T6G_MB_LIB.T6G(SCH_1):PAGE211_I71@PURE_QUANTA.PICOPROBE_BXA(CHIPS)':
 '3_G': CDS_PINID='\3_g\';
NODE_NAME     J72 3
 '@T6G_MB_LIB.T6G(SCH_1):PAGE211_I72@PURE_QUANTA.PICOPROBE_BXA(CHIPS)':
 '3_G': CDS_PINID='\3_g\';
NODE_NAME     J8067 3
 '@T6G_MB_LIB.T6G(SCH_1):PAGE211_I73@PURE_QUANTA.PICOPROBE_BXA(CHIPS)':
 '3_G': CDS_PINID='\3_g\';
NODE_NAME     J73 3
 '@T6G_MB_LIB.T6G(SCH_1):PAGE211_I74@PURE_QUANTA.PICOPROBE_BXA(CHIPS)':
 '3_G': CDS_PINID='\3_g\';
NODE_NAME     J8068 3
 '@T6G_MB_LIB.T6G(SCH_1):PAGE211_I75@PURE_QUANTA.PICOPROBE_BXA(CHIPS)':
 '3_G': CDS_PINID='\3_g\';
NODE_NAME     J74 3
 '@T6G_MB_LIB.T6G(SCH_1):PAGE211_I76@PURE_QUANTA.PICOPROBE_BXA(CHIPS)':
 '3_G': CDS_PINID='\3_g\';
NODE_NAME     J114 3
 '@T6G_MB_LIB.T6G(SCH_1):PAGE211_I77@PURE_QUANTA.PICOPROBE_BXA(CHIPS)':
 '3_G': CDS_PINID='\3_g\';
NODE_NAME     J116 3
 '@T6G_MB_LIB.T6G(SCH_1):PAGE211_I78@PURE_QUANTA.PICOPROBE_BXA(CHIPS)':
 '3_G': CDS_PINID='\3_g\';
NODE_NAME     J115 3
 '@T6G_MB_LIB.T6G(SCH_1):PAGE211_I79@PURE_QUANTA.PICOPROBE_BXA(CHIPS)':
 '3_G': CDS_PINID='\3_g\';
NODE_NAME     J117 3
 '@T6G_MB_LIB.T6G(SCH_1):PAGE211_I80@PURE_QUANTA.PICOPROBE_BXA(CHIPS)':
 '3_G': CDS_PINID='\3_g\';
NODE_NAME     J75 3
 '@T6G_MB_LIB.T6G(SCH_1):PAGE211_I81@PURE_QUANTA.PICOPROBE_BXA(CHIPS)':
 '3_G': CDS_PINID='\3_g\';
NODE_NAME     J81 3
 '@T6G_MB_LIB.T6G(SCH_1):PAGE211_I82@PURE_QUANTA.PICOPROBE_BXA(CHIPS)':
 '3_G': CDS_PINID='\3_g\';
NODE_NAME     J76 3
 '@T6G_MB_LIB.T6G(SCH_1):PAGE211_I83@PURE_QUANTA.PICOPROBE_BXA(CHIPS)':
 '3_G': CDS_PINID='\3_g\';
NODE_NAME     J82 3
 '@T6G_MB_LIB.T6G(SCH_1):PAGE211_I84@PURE_QUANTA.PICOPROBE_BXA(CHIPS)':
 '3_G': CDS_PINID='\3_g\';
NODE_NAME     J77 3
 '@T6G_MB_LIB.T6G(SCH_1):PAGE211_I85@PURE_QUANTA.PICOPROBE_BXA(CHIPS)':
 '3_G': CDS_PINID='\3_g\';
NODE_NAME     J83 3
 '@T6G_MB_LIB.T6G(SCH_1):PAGE211_I86@PURE_QUANTA.PICOPROBE_BXA(CHIPS)':
 '3_G': CDS_PINID='\3_g\';
NODE_NAME     J78 3
 '@T6G_MB_LIB.T6G(SCH_1):PAGE211_I87@PURE_QUANTA.PICOPROBE_BXA(CHIPS)':
 '3_G': CDS_PINID='\3_g\';
NODE_NAME     J84 3
 '@T6G_MB_LIB.T6G(SCH_1):PAGE211_I88@PURE_QUANTA.PICOPROBE_BXA(CHIPS)':
 '3_G': CDS_PINID='\3_g\';
NODE_NAME     J79 3
 '@T6G_MB_LIB.T6G(SCH_1):PAGE211_I89@PURE_QUANTA.PICOPROBE_BXA(CHIPS)':
 '3_G': CDS_PINID='\3_g\';
NODE_NAME     J85 3
 '@T6G_MB_LIB.T6G(SCH_1):PAGE211_I90@PURE_QUANTA.PICOPROBE_BXA(CHIPS)':
 '3_G': CDS_PINID='\3_g\';
NODE_NAME     J80 3
 '@T6G_MB_LIB.T6G(SCH_1):PAGE211_I91@PURE_QUANTA.PICOPROBE_BXA(CHIPS)':
 '3_G': CDS_PINID='\3_g\';
NODE_NAME     J86 3
 '@T6G_MB_LIB.T6G(SCH_1):PAGE211_I92@PURE_QUANTA.PICOPROBE_BXA(CHIPS)':
 '3_G': CDS_PINID='\3_g\';
NODE_NAME     J118 3
 '@T6G_MB_LIB.T6G(SCH_1):PAGE211_I93@PURE_QUANTA.PICOPROBE_BXA(CHIPS)':
 '3_G': CDS_PINID='\3_g\';
NODE_NAME     J120 3
 '@T6G_MB_LIB.T6G(SCH_1):PAGE211_I94@PURE_QUANTA.PICOPROBE_BXA(CHIPS)':
 '3_G': CDS_PINID='\3_g\';
NODE_NAME     J119 3
 '@T6G_MB_LIB.T6G(SCH_1):PAGE211_I95@PURE_QUANTA.PICOPROBE_BXA(CHIPS)':
 '3_G': CDS_PINID='\3_g\';
NODE_NAME     J121 3
 '@T6G_MB_LIB.T6G(SCH_1):PAGE211_I96@PURE_QUANTA.PICOPROBE_BXA(CHIPS)':
 '3_G': CDS_PINID='\3_g\';
NET_NAME
'E1S_0_P12V_EN'
 '@T6G_MB_LIB.T6G(SCH_1):E1S_0_P12V_EN':
 C_SIGNAL='@t6g_mb_lib.t6g(sch_1):e1s_0_p12v_en';
NODE_NAME     R3943 1
 '@T6G_MB_LIB.T6G(SCH_1):PAGE323_I19@PURE_QUANTA.Q_RES(CHIPS)':
 'A': CDS_PINID='A';
NODE_NAME     R199 1
 '@T6G_MB_LIB.T6G(SCH_1):PAGE80_I22@PURE_QUANTA.Q_RES(CHIPS)':
 'A': CDS_PINID='A';
NODE_NAME     R1314 1
 '@T6G_MB_LIB.T6G(SCH_1):PAGE82_I54@PURE_QUANTA.Q_RES(CHIPS)':
 'A': CDS_PINID='A';
NODE_NAME     R4064 1
 '@T6G_MB_LIB.T6G(SCH_1):PAGE324_I24@PURE_QUANTA.Q_RES(CHIPS)':
 'A': CDS_PINID='A';
NET_NAME
'E1S_0_P3V3_ADC_ALERT_R'
 '@T6G_MB_LIB.T6G(SCH_1):E1S_0_P3V3_ADC_ALERT_R':
 C_SIGNAL='@t6g_mb_lib.t6g(sch_1):e1s_0_p3v3_adc_alert_r';
NODE_NAME     R3752 1
 '@T6G_MB_LIB.T6G(SCH_1):PAGE295_I122@PURE_QUANTA.Q_RES(CHIPS)':
 'A': CDS_PINID='A';
NODE_NAME     U276 3
 '@T6G_MB_LIB.T6G(SCH_1):PAGE295_I129@PURE_QUANTA.ISL28022FRZT(CHIPS)':
 'EXT_CLK||INT': CDS_PINID='\ext_clk||int\';
NODE_NAME     R4093 2
 '@T6G_MB_LIB.T6G(SCH_1):PAGE295_I149@PURE_QUANTA.Q_RES(CHIPS)':
 'B': CDS_PINID='B';
NET_NAME
'E1S_0_P3V3_EN'
 '@T6G_MB_LIB.T6G(SCH_1):E1S_0_P3V3_EN':
 C_SIGNAL='@t6g_mb_lib.t6g(sch_1):e1s_0_p3v3_en';
NODE_NAME     R3946 1
 '@T6G_MB_LIB.T6G(SCH_1):PAGE323_I5@PURE_QUANTA.Q_RES(CHIPS)':
 'A': CDS_PINID='A';
NODE_NAME     R4063 1
 '@T6G_MB_LIB.T6G(SCH_1):PAGE324_I2@PURE_QUANTA.Q_RES(CHIPS)':
 'A': CDS_PINID='A';
NODE_NAME     R648 1
 '@T6G_MB_LIB.T6G(SCH_1):PAGE80_I25@PURE_QUANTA.Q_RES(CHIPS)':
 'A': CDS_PINID='A';
NODE_NAME     R757 1
 '@T6G_MB_LIB.T6G(SCH_1):PAGE82_I41@PURE_QUANTA.Q_RES(CHIPS)':
 'A': CDS_PINID='A';
NET_NAME
'E1S_0_P3V3_P12V_ADC_ALERT'
 '@T6G_MB_LIB.T6G(SCH_1):E1S_0_P3V3_P12V_ADC_ALERT':
 C_SIGNAL='@t6g_mb_lib.t6g(sch_1):e1s_0_p3v3_p12v_adc_alert';
NODE_NAME     U18 K3
 '@T6G_MB_LIB.T6G(SCH_1):PAGE81_I143@PURE_QUANTA.LCMXO3LF9400C5BG484C(CHIPS)':
 'PL13D': CDS_PINID='PL13D';
NODE_NAME     R1329 2
 '@T6G_MB_LIB.T6G(SCH_1):PAGE81_I178@PURE_QUANTA.Q_RES(CHIPS)':
 'B': CDS_PINID='B';
NET_NAME
'E1S_0_P3V3_P12V_ADC_R_ALERT'
 '@T6G_MB_LIB.T6G(SCH_1):E1S_0_P3V3_P12V_ADC_R_ALERT':
 C_SIGNAL='@t6g_mb_lib.t6g(sch_1):e1s_0_p3v3_p12v_adc_r_alert';
NODE_NAME     R3752 2
 '@T6G_MB_LIB.T6G(SCH_1):PAGE295_I122@PURE_QUANTA.Q_RES(CHIPS)':
 'B': CDS_PINID='B';
NODE_NAME     R1269 2
 '@T6G_MB_LIB.T6G(SCH_1):PAGE466_I62@PURE_QUANTA.Q_RES(CHIPS)':
 'B': CDS_PINID='B';
NODE_NAME     R1329 1
 '@T6G_MB_LIB.T6G(SCH_1):PAGE81_I178@PURE_QUANTA.Q_RES(CHIPS)':
 'A': CDS_PINID='A';
NODE_NAME     R1326 2
 '@T6G_MB_LIB.T6G(SCH_1):PAGE466_I90@PURE_QUANTA.Q_RES(CHIPS)':
 'B': CDS_PINID='B';
NET_NAME
'E1S_0_PERST1_CLKREQ_N'
 '@T6G_MB_LIB.T6G(SCH_1):E1S_0_PERST1_CLKREQ_N':
 C_SIGNAL='@t6g_mb_lib.t6g(sch_1):e1s_0_perst1_clkreq_n';
NODE_NAME     R2426 1
 '@T6G_MB_LIB.T6G(SCH_1):PAGE297_I75@PURE_QUANTA.Q_RES(CHIPS)':
 'A': CDS_PINID='A';
NODE_NAME     R10287 2
 '@T6G_MB_LIB.T6G(SCH_1):PAGE297_I79@PURE_QUANTA.Q_RES(CHIPS)':
 'B': CDS_PINID='B';
NODE_NAME     J90 A11
 '@T6G_MB_LIB.T6G(SCH_1):PAGE297_I90@PURE_QUANTA.SCONN56_123276793(CHIPS)':
 'PERST1#_CLKREQ#': CDS_PINID='\perst1#_clkreq#\';
NODE_NAME     R6094 2
 '@T6G_MB_LIB.T6G(SCH_1):PAGE79_I128@PURE_QUANTA.Q_RES(CHIPS)':
 'B': CDS_PINID='B';
NET_NAME
'E1S_0_PERST1_CLKREQ_R_N'
 '@T6G_MB_LIB.T6G(SCH_1):E1S_0_PERST1_CLKREQ_R_N':
 C_SIGNAL='@t6g_mb_lib.t6g(sch_1):e1s_0_perst1_clkreq_r_n';
NODE_NAME     U18 A6
 '@T6G_MB_LIB.T6G(SCH_1):PAGE79_I94@PURE_QUANTA.LCMXO3LF9400C5BG484C(CHIPS)':
 'PT13B': CDS_PINID='PT13B';
NODE_NAME     R6094 1
 '@T6G_MB_LIB.T6G(SCH_1):PAGE79_I128@PURE_QUANTA.Q_RES(CHIPS)':
 'A': CDS_PINID='A';
NODE_NAME     R6116 1
 '@T6G_MB_LIB.T6G(SCH_1):PAGE79_I129@PURE_QUANTA.Q_RES(CHIPS)':
 'A': CDS_PINID='A';
NET_NAME
'E1S_0_PRSNT_N'
 '@T6G_MB_LIB.T6G(SCH_1):E1S_0_PRSNT_N':
 C_SIGNAL='@t6g_mb_lib.t6g(sch_1):e1s_0_prsnt_n';
NODE_NAME     J90 A12
 '@T6G_MB_LIB.T6G(SCH_1):PAGE297_I90@PURE_QUANTA.SCONN56_123276793(CHIPS)':
 'PRSNT0#': CDS_PINID='\prsnt0#\';
NODE_NAME     R6052 2
 '@T6G_MB_LIB.T6G(SCH_1):PAGE81_I99@PURE_QUANTA.Q_RES(CHIPS)':
 'B': CDS_PINID='B';
NODE_NAME     R6116 2
 '@T6G_MB_LIB.T6G(SCH_1):PAGE79_I129@PURE_QUANTA.Q_RES(CHIPS)':
 'B': CDS_PINID='B';
NODE_NAME     R1304 1
 '@T6G_MB_LIB.T6G(SCH_1):PAGE82_I171@PURE_QUANTA.Q_RES(CHIPS)':
 'A': CDS_PINID='A';
NET_NAME
'E1S_0_PRSNT_R_N'
 '@T6G_MB_LIB.T6G(SCH_1):E1S_0_PRSNT_R_N':
 C_SIGNAL='@t6g_mb_lib.t6g(sch_1):e1s_0_prsnt_r_n';
NODE_NAME     R6052 1
 '@T6G_MB_LIB.T6G(SCH_1):PAGE81_I99@PURE_QUANTA.Q_RES(CHIPS)':
 'A': CDS_PINID='A';
NODE_NAME     U18 U3
 '@T6G_MB_LIB.T6G(SCH_1):PAGE81_I143@PURE_QUANTA.LCMXO3LF9400C5BG484C(CHIPS)':
 'PL27C': CDS_PINID='PL27C';
NET_NAME
'E1S_0_PWRDIS'
 '@T6G_MB_LIB.T6G(SCH_1):E1S_0_PWRDIS':
 C_SIGNAL='@t6g_mb_lib.t6g(sch_1):e1s_0_pwrdis';
NODE_NAME     R10296 1
 '@T6G_MB_LIB.T6G(SCH_1):PAGE297_I6@PURE_QUANTA.Q_RES(CHIPS)':
 'A': CDS_PINID='A';
NODE_NAME     R3771 2
 '@T6G_MB_LIB.T6G(SCH_1):PAGE297_I7@PURE_QUANTA.Q_RES(CHIPS)':
 'B': CDS_PINID='B';
NODE_NAME     J90 B12
 '@T6G_MB_LIB.T6G(SCH_1):PAGE297_I90@PURE_QUANTA.SCONN56_123276793(CHIPS)':
 'PWRDIS': CDS_PINID='PWRDIS';
NET_NAME
'ESPI_CPU0_ALERT_N'
 '@T6G_MB_LIB.T6G(SCH_1):ESPI_CPU0_ALERT_N':
 C_SIGNAL='@t6g_mb_lib.t6g(sch_1):espi_cpu0_alert_n';
NODE_NAME     J41 B3
 '@T6G_MB_LIB.T6G(SCH_1):PAGE348_I176@PURE_QUANTA.SCONN168_ME1016810202011(CHIPS)':
 '+12V_EDGE_B3': CDS_PINID='\+12v_edge_b3\';
NODE_NAME     R8035 2
 '@T6G_MB_LIB.T6G(SCH_1):PAGE130_I11@PURE_QUANTA.Q_RES(CHIPS)':
 'B': CDS_PINID='B';
NODE_NAME     R8034 2
 '@T6G_MB_LIB.T6G(SCH_1):PAGE130_I23@PURE_QUANTA.Q_RES(CHIPS)':
 'B': CDS_PINID='B';
NODE_NAME     R1197 2
 '@T6G_MB_LIB.T6G(SCH_1):PAGE130_I24@PURE_QUANTA.Q_RES(CHIPS)':
 'B': CDS_PINID='B';
NET_NAME
'ESPI_CPU0_ALERT_P0_N'
 '@T6G_MB_LIB.T6G(SCH_1):ESPI_CPU0_ALERT_P0_N':
 C_SIGNAL='@t6g_mb_lib.t6g(sch_1):espi_cpu0_alert_p0_n';
NODE_NAME     R458 2
 '@T6G_MB_LIB.T6G(SCH_1):PAGE29_I405@PURE_QUANTA.Q_RES(CHIPS)':
 'B': CDS_PINID='B';
NODE_NAME     R1593 1
 '@T6G_MB_LIB.T6G(SCH_1):PAGE29_I427@PURE_QUANTA.Q_RES(CHIPS)':
 'A': CDS_PINID='A';
NODE_NAME     R472 1
 '@T6G_MB_LIB.T6G(SCH_1):PAGE29_I428@PURE_QUANTA.Q_RES(CHIPS)':
 'A': CDS_PINID='A';
NODE_NAME     U8000 4
 '@T6G_MB_LIB.T6G(SCH_1):PAGE130_I1@PURE_QUANTA.NC7SB3157P6X(CHIPS)':
 'A': CDS_PINID='A';
NODE_NAME     R1197 1
 '@T6G_MB_LIB.T6G(SCH_1):PAGE130_I24@PURE_QUANTA.Q_RES(CHIPS)':
 'A': CDS_PINID='A';
NET_NAME
'ESPI_CPU0_ALERT_PLD_N'
 '@T6G_MB_LIB.T6G(SCH_1):ESPI_CPU0_ALERT_PLD_N':
 C_SIGNAL='@t6g_mb_lib.t6g(sch_1):espi_cpu0_alert_pld_n';
NODE_NAME     R1557 2
 '@T6G_MB_LIB.T6G(SCH_1):PAGE80_I175@PURE_QUANTA.Q_RES(CHIPS)':
 'B': CDS_PINID='B';
NODE_NAME     U8000 3
 '@T6G_MB_LIB.T6G(SCH_1):PAGE130_I1@PURE_QUANTA.NC7SB3157P6X(CHIPS)':
 'B0': CDS_PINID='B0';
NODE_NAME     R8036 2
 '@T6G_MB_LIB.T6G(SCH_1):PAGE130_I12@PURE_QUANTA.Q_RES(CHIPS)':
 'B': CDS_PINID='B';
NET_NAME
'ESPI_CPU0_ALERT_R1_N'
 '@T6G_MB_LIB.T6G(SCH_1):ESPI_CPU0_ALERT_R1_N':
 C_SIGNAL='@t6g_mb_lib.t6g(sch_1):espi_cpu0_alert_r1_n';
NODE_NAME     U8000 1
 '@T6G_MB_LIB.T6G(SCH_1):PAGE130_I1@PURE_QUANTA.NC7SB3157P6X(CHIPS)':
 'B1': CDS_PINID='B1';
NODE_NAME     R8034 1
 '@T6G_MB_LIB.T6G(SCH_1):PAGE130_I23@PURE_QUANTA.Q_RES(CHIPS)':
 'A': CDS_PINID='A';
NET_NAME
'ESPI_CPU0_ALERT_R_N'
 '@T6G_MB_LIB.T6G(SCH_1):ESPI_CPU0_ALERT_R_N':
 C_SIGNAL='@t6g_mb_lib.t6g(sch_1):espi_cpu0_alert_r_n';
NODE_NAME     R1557 1
 '@T6G_MB_LIB.T6G(SCH_1):PAGE80_I175@PURE_QUANTA.Q_RES(CHIPS)':
 'A': CDS_PINID='A';
NODE_NAME     U18 P20
 '@T6G_MB_LIB.T6G(SCH_1):PAGE80_I217@PURE_QUANTA.LCMXO3LF9400C5BG484C(CHIPS)':
 'PR20D': CDS_PINID='PR20D';
NET_NAME
'ESPI_CPU0_CS1_N'
 '@T6G_MB_LIB.T6G(SCH_1):ESPI_CPU0_CS1_N':
 C_SIGNAL='@t6g_mb_lib.t6g(sch_1):espi_cpu0_cs1_n';
NODE_NAME     R455 2
 '@T6G_MB_LIB.T6G(SCH_1):PAGE29_I284@PURE_QUANTA.Q_RES(CHIPS)':
 'B': CDS_PINID='B';
NODE_NAME     J41 B2
 '@T6G_MB_LIB.T6G(SCH_1):PAGE348_I176@PURE_QUANTA.SCONN168_ME1016810202011(CHIPS)':
 '+12V_EDGE_B2': CDS_PINID='\+12v_edge_b2\';
NODE_NAME     R1553 2
 '@T6G_MB_LIB.T6G(SCH_1):PAGE80_I174@PURE_QUANTA.Q_RES(CHIPS)':
 'B': CDS_PINID='B';
NODE_NAME     R462 1
 '@T6G_MB_LIB.T6G(SCH_1):PAGE29_I425@PURE_QUANTA.Q_RES(CHIPS)':
 'A': CDS_PINID='A';
NODE_NAME     R1592 1
 '@T6G_MB_LIB.T6G(SCH_1):PAGE29_I426@PURE_QUANTA.Q_RES(CHIPS)':
 'A': CDS_PINID='A';
NET_NAME
'ESPI_CPU0_CS1_R_N'
 '@T6G_MB_LIB.T6G(SCH_1):ESPI_CPU0_CS1_R_N':
 C_SIGNAL='@t6g_mb_lib.t6g(sch_1):espi_cpu0_cs1_r_n';
NODE_NAME     R1553 1
 '@T6G_MB_LIB.T6G(SCH_1):PAGE80_I174@PURE_QUANTA.Q_RES(CHIPS)':
 'A': CDS_PINID='A';
NODE_NAME     U18 P22
 '@T6G_MB_LIB.T6G(SCH_1):PAGE80_I217@PURE_QUANTA.LCMXO3LF9400C5BG484C(CHIPS)':
 'PR20C': CDS_PINID='PR20C';
NET_NAME
'ESPI_CPU0_D0'
 '@T6G_MB_LIB.T6G(SCH_1):ESPI_CPU0_D0':
 C_SIGNAL='@t6g_mb_lib.t6g(sch_1):espi_cpu0_d0';
NODE_NAME     R468 1
 '@T6G_MB_LIB.T6G(SCH_1):PAGE29_I329@PURE_QUANTA.Q_RES(CHIPS)':
 'A': CDS_PINID='A';
NODE_NAME     R1503 2
 '@T6G_MB_LIB.T6G(SCH_1):PAGE29_I396@PURE_QUANTA.Q_RES(CHIPS)':
 'B': CDS_PINID='B';
NODE_NAME     J41 B5
 '@T6G_MB_LIB.T6G(SCH_1):PAGE348_I176@PURE_QUANTA.SCONN168_ME1016810202011(CHIPS)':
 '+12V_EDGE_B5': CDS_PINID='\+12v_edge_b5\';
NODE_NAME     R1549 2
 '@T6G_MB_LIB.T6G(SCH_1):PAGE80_I173@PURE_QUANTA.Q_RES(CHIPS)':
 'B': CDS_PINID='B';
NET_NAME
'ESPI_CPU0_D1'
 '@T6G_MB_LIB.T6G(SCH_1):ESPI_CPU0_D1':
 C_SIGNAL='@t6g_mb_lib.t6g(sch_1):espi_cpu0_d1';
NODE_NAME     R469 1
 '@T6G_MB_LIB.T6G(SCH_1):PAGE29_I328@PURE_QUANTA.Q_RES(CHIPS)':
 'A': CDS_PINID='A';
NODE_NAME     R1504 2
 '@T6G_MB_LIB.T6G(SCH_1):PAGE29_I397@PURE_QUANTA.Q_RES(CHIPS)':
 'B': CDS_PINID='B';
NODE_NAME     J41 B6
 '@T6G_MB_LIB.T6G(SCH_1):PAGE348_I176@PURE_QUANTA.SCONN168_ME1016810202011(CHIPS)':
 '+12V_EDGE_B6': CDS_PINID='\+12v_edge_b6\';
NODE_NAME     R1550 2
 '@T6G_MB_LIB.T6G(SCH_1):PAGE80_I171@PURE_QUANTA.Q_RES(CHIPS)':
 'B': CDS_PINID='B';
NET_NAME
'ESPI_CPU0_D2'
 '@T6G_MB_LIB.T6G(SCH_1):ESPI_CPU0_D2':
 C_SIGNAL='@t6g_mb_lib.t6g(sch_1):espi_cpu0_d2';
NODE_NAME     R470 1
 '@T6G_MB_LIB.T6G(SCH_1):PAGE29_I327@PURE_QUANTA.Q_RES(CHIPS)':
 'A': CDS_PINID='A';
NODE_NAME     R1505 2
 '@T6G_MB_LIB.T6G(SCH_1):PAGE29_I398@PURE_QUANTA.Q_RES(CHIPS)':
 'B': CDS_PINID='B';
NODE_NAME     J41 B7
 '@T6G_MB_LIB.T6G(SCH_1):PAGE348_I176@PURE_QUANTA.SCONN168_ME1016810202011(CHIPS)':
 'BIF0#': CDS_PINID='\bif0#\';
NODE_NAME     R1551 2
 '@T6G_MB_LIB.T6G(SCH_1):PAGE80_I169@PURE_QUANTA.Q_RES(CHIPS)':
 'B': CDS_PINID='B';
NET_NAME
'ESPI_CPU0_D3'
 '@T6G_MB_LIB.T6G(SCH_1):ESPI_CPU0_D3':
 C_SIGNAL='@t6g_mb_lib.t6g(sch_1):espi_cpu0_d3';
NODE_NAME     R471 1
 '@T6G_MB_LIB.T6G(SCH_1):PAGE29_I330@PURE_QUANTA.Q_RES(CHIPS)':
 'A': CDS_PINID='A';
NODE_NAME     R1506 2
 '@T6G_MB_LIB.T6G(SCH_1):PAGE29_I399@PURE_QUANTA.Q_RES(CHIPS)':
 'B': CDS_PINID='B';
NODE_NAME     J41 B8
 '@T6G_MB_LIB.T6G(SCH_1):PAGE348_I176@PURE_QUANTA.SCONN168_ME1016810202011(CHIPS)':
 'BIF1#': CDS_PINID='\bif1#\';
NODE_NAME     R1552 2
 '@T6G_MB_LIB.T6G(SCH_1):PAGE80_I170@PURE_QUANTA.Q_RES(CHIPS)':
 'B': CDS_PINID='B';
NET_NAME
'ESPI_CPU0_R1_D0'
 '@T6G_MB_LIB.T6G(SCH_1):ESPI_CPU0_R1_D0':
 C_SIGNAL='@t6g_mb_lib.t6g(sch_1):espi_cpu0_r1_d0';
NODE_NAME     R1549 1
 '@T6G_MB_LIB.T6G(SCH_1):PAGE80_I173@PURE_QUANTA.Q_RES(CHIPS)':
 'A': CDS_PINID='A';
NODE_NAME     U18 T21
 '@T6G_MB_LIB.T6G(SCH_1):PAGE80_I217@PURE_QUANTA.LCMXO3LF9400C5BG484C(CHIPS)':
 'PR21B': CDS_PINID='PR21B';
NET_NAME
'ESPI_CPU0_R1_D1'
 '@T6G_MB_LIB.T6G(SCH_1):ESPI_CPU0_R1_D1':
 C_SIGNAL='@t6g_mb_lib.t6g(sch_1):espi_cpu0_r1_d1';
NODE_NAME     R1550 1
 '@T6G_MB_LIB.T6G(SCH_1):PAGE80_I171@PURE_QUANTA.Q_RES(CHIPS)':
 'A': CDS_PINID='A';
NODE_NAME     U18 P19
 '@T6G_MB_LIB.T6G(SCH_1):PAGE80_I217@PURE_QUANTA.LCMXO3LF9400C5BG484C(CHIPS)':
 'PR21C': CDS_PINID='PR21C';
NET_NAME
'ESPI_CPU0_R1_D2'
 '@T6G_MB_LIB.T6G(SCH_1):ESPI_CPU0_R1_D2':
 C_SIGNAL='@t6g_mb_lib.t6g(sch_1):espi_cpu0_r1_d2';
NODE_NAME     R1551 1
 '@T6G_MB_LIB.T6G(SCH_1):PAGE80_I169@PURE_QUANTA.Q_RES(CHIPS)':
 'A': CDS_PINID='A';
NODE_NAME     U18 P18
 '@T6G_MB_LIB.T6G(SCH_1):PAGE80_I217@PURE_QUANTA.LCMXO3LF9400C5BG484C(CHIPS)':
 'PR21D': CDS_PINID='PR21D';
NET_NAME
'ESPI_CPU0_R1_D3'
 '@T6G_MB_LIB.T6G(SCH_1):ESPI_CPU0_R1_D3':
 C_SIGNAL='@t6g_mb_lib.t6g(sch_1):espi_cpu0_r1_d3';
NODE_NAME     R1552 1
 '@T6G_MB_LIB.T6G(SCH_1):PAGE80_I170@PURE_QUANTA.Q_RES(CHIPS)':
 'A': CDS_PINID='A';
NODE_NAME     U18 P17
 '@T6G_MB_LIB.T6G(SCH_1):PAGE80_I217@PURE_QUANTA.LCMXO3LF9400C5BG484C(CHIPS)':
 'PR24A': CDS_PINID='PR24A';
NET_NAME
'ESPI_CPU0_R_ALERT_N'
 '@T6G_MB_LIB.T6G(SCH_1):ESPI_CPU0_R_ALERT_N':
 C_SIGNAL='@t6g_mb_lib.t6g(sch_1):espi_cpu0_r_alert_n';
NODE_NAME     U25 DF24
 '@T6G_MB_LIB.T6G(SCH_1):PAGE29_I287@PURE_QUANTA.GENOA_SP5(CHIPS)':
 'ESPI1_ALERT_L||AGPIO110': CDS_PINID='\espi1_alert_l||agpio110\';
NODE_NAME     R472 2
 '@T6G_MB_LIB.T6G(SCH_1):PAGE29_I428@PURE_QUANTA.Q_RES(CHIPS)':
 'B': CDS_PINID='B';
NET_NAME
'ESPI_CPU0_R_CS1_N'
 '@T6G_MB_LIB.T6G(SCH_1):ESPI_CPU0_R_CS1_N':
 C_SIGNAL='@t6g_mb_lib.t6g(sch_1):espi_cpu0_r_cs1_n';
NODE_NAME     U25 DJ23
 '@T6G_MB_LIB.T6G(SCH_1):PAGE29_I287@PURE_QUANTA.GENOA_SP5(CHIPS)':
 'ESPI_CS1_L||AGPIO125': CDS_PINID='\espi_cs1_l||agpio125\';
NODE_NAME     R462 2
 '@T6G_MB_LIB.T6G(SCH_1):PAGE29_I425@PURE_QUANTA.Q_RES(CHIPS)':
 'B': CDS_PINID='B';
NET_NAME
'ESPI_CPU0_R_D0'
 '@T6G_MB_LIB.T6G(SCH_1):ESPI_CPU0_R_D0':
 C_SIGNAL='@t6g_mb_lib.t6g(sch_1):espi_cpu0_r_d0';
NODE_NAME     U25 DH24
 '@T6G_MB_LIB.T6G(SCH_1):PAGE29_I287@PURE_QUANTA.GENOA_SP5(CHIPS)':
 'ESPI1_DAT0||SPI1_DAT0||AGPIO131': CDS_PINID='\espi1_dat0||spi1_dat0||agpio131\';
NODE_NAME     R468 2
 '@T6G_MB_LIB.T6G(SCH_1):PAGE29_I329@PURE_QUANTA.Q_RES(CHIPS)':
 'B': CDS_PINID='B';
NET_NAME
'ESPI_CPU0_R_D1'
 '@T6G_MB_LIB.T6G(SCH_1):ESPI_CPU0_R_D1':
 C_SIGNAL='@t6g_mb_lib.t6g(sch_1):espi_cpu0_r_d1';
NODE_NAME     U25 DE24
 '@T6G_MB_LIB.T6G(SCH_1):PAGE29_I287@PURE_QUANTA.GENOA_SP5(CHIPS)':
 'ESPI1_DAT1||SPI1_DAT1||AGPIO132': CDS_PINID='\espi1_dat1||spi1_dat1||agpio132\';
NODE_NAME     R469 2
 '@T6G_MB_LIB.T6G(SCH_1):PAGE29_I328@PURE_QUANTA.Q_RES(CHIPS)':
 'B': CDS_PINID='B';
NET_NAME
'ESPI_CPU0_R_D2'
 '@T6G_MB_LIB.T6G(SCH_1):ESPI_CPU0_R_D2':
 C_SIGNAL='@t6g_mb_lib.t6g(sch_1):espi_cpu0_r_d2';
NODE_NAME     U25 DF25
 '@T6G_MB_LIB.T6G(SCH_1):PAGE29_I287@PURE_QUANTA.GENOA_SP5(CHIPS)':
 'ESPI1_DAT2||SPI1_DAT2||AGPIO133': CDS_PINID='\espi1_dat2||spi1_dat2||agpio133\';
NODE_NAME     R470 2
 '@T6G_MB_LIB.T6G(SCH_1):PAGE29_I327@PURE_QUANTA.Q_RES(CHIPS)':
 'B': CDS_PINID='B';
NET_NAME
'ESPI_CPU0_R_D3'
 '@T6G_MB_LIB.T6G(SCH_1):ESPI_CPU0_R_D3':
 C_SIGNAL='@t6g_mb_lib.t6g(sch_1):espi_cpu0_r_d3';
NODE_NAME     U25 DG25
 '@T6G_MB_LIB.T6G(SCH_1):PAGE29_I287@PURE_QUANTA.GENOA_SP5(CHIPS)':
 'ESPI1_DAT3||SPI1_DAT3||AGPIO134': CDS_PINID='\espi1_dat3||spi1_dat3||agpio134\';
NODE_NAME     R471 2
 '@T6G_MB_LIB.T6G(SCH_1):PAGE29_I330@PURE_QUANTA.Q_RES(CHIPS)':
 'B': CDS_PINID='B';
NET_NAME
'FAB_BMC_REV_ID0'
 '@T6G_MB_LIB.T6G(SCH_1):FAB_BMC_REV_ID0':
 C_SIGNAL='@t6g_mb_lib.t6g(sch_1):fab_bmc_rev_id0';
NODE_NAME     U18 J1
 '@T6G_MB_LIB.T6G(SCH_1):PAGE81_I143@PURE_QUANTA.LCMXO3LF9400C5BG484C(CHIPS)':
 'PL12B': CDS_PINID='PL12B';
NODE_NAME     R6151 1
 '@T6G_MB_LIB.T6G(SCH_1):PAGE83_I141@PURE_QUANTA.Q_RES(CHIPS)':
 'A': CDS_PINID='A';
NODE_NAME     R6148 2
 '@T6G_MB_LIB.T6G(SCH_1):PAGE83_I142@PURE_QUANTA.Q_RES(CHIPS)':
 'B': CDS_PINID='B';
NET_NAME
'FAB_BMC_REV_ID1'
 '@T6G_MB_LIB.T6G(SCH_1):FAB_BMC_REV_ID1':
 C_SIGNAL='@t6g_mb_lib.t6g(sch_1):fab_bmc_rev_id1';
NODE_NAME     U18 K7
 '@T6G_MB_LIB.T6G(SCH_1):PAGE81_I143@PURE_QUANTA.LCMXO3LF9400C5BG484C(CHIPS)':
 'PL12C': CDS_PINID='PL12C';
NODE_NAME     R6150 1
 '@T6G_MB_LIB.T6G(SCH_1):PAGE83_I139@PURE_QUANTA.Q_RES(CHIPS)':
 'A': CDS_PINID='A';
NODE_NAME     R6147 2
 '@T6G_MB_LIB.T6G(SCH_1):PAGE83_I140@PURE_QUANTA.Q_RES(CHIPS)':
 'B': CDS_PINID='B';
NET_NAME
'FAB_BMC_REV_ID2'
 '@T6G_MB_LIB.T6G(SCH_1):FAB_BMC_REV_ID2':
 C_SIGNAL='@t6g_mb_lib.t6g(sch_1):fab_bmc_rev_id2';
NODE_NAME     U18 K6
 '@T6G_MB_LIB.T6G(SCH_1):PAGE81_I143@PURE_QUANTA.LCMXO3LF9400C5BG484C(CHIPS)':
 'PL12D': CDS_PINID='PL12D';
NODE_NAME     R6149 1
 '@T6G_MB_LIB.T6G(SCH_1):PAGE83_I137@PURE_QUANTA.Q_RES(CHIPS)':
 'A': CDS_PINID='A';
NODE_NAME     R6146 2
 '@T6G_MB_LIB.T6G(SCH_1):PAGE83_I138@PURE_QUANTA.Q_RES(CHIPS)':
 'B': CDS_PINID='B';
NET_NAME
'FAB_REV_ID0'
 '@T6G_MB_LIB.T6G(SCH_1):FAB_REV_ID0':
 C_SIGNAL='@t6g_mb_lib.t6g(sch_1):fab_rev_id0';
NODE_NAME     U25 A14
 '@T6G_MB_LIB.T6G(SCH_1):PAGE28_I188@PURE_QUANTA.GENOA_SP5(CHIPS)':
 'AGPIO256||SGPIO0_CLK': CDS_PINID='\agpio256||sgpio0_clk\';
NODE_NAME     R6132 2
 '@T6G_MB_LIB.T6G(SCH_1):PAGE83_I135@PURE_QUANTA.Q_RES(CHIPS)':
 'B': CDS_PINID='B';
NODE_NAME     R6135 1
 '@T6G_MB_LIB.T6G(SCH_1):PAGE83_I136@PURE_QUANTA.Q_RES(CHIPS)':
 'A': CDS_PINID='A';
NET_NAME
'FAB_REV_ID1'
 '@T6G_MB_LIB.T6G(SCH_1):FAB_REV_ID1':
 C_SIGNAL='@t6g_mb_lib.t6g(sch_1):fab_rev_id1';
NODE_NAME     U25 C14
 '@T6G_MB_LIB.T6G(SCH_1):PAGE28_I188@PURE_QUANTA.GENOA_SP5(CHIPS)':
 'AGPIO257||SGPIO1_CLK||CLK_REQ01_L': CDS_PINID='\agpio257||sgpio1_clk||clk_req01_l\';
NODE_NAME     R6134 1
 '@T6G_MB_LIB.T6G(SCH_1):PAGE83_I133@PURE_QUANTA.Q_RES(CHIPS)':
 'A': CDS_PINID='A';
NODE_NAME     R6131 2
 '@T6G_MB_LIB.T6G(SCH_1):PAGE83_I134@PURE_QUANTA.Q_RES(CHIPS)':
 'B': CDS_PINID='B';
NET_NAME
'FAB_REV_ID2'
 '@T6G_MB_LIB.T6G(SCH_1):FAB_REV_ID2':
 C_SIGNAL='@t6g_mb_lib.t6g(sch_1):fab_rev_id2';
NODE_NAME     U25 A13
 '@T6G_MB_LIB.T6G(SCH_1):PAGE28_I188@PURE_QUANTA.GENOA_SP5(CHIPS)':
 'AGPIO258||SGPIO2_CLK||CLK_REQ02_L': CDS_PINID='\agpio258||sgpio2_clk||clk_req02_l\';
NODE_NAME     R6130 2
 '@T6G_MB_LIB.T6G(SCH_1):PAGE83_I131@PURE_QUANTA.Q_RES(CHIPS)':
 'B': CDS_PINID='B';
NODE_NAME     R6133 1
 '@T6G_MB_LIB.T6G(SCH_1):PAGE83_I132@PURE_QUANTA.Q_RES(CHIPS)':
 'A': CDS_PINID='A';
NET_NAME
'FB_BMC_ISOLATE'
 '@T6G_MB_LIB.T6G(SCH_1):FB_BMC_ISOLATE':
 C_SIGNAL='@t6g_mb_lib.t6g(sch_1):fb_bmc_isolate';
NODE_NAME     U67 1
 '@T6G_MB_LIB.T6G(SCH_1):PAGE336_I1@PURE_QUANTA.74CBTLV3126PW(CHIPS)':
 '1OE': CDS_PINID='\1oe\';
NODE_NAME     U67 4
 '@T6G_MB_LIB.T6G(SCH_1):PAGE336_I1@PURE_QUANTA.74CBTLV3126PW(CHIPS)':
 '2OE': CDS_PINID='\2oe\';
NODE_NAME     U67 10
 '@T6G_MB_LIB.T6G(SCH_1):PAGE336_I1@PURE_QUANTA.74CBTLV3126PW(CHIPS)':
 '3OE': CDS_PINID='\3oe\';
NODE_NAME     U67 13
 '@T6G_MB_LIB.T6G(SCH_1):PAGE336_I1@PURE_QUANTA.74CBTLV3126PW(CHIPS)':
 '4OE': CDS_PINID='\4oe\';
NODE_NAME     U7 1
 '@T6G_MB_LIB.T6G(SCH_1):PAGE336_I2@PURE_QUANTA.74CBTLV3126PW(CHIPS)':
 '1OE': CDS_PINID='\1oe\';
NODE_NAME     U7 4
 '@T6G_MB_LIB.T6G(SCH_1):PAGE336_I2@PURE_QUANTA.74CBTLV3126PW(CHIPS)':
 '2OE': CDS_PINID='\2oe\';
NODE_NAME     U7 10
 '@T6G_MB_LIB.T6G(SCH_1):PAGE336_I2@PURE_QUANTA.74CBTLV3126PW(CHIPS)':
 '3OE': CDS_PINID='\3oe\';
NODE_NAME     U7 13
 '@T6G_MB_LIB.T6G(SCH_1):PAGE336_I2@PURE_QUANTA.74CBTLV3126PW(CHIPS)':
 '4OE': CDS_PINID='\4oe\';
NODE_NAME     R1289 1
 '@T6G_MB_LIB.T6G(SCH_1):PAGE336_I56@PURE_QUANTA.Q_RES(CHIPS)':
 'A': CDS_PINID='A';
NODE_NAME     U320 4
 '@T6G_MB_LIB.T6G(SCH_1):PAGE337_I82@PURE_QUANTA.74LVC1G66GV(CHIPS)':
 'E': CDS_PINID='E';
NODE_NAME     R2473 2
 '@T6G_MB_LIB.T6G(SCH_1):PAGE336_I164@PURE_QUANTA.Q_RES(CHIPS)':
 'B': CDS_PINID='B';
NODE_NAME     R2474 2
 '@T6G_MB_LIB.T6G(SCH_1):PAGE336_I165@PURE_QUANTA.Q_RES(CHIPS)':
 'B': CDS_PINID='B';
NET_NAME
'FB_BMC_ISOLATE1'
 '@T6G_MB_LIB.T6G(SCH_1):FB_BMC_ISOLATE1':
 C_SIGNAL='@t6g_mb_lib.t6g(sch_1):fb_bmc_isolate1';
NODE_NAME     R3207 1
 '@T6G_MB_LIB.T6G(SCH_1):PAGE307_I15@PURE_QUANTA.Q_RES(CHIPS)':
 'A': CDS_PINID='A';
NODE_NAME     U222 1
 '@T6G_MB_LIB.T6G(SCH_1):PAGE307_I32@PURE_QUANTA.74CBTLV3126PW(CHIPS)':
 '1OE': CDS_PINID='\1oe\';
NODE_NAME     U222 4
 '@T6G_MB_LIB.T6G(SCH_1):PAGE307_I32@PURE_QUANTA.74CBTLV3126PW(CHIPS)':
 '2OE': CDS_PINID='\2oe\';
NODE_NAME     U222 10
 '@T6G_MB_LIB.T6G(SCH_1):PAGE307_I32@PURE_QUANTA.74CBTLV3126PW(CHIPS)':
 '3OE': CDS_PINID='\3oe\';
NODE_NAME     U222 13
 '@T6G_MB_LIB.T6G(SCH_1):PAGE307_I32@PURE_QUANTA.74CBTLV3126PW(CHIPS)':
 '4OE': CDS_PINID='\4oe\';
NODE_NAME     U223 1
 '@T6G_MB_LIB.T6G(SCH_1):PAGE307_I78@PURE_QUANTA.74CBTLV3126PW(CHIPS)':
 '1OE': CDS_PINID='\1oe\';
NODE_NAME     U223 4
 '@T6G_MB_LIB.T6G(SCH_1):PAGE307_I78@PURE_QUANTA.74CBTLV3126PW(CHIPS)':
 '2OE': CDS_PINID='\2oe\';
NODE_NAME     U223 10
 '@T6G_MB_LIB.T6G(SCH_1):PAGE307_I78@PURE_QUANTA.74CBTLV3126PW(CHIPS)':
 '3OE': CDS_PINID='\3oe\';
NODE_NAME     U223 13
 '@T6G_MB_LIB.T6G(SCH_1):PAGE307_I78@PURE_QUANTA.74CBTLV3126PW(CHIPS)':
 '4OE': CDS_PINID='\4oe\';
NODE_NAME     U321 4
 '@T6G_MB_LIB.T6G(SCH_1):PAGE342_I76@PURE_QUANTA.74LVC1G66GV(CHIPS)':
 'E': CDS_PINID='E';
NODE_NAME     R3206 2
 '@T6G_MB_LIB.T6G(SCH_1):PAGE307_I85@PURE_QUANTA.Q_RES(CHIPS)':
 'B': CDS_PINID='B';
NODE_NAME     R3205 2
 '@T6G_MB_LIB.T6G(SCH_1):PAGE307_I86@PURE_QUANTA.Q_RES(CHIPS)':
 'B': CDS_PINID='B';
NET_NAME
'FB_BMC_ISOLATE_R1'
 '@T6G_MB_LIB.T6G(SCH_1):FB_BMC_ISOLATE_R1':
 C_SIGNAL='@t6g_mb_lib.t6g(sch_1):fb_bmc_isolate_r1';
NODE_NAME     U66 4
 '@T6G_MB_LIB.T6G(SCH_1):PAGE336_I157@PURE_QUANTA.74LVC1G126SE7(CHIPS)':
 'Y': CDS_PINID='Y';
NODE_NAME     R2473 1
 '@T6G_MB_LIB.T6G(SCH_1):PAGE336_I164@PURE_QUANTA.Q_RES(CHIPS)':
 'A': CDS_PINID='A';
NET_NAME
'FB_BMC_ISOLATE_R2'
 '@T6G_MB_LIB.T6G(SCH_1):FB_BMC_ISOLATE_R2':
 C_SIGNAL='@t6g_mb_lib.t6g(sch_1):fb_bmc_isolate_r2';
NODE_NAME     U286 4
 '@T6G_MB_LIB.T6G(SCH_1):PAGE307_I80@PURE_QUANTA.74LVC1G126SE7(CHIPS)':
 'Y': CDS_PINID='Y';
NODE_NAME     R3205 1
 '@T6G_MB_LIB.T6G(SCH_1):PAGE307_I86@PURE_QUANTA.Q_RES(CHIPS)':
 'A': CDS_PINID='A';
NET_NAME
'FG_SS_EN'
 '@T6G_MB_LIB.T6G(SCH_1):FG_SS_EN':
 C_SIGNAL='@t6g_mb_lib.t6g(sch_1):fg_ss_en';
NODE_NAME     R4079 1
 '@T6G_MB_LIB.T6G(SCH_1):PAGE232_I46@PURE_QUANTA.Q_RES(CHIPS)':
 'A': CDS_PINID='A';
NODE_NAME     R4078 2
 '@T6G_MB_LIB.T6G(SCH_1):PAGE232_I47@PURE_QUANTA.Q_RES(CHIPS)':
 'B': CDS_PINID='B';
NODE_NAME     U247 23
 '@T6G_MB_LIB.T6G(SCH_1):PAGE232_I77@PURE_QUANTA.9FGL0251DKILFT(CHIPS)':
 '^VSS_EN_TRI': CDS_PINID='\^vss_en_tri\';
NET_NAME
'FM_9ZXL045_P0_0_OE_N'
 '@T6G_MB_LIB.T6G(SCH_1):FM_9ZXL045_P0_0_OE_N':
 C_SIGNAL='@t6g_mb_lib.t6g(sch_1):fm_9zxl045_p0_0_oe_n';
NODE_NAME     R4520 1
 '@T6G_MB_LIB.T6G(SCH_1):PAGE160_I55@PURE_QUANTA.Q_RES(CHIPS)':
 'A': CDS_PINID='A';
NODE_NAME     U314 15
 '@T6G_MB_LIB.T6G(SCH_1):PAGE160_I63@PURE_QUANTA.9ZXL0451EKILFT(CHIPS)':
 'VOE0#': CDS_PINID='\voe0#\';
NET_NAME
'FM_9ZXL045_P0_1_OE_N'
 '@T6G_MB_LIB.T6G(SCH_1):FM_9ZXL045_P0_1_OE_N':
 C_SIGNAL='@t6g_mb_lib.t6g(sch_1):fm_9zxl045_p0_1_oe_n';
NODE_NAME     R4519 1
 '@T6G_MB_LIB.T6G(SCH_1):PAGE160_I53@PURE_QUANTA.Q_RES(CHIPS)':
 'A': CDS_PINID='A';
NODE_NAME     U314 18
 '@T6G_MB_LIB.T6G(SCH_1):PAGE160_I63@PURE_QUANTA.9ZXL0451EKILFT(CHIPS)':
 'VOE1#': CDS_PINID='\voe1#\';
NET_NAME
'FM_9ZXL045_P0_2_OE_N'
 '@T6G_MB_LIB.T6G(SCH_1):FM_9ZXL045_P0_2_OE_N':
 C_SIGNAL='@t6g_mb_lib.t6g(sch_1):fm_9zxl045_p0_2_oe_n';
NODE_NAME     R4518 1
 '@T6G_MB_LIB.T6G(SCH_1):PAGE160_I52@PURE_QUANTA.Q_RES(CHIPS)':
 'A': CDS_PINID='A';
NODE_NAME     U314 24
 '@T6G_MB_LIB.T6G(SCH_1):PAGE160_I63@PURE_QUANTA.9ZXL0451EKILFT(CHIPS)':
 'VOE2#': CDS_PINID='\voe2#\';
NET_NAME
'FM_9ZXL045_P0_3_OE_N'
 '@T6G_MB_LIB.T6G(SCH_1):FM_9ZXL045_P0_3_OE_N':
 C_SIGNAL='@t6g_mb_lib.t6g(sch_1):fm_9zxl045_p0_3_oe_n';
NODE_NAME     U314 26
 '@T6G_MB_LIB.T6G(SCH_1):PAGE160_I63@PURE_QUANTA.9ZXL0451EKILFT(CHIPS)':
 'VOE3#': CDS_PINID='\voe3#\';
NODE_NAME     R6802 1
 '@T6G_MB_LIB.T6G(SCH_1):PAGE160_I68@PURE_QUANTA.Q_RES(CHIPS)':
 'A': CDS_PINID='A';
NET_NAME
'FM_9ZXL045_P0_DEV_EN'
 '@T6G_MB_LIB.T6G(SCH_1):FM_9ZXL045_P0_DEV_EN':
 C_SIGNAL='@t6g_mb_lib.t6g(sch_1):fm_9zxl045_p0_dev_en';
NODE_NAME     U314 1
 '@T6G_MB_LIB.T6G(SCH_1):PAGE160_I63@PURE_QUANTA.9ZXL0451EKILFT(CHIPS)':
 '^CKPWRGD_PD#': CDS_PINID='\^ckpwrgd_pd#\';
NODE_NAME     R4476 2
 '@T6G_MB_LIB.T6G(SCH_1):PAGE160_I73@PURE_QUANTA.Q_RES(CHIPS)':
 'B': CDS_PINID='B';
NET_NAME
'FM_9ZXL045_P1_0_OE_N'
 '@T6G_MB_LIB.T6G(SCH_1):FM_9ZXL045_P1_0_OE_N':
 C_SIGNAL='@t6g_mb_lib.t6g(sch_1):fm_9zxl045_p1_0_oe_n';
NODE_NAME     R594 1
 '@T6G_MB_LIB.T6G(SCH_1):PAGE379_I51@PURE_QUANTA.Q_RES(CHIPS)':
 'A': CDS_PINID='A';
NODE_NAME     U10 15
 '@T6G_MB_LIB.T6G(SCH_1):PAGE379_I63@PURE_QUANTA.9ZXL0451EKILFT(CHIPS)':
 'VOE0#': CDS_PINID='\voe0#\';
NET_NAME
'FM_9ZXL045_P1_1_OE_N'
 '@T6G_MB_LIB.T6G(SCH_1):FM_9ZXL045_P1_1_OE_N':
 C_SIGNAL='@t6g_mb_lib.t6g(sch_1):fm_9zxl045_p1_1_oe_n';
NODE_NAME     R593 1
 '@T6G_MB_LIB.T6G(SCH_1):PAGE379_I50@PURE_QUANTA.Q_RES(CHIPS)':
 'A': CDS_PINID='A';
NODE_NAME     U10 18
 '@T6G_MB_LIB.T6G(SCH_1):PAGE379_I63@PURE_QUANTA.9ZXL0451EKILFT(CHIPS)':
 'VOE1#': CDS_PINID='\voe1#\';
NET_NAME
'FM_9ZXL045_P1_2_OE_N'
 '@T6G_MB_LIB.T6G(SCH_1):FM_9ZXL045_P1_2_OE_N':
 C_SIGNAL='@t6g_mb_lib.t6g(sch_1):fm_9zxl045_p1_2_oe_n';
NODE_NAME     R592 1
 '@T6G_MB_LIB.T6G(SCH_1):PAGE379_I49@PURE_QUANTA.Q_RES(CHIPS)':
 'A': CDS_PINID='A';
NODE_NAME     U10 24
 '@T6G_MB_LIB.T6G(SCH_1):PAGE379_I63@PURE_QUANTA.9ZXL0451EKILFT(CHIPS)':
 'VOE2#': CDS_PINID='\voe2#\';
NET_NAME
'FM_9ZXL045_P1_3_OE_N'
 '@T6G_MB_LIB.T6G(SCH_1):FM_9ZXL045_P1_3_OE_N':
 C_SIGNAL='@t6g_mb_lib.t6g(sch_1):fm_9zxl045_p1_3_oe_n';
NODE_NAME     U10 26
 '@T6G_MB_LIB.T6G(SCH_1):PAGE379_I63@PURE_QUANTA.9ZXL0451EKILFT(CHIPS)':
 'VOE3#': CDS_PINID='\voe3#\';
NODE_NAME     R6803 1
 '@T6G_MB_LIB.T6G(SCH_1):PAGE379_I76@PURE_QUANTA.Q_RES(CHIPS)':
 'A': CDS_PINID='A';
NET_NAME
'FM_9ZXL045_P1_DEV_EN'
 '@T6G_MB_LIB.T6G(SCH_1):FM_9ZXL045_P1_DEV_EN':
 C_SIGNAL='@t6g_mb_lib.t6g(sch_1):fm_9zxl045_p1_dev_en';
NODE_NAME     U10 1
 '@T6G_MB_LIB.T6G(SCH_1):PAGE379_I63@PURE_QUANTA.9ZXL0451EKILFT(CHIPS)':
 '^CKPWRGD_PD#': CDS_PINID='\^ckpwrgd_pd#\';
NODE_NAME     R560 2
 '@T6G_MB_LIB.T6G(SCH_1):PAGE379_I81@PURE_QUANTA.Q_RES(CHIPS)':
 'B': CDS_PINID='B';
NET_NAME
'FM_AC_PWR_BTN_N'
 '@T6G_MB_LIB.T6G(SCH_1):FM_AC_PWR_BTN_N':
 C_SIGNAL='@t6g_mb_lib.t6g(sch_1):fm_ac_pwr_btn_n';
NODE_NAME     J41 B42
 '@T6G_MB_LIB.T6G(SCH_1):PAGE348_I176@PURE_QUANTA.SCONN168_ME1016810202011(CHIPS)':
 'PRSNTB0#': CDS_PINID='\prsntb0#\';
NODE_NAME     R8101 2
 '@T6G_MB_LIB.T6G(SCH_1):PAGE348_I215@PURE_QUANTA.Q_RES(CHIPS)':
 'B': CDS_PINID='B';
NET_NAME
'FM_AC_PWR_BTN_PDB_N'
 '@T6G_MB_LIB.T6G(SCH_1):FM_AC_PWR_BTN_PDB_N':
 C_SIGNAL='@t6g_mb_lib.t6g(sch_1):fm_ac_pwr_btn_pdb_n';
NODE_NAME     J45 A2
 '@T6G_MB_LIB.T6G(SCH_1):PAGE363_I466@PURE_QUANTA.CONN60_101062636003K02LF(CHIPS)':
 'A2': CDS_PINID='A2';
NODE_NAME     R8102 2
 '@T6G_MB_LIB.T6G(SCH_1):PAGE363_I467@PURE_QUANTA.Q_RES(CHIPS)':
 'B': CDS_PINID='B';
NODE_NAME     C8011 1
 '@T6G_MB_LIB.T6G(SCH_1):PAGE363_I469@PURE_QUANTA.Q_CAP(CHIPS)':
 'A': CDS_PINID='A';
NET_NAME
'FM_AC_PWR_BTN_PLD_ISO_N'
 '@T6G_MB_LIB.T6G(SCH_1):FM_AC_PWR_BTN_PLD_ISO_N':
 C_SIGNAL='@t6g_mb_lib.t6g(sch_1):fm_ac_pwr_btn_pld_iso_n';
NODE_NAME     U18 W18
 '@T6G_MB_LIB.T6G(SCH_1):PAGE80_I216@PURE_QUANTA.LCMXO3LF9400C5BG484C(CHIPS)':
 'PB44D': CDS_PINID='PB44D';
NODE_NAME     R8105 2
 '@T6G_MB_LIB.T6G(SCH_1):PAGE365_I20@PURE_QUANTA.Q_RES(CHIPS)':
 'B': CDS_PINID='B';
NODE_NAME     R8106 2
 '@T6G_MB_LIB.T6G(SCH_1):PAGE365_I31@PURE_QUANTA.Q_RES(CHIPS)':
 'B': CDS_PINID='B';
NET_NAME
'FM_AC_PWR_BTN_PLD_ISO_R_N'
 '@T6G_MB_LIB.T6G(SCH_1):FM_AC_PWR_BTN_PLD_ISO_R_N':
 C_SIGNAL='@t6g_mb_lib.t6g(sch_1):fm_ac_pwr_btn_pld_iso_r_n';
NODE_NAME     U8004 6
 '@T6G_MB_LIB.T6G(SCH_1):PAGE365_I16@PURE_QUANTA.74LVC2G07DW7(CHIPS)':
 '1Y': CDS_PINID='\1y\';
NODE_NAME     R8105 1
 '@T6G_MB_LIB.T6G(SCH_1):PAGE365_I20@PURE_QUANTA.Q_RES(CHIPS)':
 'A': CDS_PINID='A';
NET_NAME
'FM_AC_PWR_BTN_PLD_N'
 '@T6G_MB_LIB.T6G(SCH_1):FM_AC_PWR_BTN_PLD_N':
 C_SIGNAL='@t6g_mb_lib.t6g(sch_1):fm_ac_pwr_btn_pld_n';
NODE_NAME     U8004 1
 '@T6G_MB_LIB.T6G(SCH_1):PAGE365_I16@PURE_QUANTA.74LVC2G07DW7(CHIPS)':
 '1A': CDS_PINID='\1a\';
NODE_NAME     R8104 2
 '@T6G_MB_LIB.T6G(SCH_1):PAGE365_I18@PURE_QUANTA.Q_RES(CHIPS)':
 'B': CDS_PINID='B';
NET_NAME
'FM_AC_PWR_BTN_R_N'
 '@T6G_MB_LIB.T6G(SCH_1):FM_AC_PWR_BTN_R_N':
 C_SIGNAL='@t6g_mb_lib.t6g(sch_1):fm_ac_pwr_btn_r_n';
NODE_NAME     R8101 1
 '@T6G_MB_LIB.T6G(SCH_1):PAGE348_I215@PURE_QUANTA.Q_RES(CHIPS)':
 'A': CDS_PINID='A';
NODE_NAME     R8102 1
 '@T6G_MB_LIB.T6G(SCH_1):PAGE363_I467@PURE_QUANTA.Q_RES(CHIPS)':
 'A': CDS_PINID='A';
NODE_NAME     R8104 1
 '@T6G_MB_LIB.T6G(SCH_1):PAGE365_I18@PURE_QUANTA.Q_RES(CHIPS)':
 'A': CDS_PINID='A';
NODE_NAME     C8012 1
 '@T6G_MB_LIB.T6G(SCH_1):PAGE365_I25@PURE_QUANTA.Q_CAP(CHIPS)':
 'A': CDS_PINID='A';
NODE_NAME     R8103 2
 '@T6G_MB_LIB.T6G(SCH_1):PAGE365_I27@PURE_QUANTA.Q_RES(CHIPS)':
 'B': CDS_PINID='B';
NET_NAME
'FM_APML_MUX2_OE_N'
 '@T6G_MB_LIB.T6G(SCH_1):FM_APML_MUX2_OE_N':
 C_SIGNAL='@t6g_mb_lib.t6g(sch_1):fm_apml_mux2_oe_n';
NODE_NAME     R132 1
 '@T6G_MB_LIB.T6G(SCH_1):PAGE81_I168@PURE_QUANTA.Q_RES(CHIPS)':
 'A': CDS_PINID='A';
NODE_NAME     R134 1
 '@T6G_MB_LIB.T6G(SCH_1):PAGE82_I156@PURE_QUANTA.Q_RES(CHIPS)':
 'A': CDS_PINID='A';
NODE_NAME     R126 1
 '@T6G_MB_LIB.T6G(SCH_1):PAGE82_I163@PURE_QUANTA.Q_RES(CHIPS)':
 'A': CDS_PINID='A';
NODE_NAME     U4 6
 '@T6G_MB_LIB.T6G(SCH_1):PAGE138_I114@PURE_QUANTA.PI3CSW12ZUAEX(CHIPS)':
 'OE#': CDS_PINID='\oe#\';
NET_NAME
'FM_APML_MUX2_OE_R_N'
 '@T6G_MB_LIB.T6G(SCH_1):FM_APML_MUX2_OE_R_N':
 C_SIGNAL='@t6g_mb_lib.t6g(sch_1):fm_apml_mux2_oe_r_n';
NODE_NAME     U18 P6
 '@T6G_MB_LIB.T6G(SCH_1):PAGE81_I143@PURE_QUANTA.LCMXO3LF9400C5BG484C(CHIPS)':
 'PL21D': CDS_PINID='PL21D';
NODE_NAME     R132 2
 '@T6G_MB_LIB.T6G(SCH_1):PAGE81_I168@PURE_QUANTA.Q_RES(CHIPS)':
 'B': CDS_PINID='B';
NET_NAME
'FM_APML_MUX2_SEL'
 '@T6G_MB_LIB.T6G(SCH_1):FM_APML_MUX2_SEL':
 C_SIGNAL='@t6g_mb_lib.t6g(sch_1):fm_apml_mux2_sel';
NODE_NAME     R133 1
 '@T6G_MB_LIB.T6G(SCH_1):PAGE81_I169@PURE_QUANTA.Q_RES(CHIPS)':
 'A': CDS_PINID='A';
NODE_NAME     R135 1
 '@T6G_MB_LIB.T6G(SCH_1):PAGE82_I157@PURE_QUANTA.Q_RES(CHIPS)':
 'A': CDS_PINID='A';
NODE_NAME     R136 1
 '@T6G_MB_LIB.T6G(SCH_1):PAGE82_I162@PURE_QUANTA.Q_RES(CHIPS)':
 'A': CDS_PINID='A';
NODE_NAME     U4 9
 '@T6G_MB_LIB.T6G(SCH_1):PAGE138_I114@PURE_QUANTA.PI3CSW12ZUAEX(CHIPS)':
 'S': CDS_PINID='S';
NET_NAME
'FM_APML_MUX2_SEL_R'
 '@T6G_MB_LIB.T6G(SCH_1):FM_APML_MUX2_SEL_R':
 C_SIGNAL='@t6g_mb_lib.t6g(sch_1):fm_apml_mux2_sel_r';
NODE_NAME     U18 P5
 '@T6G_MB_LIB.T6G(SCH_1):PAGE81_I143@PURE_QUANTA.LCMXO3LF9400C5BG484C(CHIPS)':
 'PL21C': CDS_PINID='PL21C';
NODE_NAME     R133 2
 '@T6G_MB_LIB.T6G(SCH_1):PAGE81_I169@PURE_QUANTA.Q_RES(CHIPS)':
 'B': CDS_PINID='B';
NET_NAME
'FM_BIOS_POST_CMPLT_BUF_N'
 '@T6G_MB_LIB.T6G(SCH_1):FM_BIOS_POST_CMPLT_BUF_N':
 C_SIGNAL='@t6g_mb_lib.t6g(sch_1):fm_bios_post_cmplt_buf_n';
NODE_NAME     R937 2
 '@T6G_MB_LIB.T6G(SCH_1):PAGE80_I166@PURE_QUANTA.Q_RES(CHIPS)':
 'B': CDS_PINID='B';
NODE_NAME     C5000 1
 '@T6G_MB_LIB.T6G(SCH_1):PAGE34_I124@PURE_QUANTA.Q_CAP(CHIPS)':
 'A': CDS_PINID='A';
NODE_NAME     R6100 2
 '@T6G_MB_LIB.T6G(SCH_1):PAGE34_I125@PURE_QUANTA.Q_RES(CHIPS)':
 'B': CDS_PINID='B';
NET_NAME
'FM_BIOS_POST_CMPLT_BUF_R1_N'
 '@T6G_MB_LIB.T6G(SCH_1):FM_BIOS_POST_CMPLT_BUF_R1_N':
 C_SIGNAL='@t6g_mb_lib.t6g(sch_1):fm_bios_post_cmplt_buf_r1_n';
NODE_NAME     R943 2
 '@T6G_MB_LIB.T6G(SCH_1):PAGE34_I53@PURE_QUANTA.Q_RES(CHIPS)':
 'B': CDS_PINID='B';
NODE_NAME     U101 4
 '@T6G_MB_LIB.T6G(SCH_1):PAGE34_I55@PURE_QUANTA.SN74LVC1G07DBVR(CHIPS)':
 'Y': CDS_PINID='Y';
NODE_NAME     R6100 1
 '@T6G_MB_LIB.T6G(SCH_1):PAGE34_I125@PURE_QUANTA.Q_RES(CHIPS)':
 'A': CDS_PINID='A';
NET_NAME
'FM_BIOS_POST_CMPLT_BUF_R_N'
 '@T6G_MB_LIB.T6G(SCH_1):FM_BIOS_POST_CMPLT_BUF_R_N':
 C_SIGNAL='@t6g_mb_lib.t6g(sch_1):fm_bios_post_cmplt_buf_r_n';
NODE_NAME     R937 1
 '@T6G_MB_LIB.T6G(SCH_1):PAGE80_I166@PURE_QUANTA.Q_RES(CHIPS)':
 'A': CDS_PINID='A';
NODE_NAME     U18 U21
 '@T6G_MB_LIB.T6G(SCH_1):PAGE80_I217@PURE_QUANTA.LCMXO3LF9400C5BG484C(CHIPS)':
 'PR24D': CDS_PINID='PR24D';
NET_NAME
'FM_BIOS_POST_CMPLT_N'
 '@T6G_MB_LIB.T6G(SCH_1):FM_BIOS_POST_CMPLT_N':
 C_SIGNAL='@t6g_mb_lib.t6g(sch_1):fm_bios_post_cmplt_n';
NODE_NAME     U101 2
 '@T6G_MB_LIB.T6G(SCH_1):PAGE34_I55@PURE_QUANTA.SN74LVC1G07DBVR(CHIPS)':
 'A': CDS_PINID='A';
NODE_NAME     R942 2
 '@T6G_MB_LIB.T6G(SCH_1):PAGE34_I60@PURE_QUANTA.Q_RES(CHIPS)':
 'B': CDS_PINID='B';
NODE_NAME     R934 1
 '@T6G_MB_LIB.T6G(SCH_1):PAGE143_I33@PURE_QUANTA.Q_RES(CHIPS)':
 'A': CDS_PINID='A';
NODE_NAME     R939 2
 '@T6G_MB_LIB.T6G(SCH_1):PAGE28_I93@PURE_QUANTA.Q_RES(CHIPS)':
 'B': CDS_PINID='B';
NET_NAME
'FM_BIOS_POST_CMPLT_R_N'
 '@T6G_MB_LIB.T6G(SCH_1):FM_BIOS_POST_CMPLT_R_N':
 C_SIGNAL='@t6g_mb_lib.t6g(sch_1):fm_bios_post_cmplt_r_n';
NODE_NAME     R939 1
 '@T6G_MB_LIB.T6G(SCH_1):PAGE28_I93@PURE_QUANTA.Q_RES(CHIPS)':
 'A': CDS_PINID='A';
NODE_NAME     U25 DJ29
 '@T6G_MB_LIB.T6G(SCH_1):PAGE28_I188@PURE_QUANTA.GENOA_SP5(CHIPS)':
 'AGPIO88': CDS_PINID='AGPIO88';
NET_NAME
'FM_BIOS_USB_RECOVERY'
 '@T6G_MB_LIB.T6G(SCH_1):FM_BIOS_USB_RECOVERY':
 C_SIGNAL='@t6g_mb_lib.t6g(sch_1):fm_bios_usb_recovery';
NODE_NAME     R1204 2
 '@T6G_MB_LIB.T6G(SCH_1):PAGE27_I353@PURE_QUANTA.Q_RES(CHIPS)':
 'B': CDS_PINID='B';
NODE_NAME     R1265 1
 '@T6G_MB_LIB.T6G(SCH_1):PAGE144_I52@PURE_QUANTA.Q_RES(CHIPS)':
 'A': CDS_PINID='A';
NODE_NAME     U18 V22
 '@T6G_MB_LIB.T6G(SCH_1):PAGE80_I217@PURE_QUANTA.LCMXO3LF9400C5BG484C(CHIPS)':
 'PR25A': CDS_PINID='PR25A';
NODE_NAME     SW1 14
 '@T6G_MB_LIB.T6G(SCH_1):PAGE144_I90@PURE_QUANTA.SW20S_DHNF10FQTR(CHIPS)':
 '14': CDS_PINID='\14\';
NET_NAME
'FM_BIOS_USB_RECOVERY_R'
 '@T6G_MB_LIB.T6G(SCH_1):FM_BIOS_USB_RECOVERY_R':
 C_SIGNAL='@t6g_mb_lib.t6g(sch_1):fm_bios_usb_recovery_r';
NODE_NAME     U25 DJ33
 '@T6G_MB_LIB.T6G(SCH_1):PAGE27_I227@PURE_QUANTA.GENOA_SP5(CHIPS)':
 'UART0_CTS_L||UART2_TXD||AGPIO135': CDS_PINID='\uart0_cts_l||uart2_txd||agpio135\';
NODE_NAME     R1204 1
 '@T6G_MB_LIB.T6G(SCH_1):PAGE27_I353@PURE_QUANTA.Q_RES(CHIPS)':
 'A': CDS_PINID='A';
NET_NAME
'FM_BMC_READY_N'
 '@T6G_MB_LIB.T6G(SCH_1):FM_BMC_READY_N':
 C_SIGNAL='@t6g_mb_lib.t6g(sch_1):fm_bmc_ready_n';
NODE_NAME     U26 DE40
 '@T6G_MB_LIB.T6G(SCH_1):PAGE55_I182@PURE_QUANTA.GENOA_SP5(CHIPS)':
 'AGPIO6||DEVSLP1||SATA_ZP1_L': CDS_PINID='\agpio6||devslp1||sata_zp1_l\';
NODE_NAME     R188 1
 '@T6G_MB_LIB.T6G(SCH_1):PAGE81_I61@PURE_QUANTA.Q_RES(CHIPS)':
 'A': CDS_PINID='A';
NODE_NAME     R5031 2
 '@T6G_MB_LIB.T6G(SCH_1):PAGE55_I331@PURE_QUANTA.Q_RES(CHIPS)':
 'B': CDS_PINID='B';
NODE_NAME     R545 1
 '@T6G_MB_LIB.T6G(SCH_1):PAGE55_I337@PURE_QUANTA.Q_RES(CHIPS)':
 'A': CDS_PINID='A';
NET_NAME
'FM_BMC_READY_R_N'
 '@T6G_MB_LIB.T6G(SCH_1):FM_BMC_READY_R_N':
 C_SIGNAL='@t6g_mb_lib.t6g(sch_1):fm_bmc_ready_r_n';
NODE_NAME     R188 2
 '@T6G_MB_LIB.T6G(SCH_1):PAGE81_I61@PURE_QUANTA.Q_RES(CHIPS)':
 'B': CDS_PINID='B';
NODE_NAME     U18 F4
 '@T6G_MB_LIB.T6G(SCH_1):PAGE81_I143@PURE_QUANTA.LCMXO3LF9400C5BG484C(CHIPS)':
 'PL5D': CDS_PINID='PL5D';
NET_NAME
'FM_BMC_TPM_PRES_N'
 '@T6G_MB_LIB.T6G(SCH_1):FM_BMC_TPM_PRES_N':
 C_SIGNAL='@t6g_mb_lib.t6g(sch_1):fm_bmc_tpm_pres_n';
NODE_NAME     U26 DH16
 '@T6G_MB_LIB.T6G(SCH_1):PAGE55_I182@PURE_QUANTA.GENOA_SP5(CHIPS)':
 'AGPIO115||CLK_REQ11_L': CDS_PINID='\agpio115||clk_req11_l\';
NODE_NAME     R189 1
 '@T6G_MB_LIB.T6G(SCH_1):PAGE81_I58@PURE_QUANTA.Q_RES(CHIPS)':
 'A': CDS_PINID='A';
NODE_NAME     R5030 2
 '@T6G_MB_LIB.T6G(SCH_1):PAGE55_I334@PURE_QUANTA.Q_RES(CHIPS)':
 'B': CDS_PINID='B';
NODE_NAME     R546 1
 '@T6G_MB_LIB.T6G(SCH_1):PAGE55_I338@PURE_QUANTA.Q_RES(CHIPS)':
 'A': CDS_PINID='A';
NET_NAME
'FM_BMC_TPM_PRES_N_R'
 '@T6G_MB_LIB.T6G(SCH_1):FM_BMC_TPM_PRES_N_R':
 C_SIGNAL='@t6g_mb_lib.t6g(sch_1):fm_bmc_tpm_pres_n_r';
NODE_NAME     R189 2
 '@T6G_MB_LIB.T6G(SCH_1):PAGE81_I58@PURE_QUANTA.Q_RES(CHIPS)':
 'B': CDS_PINID='B';
NODE_NAME     U18 E1
 '@T6G_MB_LIB.T6G(SCH_1):PAGE81_I143@PURE_QUANTA.LCMXO3LF9400C5BG484C(CHIPS)':
 'PL6A': CDS_PINID='PL6A';
NET_NAME
'FM_BOARD_BMC_SKU_ID0'
 '@T6G_MB_LIB.T6G(SCH_1):FM_BOARD_BMC_SKU_ID0':
 C_SIGNAL='@t6g_mb_lib.t6g(sch_1):fm_board_bmc_sku_id0';
NODE_NAME     R6145 1
 '@T6G_MB_LIB.T6G(SCH_1):PAGE83_I54@PURE_QUANTA.Q_RES(CHIPS)':
 'A': CDS_PINID='A';
NODE_NAME     U18 C5
 '@T6G_MB_LIB.T6G(SCH_1):PAGE79_I94@PURE_QUANTA.LCMXO3LF9400C5BG484C(CHIPS)':
 'PT12D': CDS_PINID='PT12D';
NODE_NAME     R6140 2
 '@T6G_MB_LIB.T6G(SCH_1):PAGE83_I56@PURE_QUANTA.Q_RES(CHIPS)':
 'B': CDS_PINID='B';
NET_NAME
'FM_BOARD_BMC_SKU_ID1'
 '@T6G_MB_LIB.T6G(SCH_1):FM_BOARD_BMC_SKU_ID1':
 C_SIGNAL='@t6g_mb_lib.t6g(sch_1):fm_board_bmc_sku_id1';
NODE_NAME     U18 G9
 '@T6G_MB_LIB.T6G(SCH_1):PAGE79_I94@PURE_QUANTA.LCMXO3LF9400C5BG484C(CHIPS)':
 'PT21D': CDS_PINID='PT21D';
NODE_NAME     R6144 1
 '@T6G_MB_LIB.T6G(SCH_1):PAGE83_I52@PURE_QUANTA.Q_RES(CHIPS)':
 'A': CDS_PINID='A';
NODE_NAME     R6139 2
 '@T6G_MB_LIB.T6G(SCH_1):PAGE83_I55@PURE_QUANTA.Q_RES(CHIPS)':
 'B': CDS_PINID='B';
NET_NAME
'FM_BOARD_BMC_SKU_ID2'
 '@T6G_MB_LIB.T6G(SCH_1):FM_BOARD_BMC_SKU_ID2':
 C_SIGNAL='@t6g_mb_lib.t6g(sch_1):fm_board_bmc_sku_id2';
NODE_NAME     U18 F10
 '@T6G_MB_LIB.T6G(SCH_1):PAGE79_I94@PURE_QUANTA.LCMXO3LF9400C5BG484C(CHIPS)':
 'PT22A': CDS_PINID='PT22A';
NODE_NAME     R6143 1
 '@T6G_MB_LIB.T6G(SCH_1):PAGE83_I36@PURE_QUANTA.Q_RES(CHIPS)':
 'A': CDS_PINID='A';
NODE_NAME     R6138 2
 '@T6G_MB_LIB.T6G(SCH_1):PAGE83_I39@PURE_QUANTA.Q_RES(CHIPS)':
 'B': CDS_PINID='B';
NET_NAME
'FM_BOARD_BMC_SKU_ID3'
 '@T6G_MB_LIB.T6G(SCH_1):FM_BOARD_BMC_SKU_ID3':
 C_SIGNAL='@t6g_mb_lib.t6g(sch_1):fm_board_bmc_sku_id3';
NODE_NAME     U18 B11
 '@T6G_MB_LIB.T6G(SCH_1):PAGE79_I94@PURE_QUANTA.LCMXO3LF9400C5BG484C(CHIPS)':
 'PT24A': CDS_PINID='PT24A';
NODE_NAME     R6137 2
 '@T6G_MB_LIB.T6G(SCH_1):PAGE83_I121@PURE_QUANTA.Q_RES(CHIPS)':
 'B': CDS_PINID='B';
NODE_NAME     R6142 1
 '@T6G_MB_LIB.T6G(SCH_1):PAGE83_I122@PURE_QUANTA.Q_RES(CHIPS)':
 'A': CDS_PINID='A';
NET_NAME
'FM_BOARD_BMC_SKU_ID4'
 '@T6G_MB_LIB.T6G(SCH_1):FM_BOARD_BMC_SKU_ID4':
 C_SIGNAL='@t6g_mb_lib.t6g(sch_1):fm_board_bmc_sku_id4';
NODE_NAME     U18 A11
 '@T6G_MB_LIB.T6G(SCH_1):PAGE79_I94@PURE_QUANTA.LCMXO3LF9400C5BG484C(CHIPS)':
 'PT24B': CDS_PINID='PT24B';
NODE_NAME     R6136 2
 '@T6G_MB_LIB.T6G(SCH_1):PAGE83_I117@PURE_QUANTA.Q_RES(CHIPS)':
 'B': CDS_PINID='B';
NODE_NAME     R6141 1
 '@T6G_MB_LIB.T6G(SCH_1):PAGE83_I118@PURE_QUANTA.Q_RES(CHIPS)':
 'A': CDS_PINID='A';
NET_NAME
'FM_BOARD_SKU_ID0'
 '@T6G_MB_LIB.T6G(SCH_1):FM_BOARD_SKU_ID0':
 C_SIGNAL='@t6g_mb_lib.t6g(sch_1):fm_board_sku_id0';
NODE_NAME     U25 DF33
 '@T6G_MB_LIB.T6G(SCH_1):PAGE28_I188@PURE_QUANTA.GENOA_SP5(CHIPS)':
 'AGPIO21': CDS_PINID='AGPIO21';
NODE_NAME     R6129 1
 '@T6G_MB_LIB.T6G(SCH_1):PAGE83_I65@PURE_QUANTA.Q_RES(CHIPS)':
 'A': CDS_PINID='A';
NODE_NAME     R6124 2
 '@T6G_MB_LIB.T6G(SCH_1):PAGE83_I72@PURE_QUANTA.Q_RES(CHIPS)':
 'B': CDS_PINID='B';
NET_NAME
'FM_BOARD_SKU_ID1'
 '@T6G_MB_LIB.T6G(SCH_1):FM_BOARD_SKU_ID1':
 C_SIGNAL='@t6g_mb_lib.t6g(sch_1):fm_board_sku_id1';
NODE_NAME     U25 DE32
 '@T6G_MB_LIB.T6G(SCH_1):PAGE28_I188@PURE_QUANTA.GENOA_SP5(CHIPS)':
 'AGPIO22': CDS_PINID='AGPIO22';
NODE_NAME     R6128 1
 '@T6G_MB_LIB.T6G(SCH_1):PAGE83_I64@PURE_QUANTA.Q_RES(CHIPS)':
 'A': CDS_PINID='A';
NODE_NAME     R6123 2
 '@T6G_MB_LIB.T6G(SCH_1):PAGE83_I71@PURE_QUANTA.Q_RES(CHIPS)':
 'B': CDS_PINID='B';
NET_NAME
'FM_BOARD_SKU_ID2'
 '@T6G_MB_LIB.T6G(SCH_1):FM_BOARD_SKU_ID2':
 C_SIGNAL='@t6g_mb_lib.t6g(sch_1):fm_board_sku_id2';
NODE_NAME     R6122 2
 '@T6G_MB_LIB.T6G(SCH_1):PAGE83_I50@PURE_QUANTA.Q_RES(CHIPS)':
 'B': CDS_PINID='B';
NODE_NAME     U25 DF31
 '@T6G_MB_LIB.T6G(SCH_1):PAGE28_I188@PURE_QUANTA.GENOA_SP5(CHIPS)':
 'AGPIO106': CDS_PINID='AGPIO106';
NODE_NAME     R6127 1
 '@T6G_MB_LIB.T6G(SCH_1):PAGE83_I46@PURE_QUANTA.Q_RES(CHIPS)':
 'A': CDS_PINID='A';
NET_NAME
'FM_BOARD_SKU_ID3'
 '@T6G_MB_LIB.T6G(SCH_1):FM_BOARD_SKU_ID3':
 C_SIGNAL='@t6g_mb_lib.t6g(sch_1):fm_board_sku_id3';
NODE_NAME     U25 DG31
 '@T6G_MB_LIB.T6G(SCH_1):PAGE28_I188@PURE_QUANTA.GENOA_SP5(CHIPS)':
 'AGPIO107': CDS_PINID='AGPIO107';
NODE_NAME     R6126 1
 '@T6G_MB_LIB.T6G(SCH_1):PAGE83_I119@PURE_QUANTA.Q_RES(CHIPS)':
 'A': CDS_PINID='A';
NODE_NAME     R6121 2
 '@T6G_MB_LIB.T6G(SCH_1):PAGE83_I120@PURE_QUANTA.Q_RES(CHIPS)':
 'B': CDS_PINID='B';
NET_NAME
'FM_BOARD_SKU_ID4'
 '@T6G_MB_LIB.T6G(SCH_1):FM_BOARD_SKU_ID4':
 C_SIGNAL='@t6g_mb_lib.t6g(sch_1):fm_board_sku_id4';
NODE_NAME     U25 DH4
 '@T6G_MB_LIB.T6G(SCH_1):PAGE28_I188@PURE_QUANTA.GENOA_SP5(CHIPS)':
 'AGPIO7': CDS_PINID='AGPIO7';
NODE_NAME     R6120 2
 '@T6G_MB_LIB.T6G(SCH_1):PAGE83_I115@PURE_QUANTA.Q_RES(CHIPS)':
 'B': CDS_PINID='B';
NODE_NAME     R6125 1
 '@T6G_MB_LIB.T6G(SCH_1):PAGE83_I116@PURE_QUANTA.Q_RES(CHIPS)':
 'A': CDS_PINID='A';
NET_NAME
'FM_CLKREQ_M2_1_N'
 '@T6G_MB_LIB.T6G(SCH_1):FM_CLKREQ_M2_1_N':
 C_SIGNAL='@t6g_mb_lib.t6g(sch_1):fm_clkreq_m2_1_n';
NODE_NAME     U18 N2
 '@T6G_MB_LIB.T6G(SCH_1):PAGE81_I143@PURE_QUANTA.LCMXO3LF9400C5BG484C(CHIPS)':
 'PL18A': CDS_PINID='PL18A';
NODE_NAME     R6053 2
 '@T6G_MB_LIB.T6G(SCH_1):PAGE81_I85@PURE_QUANTA.Q_RES(CHIPS)':
 'B': CDS_PINID='B';
NET_NAME
'FM_CLR_CMOS'
 '@T6G_MB_LIB.T6G(SCH_1):FM_CLR_CMOS':
 C_SIGNAL='@t6g_mb_lib.t6g(sch_1):fm_clr_cmos';
NODE_NAME     U18 N3
 '@T6G_MB_LIB.T6G(SCH_1):PAGE81_I143@PURE_QUANTA.LCMXO3LF9400C5BG484C(CHIPS)':
 'PL18C': CDS_PINID='PL18C';
NODE_NAME     R275 2
 '@T6G_MB_LIB.T6G(SCH_1):PAGE81_I84@PURE_QUANTA.Q_RES(CHIPS)':
 'B': CDS_PINID='B';
NET_NAME
'FM_CPU0_CORETYPE0'
 '@T6G_MB_LIB.T6G(SCH_1):FM_CPU0_CORETYPE0':
 C_SIGNAL='@t6g_mb_lib.t6g(sch_1):fm_cpu0_coretype0';
NODE_NAME     R183 2
 '@T6G_MB_LIB.T6G(SCH_1):PAGE81_I82@PURE_QUANTA.Q_RES(CHIPS)':
 'B': CDS_PINID='B';
NODE_NAME     U18 R1
 '@T6G_MB_LIB.T6G(SCH_1):PAGE81_I143@PURE_QUANTA.LCMXO3LF9400C5BG484C(CHIPS)':
 'PL19B': CDS_PINID='PL19B';
NET_NAME
'FM_CPU0_CORETYPE1'
 '@T6G_MB_LIB.T6G(SCH_1):FM_CPU0_CORETYPE1':
 C_SIGNAL='@t6g_mb_lib.t6g(sch_1):fm_cpu0_coretype1';
NODE_NAME     R184 2
 '@T6G_MB_LIB.T6G(SCH_1):PAGE81_I48@PURE_QUANTA.Q_RES(CHIPS)':
 'B': CDS_PINID='B';
NODE_NAME     U18 R2
 '@T6G_MB_LIB.T6G(SCH_1):PAGE81_I143@PURE_QUANTA.LCMXO3LF9400C5BG484C(CHIPS)':
 'PL21A': CDS_PINID='PL21A';
NET_NAME
'FM_CPU0_CORETYPE2'
 '@T6G_MB_LIB.T6G(SCH_1):FM_CPU0_CORETYPE2':
 C_SIGNAL='@t6g_mb_lib.t6g(sch_1):fm_cpu0_coretype2';
NODE_NAME     R185 2
 '@T6G_MB_LIB.T6G(SCH_1):PAGE81_I80@PURE_QUANTA.Q_RES(CHIPS)':
 'B': CDS_PINID='B';
NODE_NAME     U18 P3
 '@T6G_MB_LIB.T6G(SCH_1):PAGE81_I143@PURE_QUANTA.LCMXO3LF9400C5BG484C(CHIPS)':
 'PL19C': CDS_PINID='PL19C';
NET_NAME
'FM_CPU0_FORCE_SELFREFRESH'
 '@T6G_MB_LIB.T6G(SCH_1):FM_CPU0_FORCE_SELFREFRESH':
 C_SIGNAL='@t6g_mb_lib.t6g(sch_1):fm_cpu0_force_selfrefresh';
NODE_NAME     R186 1
 '@T6G_MB_LIB.T6G(SCH_1):PAGE80_I129@PURE_QUANTA.Q_RES(CHIPS)':
 'A': CDS_PINID='A';
NODE_NAME     U18 U17
 '@T6G_MB_LIB.T6G(SCH_1):PAGE80_I217@PURE_QUANTA.LCMXO3LF9400C5BG484C(CHIPS)':
 'PR29C': CDS_PINID='PR29C';
NET_NAME
'FM_CPU0_HDT_CONN_TESTEN'
 '@T6G_MB_LIB.T6G(SCH_1):FM_CPU0_HDT_CONN_TESTEN':
 C_SIGNAL='@t6g_mb_lib.t6g(sch_1):fm_cpu0_hdt_conn_testen';
NODE_NAME     R258 1
 '@T6G_MB_LIB.T6G(SCH_1):PAGE80_I177@PURE_QUANTA.Q_RES(CHIPS)':
 'A': CDS_PINID='A';
NODE_NAME     U18 P21
 '@T6G_MB_LIB.T6G(SCH_1):PAGE80_I217@PURE_QUANTA.LCMXO3LF9400C5BG484C(CHIPS)':
 'PR19B': CDS_PINID='PR19B';
NET_NAME
'FM_CPU0_NMI_SYNC_FLOOD_N'
 '@T6G_MB_LIB.T6G(SCH_1):FM_CPU0_NMI_SYNC_FLOOD_N':
 C_SIGNAL='@t6g_mb_lib.t6g(sch_1):fm_cpu0_nmi_sync_flood_n';
NODE_NAME     R219 2
 '@T6G_MB_LIB.T6G(SCH_1):PAGE80_I108@PURE_QUANTA.Q_RES(CHIPS)':
 'B': CDS_PINID='B';
NODE_NAME     U18 J16
 '@T6G_MB_LIB.T6G(SCH_1):PAGE80_I217@PURE_QUANTA.LCMXO3LF9400C5BG484C(CHIPS)':
 'PR11A': CDS_PINID='PR11A';
NET_NAME
'FM_CPU0_NV_SAVE_N'
 '@T6G_MB_LIB.T6G(SCH_1):FM_CPU0_NV_SAVE_N':
 C_SIGNAL='@t6g_mb_lib.t6g(sch_1):fm_cpu0_nv_save_n';
NODE_NAME     R253 2
 '@T6G_MB_LIB.T6G(SCH_1):PAGE80_I116@PURE_QUANTA.Q_RES(CHIPS)':
 'B': CDS_PINID='B';
NODE_NAME     U18 G20
 '@T6G_MB_LIB.T6G(SCH_1):PAGE80_I217@PURE_QUANTA.LCMXO3LF9400C5BG484C(CHIPS)':
 'PR6B': CDS_PINID='PR6B';
NET_NAME
'FM_CPU0_PROCHOT_R_N'
 '@T6G_MB_LIB.T6G(SCH_1):FM_CPU0_PROCHOT_R_N':
 C_SIGNAL='@t6g_mb_lib.t6g(sch_1):fm_cpu0_prochot_r_n';
NODE_NAME     U18 J6
 '@T6G_MB_LIB.T6G(SCH_1):PAGE81_I143@PURE_QUANTA.LCMXO3LF9400C5BG484C(CHIPS)':
 'PL10D': CDS_PINID='PL10D';
NODE_NAME     R179 1
 '@T6G_MB_LIB.T6G(SCH_1):PAGE81_I110@PURE_QUANTA.Q_RES(CHIPS)':
 'A': CDS_PINID='A';
NET_NAME
'FM_CPU0_PWR_BTN_N'
 '@T6G_MB_LIB.T6G(SCH_1):FM_CPU0_PWR_BTN_N':
 C_SIGNAL='@t6g_mb_lib.t6g(sch_1):fm_cpu0_pwr_btn_n';
NODE_NAME     R215 2
 '@T6G_MB_LIB.T6G(SCH_1):PAGE80_I104@PURE_QUANTA.Q_RES(CHIPS)':
 'B': CDS_PINID='B';
NODE_NAME     U18 J22
 '@T6G_MB_LIB.T6G(SCH_1):PAGE80_I217@PURE_QUANTA.LCMXO3LF9400C5BG484C(CHIPS)':
 'PR12B': CDS_PINID='PR12B';
NET_NAME
'FM_CPU0_PWR_GOOD'
 '@T6G_MB_LIB.T6G(SCH_1):FM_CPU0_PWR_GOOD':
 C_SIGNAL='@t6g_mb_lib.t6g(sch_1):fm_cpu0_pwr_good';
NODE_NAME     R218 2
 '@T6G_MB_LIB.T6G(SCH_1):PAGE80_I32@PURE_QUANTA.Q_RES(CHIPS)':
 'B': CDS_PINID='B';
NODE_NAME     U18 W9
 '@T6G_MB_LIB.T6G(SCH_1):PAGE80_I216@PURE_QUANTA.LCMXO3LF9400C5BG484C(CHIPS)':
 'PB18D': CDS_PINID='PB18D';
NET_NAME
'FM_CPU0_RSMRST_N'
 '@T6G_MB_LIB.T6G(SCH_1):FM_CPU0_RSMRST_N':
 C_SIGNAL='@t6g_mb_lib.t6g(sch_1):fm_cpu0_rsmrst_n';
NODE_NAME     R217 2
 '@T6G_MB_LIB.T6G(SCH_1):PAGE80_I118@PURE_QUANTA.Q_RES(CHIPS)':
 'B': CDS_PINID='B';
NODE_NAME     U18 G22
 '@T6G_MB_LIB.T6G(SCH_1):PAGE80_I217@PURE_QUANTA.LCMXO3LF9400C5BG484C(CHIPS)':
 'PR5B': CDS_PINID='PR5B';
NET_NAME
'FM_CPU0_SA0'
 '@T6G_MB_LIB.T6G(SCH_1):FM_CPU0_SA0':
 C_SIGNAL='@t6g_mb_lib.t6g(sch_1):fm_cpu0_sa0';
NODE_NAME     U18 H5
 '@T6G_MB_LIB.T6G(SCH_1):PAGE81_I143@PURE_QUANTA.LCMXO3LF9400C5BG484C(CHIPS)':
 'PL11A': CDS_PINID='PL11A';
NODE_NAME     R220 1
 '@T6G_MB_LIB.T6G(SCH_1):PAGE81_I109@PURE_QUANTA.Q_RES(CHIPS)':
 'A': CDS_PINID='A';
NET_NAME
'FM_CPU0_SA1'
 '@T6G_MB_LIB.T6G(SCH_1):FM_CPU0_SA1':
 C_SIGNAL='@t6g_mb_lib.t6g(sch_1):fm_cpu0_sa1';
NODE_NAME     U18 J2
 '@T6G_MB_LIB.T6G(SCH_1):PAGE81_I143@PURE_QUANTA.LCMXO3LF9400C5BG484C(CHIPS)':
 'PL12A': CDS_PINID='PL12A';
NODE_NAME     R221 1
 '@T6G_MB_LIB.T6G(SCH_1):PAGE81_I107@PURE_QUANTA.Q_RES(CHIPS)':
 'A': CDS_PINID='A';
NET_NAME
'FM_CPU0_SLP_S3_N'
 '@T6G_MB_LIB.T6G(SCH_1):FM_CPU0_SLP_S3_N':
 C_SIGNAL='@t6g_mb_lib.t6g(sch_1):fm_cpu0_slp_s3_n';
NODE_NAME     U18 C22
 '@T6G_MB_LIB.T6G(SCH_1):PAGE80_I217@PURE_QUANTA.LCMXO3LF9400C5BG484C(CHIPS)':
 'PR2B||R_GPLLC_FB': CDS_PINID='\pr2b||r_gpllc_fb\';
NODE_NAME     R249 1
 '@T6G_MB_LIB.T6G(SCH_1):PAGE28_I135@PURE_QUANTA.Q_RES(CHIPS)':
 'A': CDS_PINID='A';
NET_NAME
'FM_CPU0_SLP_S5_N'
 '@T6G_MB_LIB.T6G(SCH_1):FM_CPU0_SLP_S5_N':
 C_SIGNAL='@t6g_mb_lib.t6g(sch_1):fm_cpu0_slp_s5_n';
NODE_NAME     R248 1
 '@T6G_MB_LIB.T6G(SCH_1):PAGE28_I136@PURE_QUANTA.Q_RES(CHIPS)':
 'A': CDS_PINID='A';
NODE_NAME     U18 C21
 '@T6G_MB_LIB.T6G(SCH_1):PAGE80_I217@PURE_QUANTA.LCMXO3LF9400C5BG484C(CHIPS)':
 'PR2A||R_GPLLT_FB': CDS_PINID='\pr2a||r_gpllt_fb\';
NET_NAME
'FM_CPU0_SMERR_N'
 '@T6G_MB_LIB.T6G(SCH_1):FM_CPU0_SMERR_N':
 C_SIGNAL='@t6g_mb_lib.t6g(sch_1):fm_cpu0_smerr_n';
NODE_NAME     R250 1
 '@T6G_MB_LIB.T6G(SCH_1):PAGE80_I180@PURE_QUANTA.Q_RES(CHIPS)':
 'A': CDS_PINID='A';
NODE_NAME     U18 M21
 '@T6G_MB_LIB.T6G(SCH_1):PAGE80_I217@PURE_QUANTA.LCMXO3LF9400C5BG484C(CHIPS)':
 'PR17B||PCLKC1_0': CDS_PINID='\pr17b||pclkc1_0\';
NET_NAME
'FM_CPU0_SP5R1'
 '@T6G_MB_LIB.T6G(SCH_1):FM_CPU0_SP5R1':
 C_SIGNAL='@t6g_mb_lib.t6g(sch_1):fm_cpu0_sp5r1';
NODE_NAME     R180 2
 '@T6G_MB_LIB.T6G(SCH_1):PAGE81_I45@PURE_QUANTA.Q_RES(CHIPS)':
 'B': CDS_PINID='B';
NODE_NAME     U18 N5
 '@T6G_MB_LIB.T6G(SCH_1):PAGE81_I143@PURE_QUANTA.LCMXO3LF9400C5BG484C(CHIPS)':
 'PL20B': CDS_PINID='PL20B';
NET_NAME
'FM_CPU0_SP5R2'
 '@T6G_MB_LIB.T6G(SCH_1):FM_CPU0_SP5R2':
 C_SIGNAL='@t6g_mb_lib.t6g(sch_1):fm_cpu0_sp5r2';
NODE_NAME     R181 2
 '@T6G_MB_LIB.T6G(SCH_1):PAGE81_I46@PURE_QUANTA.Q_RES(CHIPS)':
 'B': CDS_PINID='B';
NODE_NAME     U18 N6
 '@T6G_MB_LIB.T6G(SCH_1):PAGE81_I143@PURE_QUANTA.LCMXO3LF9400C5BG484C(CHIPS)':
 'PL20C': CDS_PINID='PL20C';
NET_NAME
'FM_CPU0_SP5R3'
 '@T6G_MB_LIB.T6G(SCH_1):FM_CPU0_SP5R3':
 C_SIGNAL='@t6g_mb_lib.t6g(sch_1):fm_cpu0_sp5r3';
NODE_NAME     R222 2
 '@T6G_MB_LIB.T6G(SCH_1):PAGE81_I52@PURE_QUANTA.Q_RES(CHIPS)':
 'B': CDS_PINID='B';
NODE_NAME     U18 U1
 '@T6G_MB_LIB.T6G(SCH_1):PAGE81_I143@PURE_QUANTA.LCMXO3LF9400C5BG484C(CHIPS)':
 'PL25B': CDS_PINID='PL25B';
NET_NAME
'FM_CPU0_SP5R4'
 '@T6G_MB_LIB.T6G(SCH_1):FM_CPU0_SP5R4':
 C_SIGNAL='@t6g_mb_lib.t6g(sch_1):fm_cpu0_sp5r4';
NODE_NAME     R223 1
 '@T6G_MB_LIB.T6G(SCH_1):PAGE81_I100@PURE_QUANTA.Q_RES(CHIPS)':
 'A': CDS_PINID='A';
NODE_NAME     U18 U2
 '@T6G_MB_LIB.T6G(SCH_1):PAGE81_I143@PURE_QUANTA.LCMXO3LF9400C5BG484C(CHIPS)':
 'PL27A||PCLKT3_0': CDS_PINID='\pl27a||pclkt3_0\';
NET_NAME
'FM_CPU0_SYS_RESET_N'
 '@T6G_MB_LIB.T6G(SCH_1):FM_CPU0_SYS_RESET_N':
 C_SIGNAL='@t6g_mb_lib.t6g(sch_1):fm_cpu0_sys_reset_n';
NODE_NAME     R216 2
 '@T6G_MB_LIB.T6G(SCH_1):PAGE80_I117@PURE_QUANTA.Q_RES(CHIPS)':
 'B': CDS_PINID='B';
NODE_NAME     U18 F19
 '@T6G_MB_LIB.T6G(SCH_1):PAGE80_I217@PURE_QUANTA.LCMXO3LF9400C5BG484C(CHIPS)':
 'PR5D': CDS_PINID='PR5D';
NET_NAME
'FM_CPU0_XTRIG_L4'
 '@T6G_MB_LIB.T6G(SCH_1):FM_CPU0_XTRIG_L4':
 C_SIGNAL='@t6g_mb_lib.t6g(sch_1):fm_cpu0_xtrig_l4';
NODE_NAME     R236 2
 '@T6G_MB_LIB.T6G(SCH_1):PAGE81_I66@PURE_QUANTA.Q_RES(CHIPS)':
 'B': CDS_PINID='B';
NODE_NAME     U18 D2
 '@T6G_MB_LIB.T6G(SCH_1):PAGE81_I143@PURE_QUANTA.LCMXO3LF9400C5BG484C(CHIPS)':
 'PL4B||L_GPLLC_IN': CDS_PINID='\pl4b||l_gpllc_in\';
NET_NAME
'FM_CPU0_XTRIG_L5'
 '@T6G_MB_LIB.T6G(SCH_1):FM_CPU0_XTRIG_L5':
 C_SIGNAL='@t6g_mb_lib.t6g(sch_1):fm_cpu0_xtrig_l5';
NODE_NAME     R237 2
 '@T6G_MB_LIB.T6G(SCH_1):PAGE81_I69@PURE_QUANTA.Q_RES(CHIPS)':
 'B': CDS_PINID='B';
NODE_NAME     U18 C1
 '@T6G_MB_LIB.T6G(SCH_1):PAGE81_I143@PURE_QUANTA.LCMXO3LF9400C5BG484C(CHIPS)':
 'PL4A||L_GPLLT_IN': CDS_PINID='\pl4a||l_gpllt_in\';
NET_NAME
'FM_CPU0_XTRIG_L6'
 '@T6G_MB_LIB.T6G(SCH_1):FM_CPU0_XTRIG_L6':
 C_SIGNAL='@t6g_mb_lib.t6g(sch_1):fm_cpu0_xtrig_l6';
NODE_NAME     R238 2
 '@T6G_MB_LIB.T6G(SCH_1):PAGE81_I71@PURE_QUANTA.Q_RES(CHIPS)':
 'B': CDS_PINID='B';
NODE_NAME     U18 E4
 '@T6G_MB_LIB.T6G(SCH_1):PAGE81_I143@PURE_QUANTA.LCMXO3LF9400C5BG484C(CHIPS)':
 'PL3A||L_GPLLT_FB': CDS_PINID='\pl3a||l_gpllt_fb\';
NET_NAME
'FM_CPU0_XTRIG_L7'
 '@T6G_MB_LIB.T6G(SCH_1):FM_CPU0_XTRIG_L7':
 C_SIGNAL='@t6g_mb_lib.t6g(sch_1):fm_cpu0_xtrig_l7';
NODE_NAME     R239 2
 '@T6G_MB_LIB.T6G(SCH_1):PAGE81_I62@PURE_QUANTA.Q_RES(CHIPS)':
 'B': CDS_PINID='B';
NODE_NAME     U18 E3
 '@T6G_MB_LIB.T6G(SCH_1):PAGE81_I143@PURE_QUANTA.LCMXO3LF9400C5BG484C(CHIPS)':
 'PL5C': CDS_PINID='PL5C';
NET_NAME
'FM_CPU1_BMC_RST_N'
 '@T6G_MB_LIB.T6G(SCH_1):FM_CPU1_BMC_RST_N':
 C_SIGNAL='@t6g_mb_lib.t6g(sch_1):fm_cpu1_bmc_rst_n';
NODE_NAME     U26 DH15
 '@T6G_MB_LIB.T6G(SCH_1):PAGE55_I182@PURE_QUANTA.GENOA_SP5(CHIPS)':
 'AGPIO116||CLK_REQ12_L': CDS_PINID='\agpio116||clk_req12_l\';
NODE_NAME     R190 1
 '@T6G_MB_LIB.T6G(SCH_1):PAGE81_I64@PURE_QUANTA.Q_RES(CHIPS)':
 'A': CDS_PINID='A';
NODE_NAME     R547 1
 '@T6G_MB_LIB.T6G(SCH_1):PAGE55_I362@PURE_QUANTA.Q_RES(CHIPS)':
 'A': CDS_PINID='A';
NET_NAME
'FM_CPU1_BMC_RST_R_N'
 '@T6G_MB_LIB.T6G(SCH_1):FM_CPU1_BMC_RST_R_N':
 C_SIGNAL='@t6g_mb_lib.t6g(sch_1):fm_cpu1_bmc_rst_r_n';
NODE_NAME     R190 2
 '@T6G_MB_LIB.T6G(SCH_1):PAGE81_I64@PURE_QUANTA.Q_RES(CHIPS)':
 'B': CDS_PINID='B';
NODE_NAME     U18 E2
 '@T6G_MB_LIB.T6G(SCH_1):PAGE81_I143@PURE_QUANTA.LCMXO3LF9400C5BG484C(CHIPS)':
 'PL5B': CDS_PINID='PL5B';
NET_NAME
'FM_CPU1_CORETYPE0'
 '@T6G_MB_LIB.T6G(SCH_1):FM_CPU1_CORETYPE0':
 C_SIGNAL='@t6g_mb_lib.t6g(sch_1):fm_cpu1_coretype0';
NODE_NAME     R262 2
 '@T6G_MB_LIB.T6G(SCH_1):PAGE81_I44@PURE_QUANTA.Q_RES(CHIPS)':
 'B': CDS_PINID='B';
NODE_NAME     U18 P4
 '@T6G_MB_LIB.T6G(SCH_1):PAGE81_I143@PURE_QUANTA.LCMXO3LF9400C5BG484C(CHIPS)':
 'PL20A': CDS_PINID='PL20A';
NET_NAME
'FM_CPU1_CORETYPE1'
 '@T6G_MB_LIB.T6G(SCH_1):FM_CPU1_CORETYPE1':
 C_SIGNAL='@t6g_mb_lib.t6g(sch_1):fm_cpu1_coretype1';
NODE_NAME     R263 2
 '@T6G_MB_LIB.T6G(SCH_1):PAGE81_I47@PURE_QUANTA.Q_RES(CHIPS)':
 'B': CDS_PINID='B';
NODE_NAME     U18 T1
 '@T6G_MB_LIB.T6G(SCH_1):PAGE81_I143@PURE_QUANTA.LCMXO3LF9400C5BG484C(CHIPS)':
 'PL21B': CDS_PINID='PL21B';
NET_NAME
'FM_CPU1_CORETYPE2'
 '@T6G_MB_LIB.T6G(SCH_1):FM_CPU1_CORETYPE2':
 C_SIGNAL='@t6g_mb_lib.t6g(sch_1):fm_cpu1_coretype2';
NODE_NAME     R264 2
 '@T6G_MB_LIB.T6G(SCH_1):PAGE81_I53@PURE_QUANTA.Q_RES(CHIPS)':
 'B': CDS_PINID='B';
NODE_NAME     U18 T2
 '@T6G_MB_LIB.T6G(SCH_1):PAGE81_I143@PURE_QUANTA.LCMXO3LF9400C5BG484C(CHIPS)':
 'PL25A': CDS_PINID='PL25A';
NET_NAME
'FM_CPU1_FORCE_SELFREFRESH'
 '@T6G_MB_LIB.T6G(SCH_1):FM_CPU1_FORCE_SELFREFRESH':
 C_SIGNAL='@t6g_mb_lib.t6g(sch_1):fm_cpu1_force_selfrefresh';
NODE_NAME     R265 1
 '@T6G_MB_LIB.T6G(SCH_1):PAGE80_I126@PURE_QUANTA.Q_RES(CHIPS)':
 'A': CDS_PINID='A';
NODE_NAME     U18 W19
 '@T6G_MB_LIB.T6G(SCH_1):PAGE80_I217@PURE_QUANTA.LCMXO3LF9400C5BG484C(CHIPS)':
 'PR30C': CDS_PINID='PR30C';
NET_NAME
'FM_CPU1_NMI_SYNC_FLOOD_N'
 '@T6G_MB_LIB.T6G(SCH_1):FM_CPU1_NMI_SYNC_FLOOD_N':
 C_SIGNAL='@t6g_mb_lib.t6g(sch_1):fm_cpu1_nmi_sync_flood_n';
NODE_NAME     R277 1
 '@T6G_MB_LIB.T6G(SCH_1):PAGE80_I165@PURE_QUANTA.Q_RES(CHIPS)':
 'A': CDS_PINID='A';
NODE_NAME     U18 W22
 '@T6G_MB_LIB.T6G(SCH_1):PAGE80_I217@PURE_QUANTA.LCMXO3LF9400C5BG484C(CHIPS)':
 'PR25B': CDS_PINID='PR25B';
NET_NAME
'FM_CPU1_NV_SAVE_N'
 '@T6G_MB_LIB.T6G(SCH_1):FM_CPU1_NV_SAVE_N':
 C_SIGNAL='@t6g_mb_lib.t6g(sch_1):fm_cpu1_nv_save_n';
NODE_NAME     R196 2
 '@T6G_MB_LIB.T6G(SCH_1):PAGE80_I109@PURE_QUANTA.Q_RES(CHIPS)':
 'B': CDS_PINID='B';
NODE_NAME     U18 H18
 '@T6G_MB_LIB.T6G(SCH_1):PAGE80_I217@PURE_QUANTA.LCMXO3LF9400C5BG484C(CHIPS)':
 'PR10B': CDS_PINID='PR10B';
NET_NAME
'FM_CPU1_PROCHOT_R_N'
 '@T6G_MB_LIB.T6G(SCH_1):FM_CPU1_PROCHOT_R_N':
 C_SIGNAL='@t6g_mb_lib.t6g(sch_1):fm_cpu1_prochot_r_n';
NODE_NAME     U18 G1
 '@T6G_MB_LIB.T6G(SCH_1):PAGE81_I143@PURE_QUANTA.LCMXO3LF9400C5BG484C(CHIPS)':
 'PL7B||PCLKC5_0': CDS_PINID='\pl7b||pclkc5_0\';
NODE_NAME     R270 1
 '@T6G_MB_LIB.T6G(SCH_1):PAGE81_I112@PURE_QUANTA.Q_RES(CHIPS)':
 'A': CDS_PINID='A';
NET_NAME
'FM_CPU1_PWRGD_OUT'
 '@T6G_MB_LIB.T6G(SCH_1):FM_CPU1_PWRGD_OUT':
 C_SIGNAL='@t6g_mb_lib.t6g(sch_1):fm_cpu1_pwrgd_out';
NODE_NAME     U18 AA22
 '@T6G_MB_LIB.T6G(SCH_1):PAGE80_I217@PURE_QUANTA.LCMXO3LF9400C5BG484C(CHIPS)':
 'PR29A': CDS_PINID='PR29A';
NODE_NAME     R195 1
 '@T6G_MB_LIB.T6G(SCH_1):PAGE80_I303@PURE_QUANTA.Q_RES(CHIPS)':
 'A': CDS_PINID='A';
NET_NAME
'FM_CPU1_PWR_GD_IN'
 '@T6G_MB_LIB.T6G(SCH_1):FM_CPU1_PWR_GD_IN':
 C_SIGNAL='@t6g_mb_lib.t6g(sch_1):fm_cpu1_pwr_gd_in';
NODE_NAME     R252 1
 '@T6G_MB_LIB.T6G(SCH_1):PAGE80_I128@PURE_QUANTA.Q_RES(CHIPS)':
 'A': CDS_PINID='A';
NODE_NAME     U18 Y21
 '@T6G_MB_LIB.T6G(SCH_1):PAGE80_I217@PURE_QUANTA.LCMXO3LF9400C5BG484C(CHIPS)':
 'PR29B': CDS_PINID='PR29B';
NET_NAME
'FM_CPU1_RSMRST_N'
 '@T6G_MB_LIB.T6G(SCH_1):FM_CPU1_RSMRST_N':
 C_SIGNAL='@t6g_mb_lib.t6g(sch_1):fm_cpu1_rsmrst_n';
NODE_NAME     R273 2
 '@T6G_MB_LIB.T6G(SCH_1):PAGE80_I119@PURE_QUANTA.Q_RES(CHIPS)':
 'B': CDS_PINID='B';
NODE_NAME     U18 F22
 '@T6G_MB_LIB.T6G(SCH_1):PAGE80_I217@PURE_QUANTA.LCMXO3LF9400C5BG484C(CHIPS)':
 'PR5A': CDS_PINID='PR5A';
NET_NAME
'FM_CPU1_SA0'
 '@T6G_MB_LIB.T6G(SCH_1):FM_CPU1_SA0':
 C_SIGNAL='@t6g_mb_lib.t6g(sch_1):fm_cpu1_sa0';
NODE_NAME     U18 J7
 '@T6G_MB_LIB.T6G(SCH_1):PAGE81_I143@PURE_QUANTA.LCMXO3LF9400C5BG484C(CHIPS)':
 'PL10C': CDS_PINID='PL10C';
NODE_NAME     R266 1
 '@T6G_MB_LIB.T6G(SCH_1):PAGE81_I108@PURE_QUANTA.Q_RES(CHIPS)':
 'A': CDS_PINID='A';
NET_NAME
'FM_CPU1_SA1'
 '@T6G_MB_LIB.T6G(SCH_1):FM_CPU1_SA1':
 C_SIGNAL='@t6g_mb_lib.t6g(sch_1):fm_cpu1_sa1';
NODE_NAME     R267 2
 '@T6G_MB_LIB.T6G(SCH_1):PAGE81_I73@PURE_QUANTA.Q_RES(CHIPS)':
 'B': CDS_PINID='B';
NODE_NAME     U18 G7
 '@T6G_MB_LIB.T6G(SCH_1):PAGE81_I143@PURE_QUANTA.LCMXO3LF9400C5BG484C(CHIPS)':
 'PL2D': CDS_PINID='PL2D';
NET_NAME
'FM_CPU1_SLP_S3_N'
 '@T6G_MB_LIB.T6G(SCH_1):FM_CPU1_SLP_S3_N':
 C_SIGNAL='@t6g_mb_lib.t6g(sch_1):fm_cpu1_slp_s3_n';
NODE_NAME     R192 1
 '@T6G_MB_LIB.T6G(SCH_1):PAGE55_I298@PURE_QUANTA.Q_RES(CHIPS)':
 'A': CDS_PINID='A';
NODE_NAME     U18 D21
 '@T6G_MB_LIB.T6G(SCH_1):PAGE80_I217@PURE_QUANTA.LCMXO3LF9400C5BG484C(CHIPS)':
 'PR3B||R_GPLLC_IN': CDS_PINID='\pr3b||r_gpllc_in\';
NET_NAME
'FM_CPU1_SLP_S5_N'
 '@T6G_MB_LIB.T6G(SCH_1):FM_CPU1_SLP_S5_N':
 C_SIGNAL='@t6g_mb_lib.t6g(sch_1):fm_cpu1_slp_s5_n';
NODE_NAME     R191 1
 '@T6G_MB_LIB.T6G(SCH_1):PAGE55_I297@PURE_QUANTA.Q_RES(CHIPS)':
 'A': CDS_PINID='A';
NODE_NAME     U18 D22
 '@T6G_MB_LIB.T6G(SCH_1):PAGE80_I217@PURE_QUANTA.LCMXO3LF9400C5BG484C(CHIPS)':
 'PR3A||R_GPLLT_IN': CDS_PINID='\pr3a||r_gpllt_in\';
NET_NAME
'FM_CPU1_SMERR_N'
 '@T6G_MB_LIB.T6G(SCH_1):FM_CPU1_SMERR_N':
 C_SIGNAL='@t6g_mb_lib.t6g(sch_1):fm_cpu1_smerr_n';
NODE_NAME     R193 1
 '@T6G_MB_LIB.T6G(SCH_1):PAGE80_I179@PURE_QUANTA.Q_RES(CHIPS)':
 'A': CDS_PINID='A';
NODE_NAME     U18 N16
 '@T6G_MB_LIB.T6G(SCH_1):PAGE80_I217@PURE_QUANTA.LCMXO3LF9400C5BG484C(CHIPS)':
 'PR18B': CDS_PINID='PR18B';
NET_NAME
'FM_CPU1_SP5R1'
 '@T6G_MB_LIB.T6G(SCH_1):FM_CPU1_SP5R1':
 C_SIGNAL='@t6g_mb_lib.t6g(sch_1):fm_cpu1_sp5r1';
NODE_NAME     R260 2
 '@T6G_MB_LIB.T6G(SCH_1):PAGE81_I49@PURE_QUANTA.Q_RES(CHIPS)':
 'B': CDS_PINID='B';
NODE_NAME     U18 R3
 '@T6G_MB_LIB.T6G(SCH_1):PAGE81_I143@PURE_QUANTA.LCMXO3LF9400C5BG484C(CHIPS)':
 'PL24A': CDS_PINID='PL24A';
NET_NAME
'FM_CPU1_SP5R2'
 '@T6G_MB_LIB.T6G(SCH_1):FM_CPU1_SP5R2':
 C_SIGNAL='@t6g_mb_lib.t6g(sch_1):fm_cpu1_sp5r2';
NODE_NAME     R261 2
 '@T6G_MB_LIB.T6G(SCH_1):PAGE81_I50@PURE_QUANTA.Q_RES(CHIPS)':
 'B': CDS_PINID='B';
NODE_NAME     U18 R4
 '@T6G_MB_LIB.T6G(SCH_1):PAGE81_I143@PURE_QUANTA.LCMXO3LF9400C5BG484C(CHIPS)':
 'PL24B': CDS_PINID='PL24B';
NET_NAME
'FM_CPU1_SP5R3'
 '@T6G_MB_LIB.T6G(SCH_1):FM_CPU1_SP5R3':
 C_SIGNAL='@t6g_mb_lib.t6g(sch_1):fm_cpu1_sp5r3';
NODE_NAME     R268 2
 '@T6G_MB_LIB.T6G(SCH_1):PAGE81_I55@PURE_QUANTA.Q_RES(CHIPS)':
 'B': CDS_PINID='B';
NODE_NAME     U18 T3
 '@T6G_MB_LIB.T6G(SCH_1):PAGE81_I143@PURE_QUANTA.LCMXO3LF9400C5BG484C(CHIPS)':
 'PL26A': CDS_PINID='PL26A';
NET_NAME
'FM_CPU1_SP5R4'
 '@T6G_MB_LIB.T6G(SCH_1):FM_CPU1_SP5R4':
 C_SIGNAL='@t6g_mb_lib.t6g(sch_1):fm_cpu1_sp5r4';
NODE_NAME     R269 2
 '@T6G_MB_LIB.T6G(SCH_1):PAGE81_I56@PURE_QUANTA.Q_RES(CHIPS)':
 'B': CDS_PINID='B';
NODE_NAME     U18 T4
 '@T6G_MB_LIB.T6G(SCH_1):PAGE81_I143@PURE_QUANTA.LCMXO3LF9400C5BG484C(CHIPS)':
 'PL26B': CDS_PINID='PL26B';
NET_NAME
'FM_CPU1_SYS_RESET_N'
 '@T6G_MB_LIB.T6G(SCH_1):FM_CPU1_SYS_RESET_N':
 C_SIGNAL='@t6g_mb_lib.t6g(sch_1):fm_cpu1_sys_reset_n';
NODE_NAME     R272 2
 '@T6G_MB_LIB.T6G(SCH_1):PAGE80_I115@PURE_QUANTA.Q_RES(CHIPS)':
 'B': CDS_PINID='B';
NODE_NAME     U18 G21
 '@T6G_MB_LIB.T6G(SCH_1):PAGE80_I217@PURE_QUANTA.LCMXO3LF9400C5BG484C(CHIPS)':
 'PR6A': CDS_PINID='PR6A';
NET_NAME
'FM_CPU1_XTRIG_L4'
 '@T6G_MB_LIB.T6G(SCH_1):FM_CPU1_XTRIG_L4':
 C_SIGNAL='@t6g_mb_lib.t6g(sch_1):fm_cpu1_xtrig_l4';
NODE_NAME     R204 2
 '@T6G_MB_LIB.T6G(SCH_1):PAGE81_I77@PURE_QUANTA.Q_RES(CHIPS)':
 'B': CDS_PINID='B';
NODE_NAME     U18 D3
 '@T6G_MB_LIB.T6G(SCH_1):PAGE81_I143@PURE_QUANTA.LCMXO3LF9400C5BG484C(CHIPS)':
 'PL2A': CDS_PINID='PL2A';
NET_NAME
'FM_CPU1_XTRIG_L5'
 '@T6G_MB_LIB.T6G(SCH_1):FM_CPU1_XTRIG_L5':
 C_SIGNAL='@t6g_mb_lib.t6g(sch_1):fm_cpu1_xtrig_l5';
NODE_NAME     U18 D4
 '@T6G_MB_LIB.T6G(SCH_1):PAGE81_I143@PURE_QUANTA.LCMXO3LF9400C5BG484C(CHIPS)':
 'PL2B': CDS_PINID='PL2B';
NODE_NAME     R205 2
 '@T6G_MB_LIB.T6G(SCH_1):PAGE81_I74@PURE_QUANTA.Q_RES(CHIPS)':
 'B': CDS_PINID='B';
NET_NAME
'FM_CPU1_XTRIG_L6'
 '@T6G_MB_LIB.T6G(SCH_1):FM_CPU1_XTRIG_L6':
 C_SIGNAL='@t6g_mb_lib.t6g(sch_1):fm_cpu1_xtrig_l6';
NODE_NAME     R234 2
 '@T6G_MB_LIB.T6G(SCH_1):PAGE81_I75@PURE_QUANTA.Q_RES(CHIPS)':
 'B': CDS_PINID='B';
NODE_NAME     U18 F6
 '@T6G_MB_LIB.T6G(SCH_1):PAGE81_I143@PURE_QUANTA.LCMXO3LF9400C5BG484C(CHIPS)':
 'PL2C': CDS_PINID='PL2C';
NET_NAME
'FM_CPU1_XTRIG_L7'
 '@T6G_MB_LIB.T6G(SCH_1):FM_CPU1_XTRIG_L7':
 C_SIGNAL='@t6g_mb_lib.t6g(sch_1):fm_cpu1_xtrig_l7';
NODE_NAME     R235 2
 '@T6G_MB_LIB.T6G(SCH_1):PAGE81_I70@PURE_QUANTA.Q_RES(CHIPS)':
 'B': CDS_PINID='B';
NODE_NAME     U18 G6
 '@T6G_MB_LIB.T6G(SCH_1):PAGE81_I143@PURE_QUANTA.LCMXO3LF9400C5BG484C(CHIPS)':
 'PL3C': CDS_PINID='PL3C';
NET_NAME
'FM_ESPI_CPU0_ALERT_R_SEL'
 '@T6G_MB_LIB.T6G(SCH_1):FM_ESPI_CPU0_ALERT_R_SEL':
 C_SIGNAL='@t6g_mb_lib.t6g(sch_1):fm_espi_cpu0_alert_r_sel';
NODE_NAME     U8000 6
 '@T6G_MB_LIB.T6G(SCH_1):PAGE130_I1@PURE_QUANTA.NC7SB3157P6X(CHIPS)':
 'S': CDS_PINID='S';
NODE_NAME     R8032 2
 '@T6G_MB_LIB.T6G(SCH_1):PAGE80_I319@PURE_QUANTA.Q_RES(CHIPS)':
 'B': CDS_PINID='B';
NODE_NAME     R8033 1
 '@T6G_MB_LIB.T6G(SCH_1):PAGE82_I170@PURE_QUANTA.Q_RES(CHIPS)':
 'A': CDS_PINID='A';
NET_NAME
'FM_ESPI_CPU0_ALERT_SEL'
 '@T6G_MB_LIB.T6G(SCH_1):FM_ESPI_CPU0_ALERT_SEL':
 C_SIGNAL='@t6g_mb_lib.t6g(sch_1):fm_espi_cpu0_alert_sel';
NODE_NAME     U18 N17
 '@T6G_MB_LIB.T6G(SCH_1):PAGE80_I217@PURE_QUANTA.LCMXO3LF9400C5BG484C(CHIPS)':
 'PR18C': CDS_PINID='PR18C';
NODE_NAME     R8032 1
 '@T6G_MB_LIB.T6G(SCH_1):PAGE80_I319@PURE_QUANTA.Q_RES(CHIPS)':
 'A': CDS_PINID='A';
NET_NAME
'FM_FAN_PWR_EN'
 '@T6G_MB_LIB.T6G(SCH_1):FM_FAN_PWR_EN':
 C_SIGNAL='@t6g_mb_lib.t6g(sch_1):fm_fan_pwr_en';
NODE_NAME     R2803 2
 '@T6G_MB_LIB.T6G(SCH_1):PAGE363_I388@PURE_QUANTA.Q_RES(CHIPS)':
 'B': CDS_PINID='B';
NODE_NAME     U18 D12
 '@T6G_MB_LIB.T6G(SCH_1):PAGE79_I94@PURE_QUANTA.LCMXO3LF9400C5BG484C(CHIPS)':
 'PT27A': CDS_PINID='PT27A';
NODE_NAME     R9000 2
 '@T6G_MB_LIB.T6G(SCH_1):PAGE363_I472@PURE_QUANTA.Q_RES(CHIPS)':
 'B': CDS_PINID='B';
NET_NAME
'FM_FAN_PWR_EN_R'
 '@T6G_MB_LIB.T6G(SCH_1):FM_FAN_PWR_EN_R':
 C_SIGNAL='@t6g_mb_lib.t6g(sch_1):fm_fan_pwr_en_r';
NODE_NAME     R2803 1
 '@T6G_MB_LIB.T6G(SCH_1):PAGE363_I388@PURE_QUANTA.Q_RES(CHIPS)':
 'A': CDS_PINID='A';
NODE_NAME     C66 1
 '@T6G_MB_LIB.T6G(SCH_1):PAGE363_I455@PURE_QUANTA.Q_CAP(CHIPS)':
 'A': CDS_PINID='A';
NODE_NAME     J45 D1
 '@T6G_MB_LIB.T6G(SCH_1):PAGE363_I466@PURE_QUANTA.CONN60_101062636003K02LF(CHIPS)':
 'D1': CDS_PINID='D1';
NET_NAME
'FM_FORCE_ALL_PWRON'
 '@T6G_MB_LIB.T6G(SCH_1):FM_FORCE_ALL_PWRON':
 C_SIGNAL='@t6g_mb_lib.t6g(sch_1):fm_force_all_pwron';
NODE_NAME     R1202 2
 '@T6G_MB_LIB.T6G(SCH_1):PAGE80_I127@PURE_QUANTA.Q_RES(CHIPS)':
 'B': CDS_PINID='B';
NODE_NAME     R6044 1
 '@T6G_MB_LIB.T6G(SCH_1):PAGE144_I33@PURE_QUANTA.Q_RES(CHIPS)':
 'A': CDS_PINID='A';
NODE_NAME     SW1 12
 '@T6G_MB_LIB.T6G(SCH_1):PAGE144_I90@PURE_QUANTA.SW20S_DHNF10FQTR(CHIPS)':
 '12': CDS_PINID='\12\';
NET_NAME
'FM_FORCE_ALL_PWRON_ON'
 '@T6G_MB_LIB.T6G(SCH_1):FM_FORCE_ALL_PWRON_ON':
 C_SIGNAL='@t6g_mb_lib.t6g(sch_1):fm_force_all_pwron_on';
NODE_NAME     R5071 2
 '@T6G_MB_LIB.T6G(SCH_1):PAGE144_I34@PURE_QUANTA.Q_RES(CHIPS)':
 'B': CDS_PINID='B';
NODE_NAME     SW1 2
 '@T6G_MB_LIB.T6G(SCH_1):PAGE144_I90@PURE_QUANTA.SW20S_DHNF10FQTR(CHIPS)':
 '2': CDS_PINID='\2\';
NET_NAME
'FM_FORCE_ALL_PWRON_R'
 '@T6G_MB_LIB.T6G(SCH_1):FM_FORCE_ALL_PWRON_R':
 C_SIGNAL='@t6g_mb_lib.t6g(sch_1):fm_force_all_pwron_r';
NODE_NAME     R1202 1
 '@T6G_MB_LIB.T6G(SCH_1):PAGE80_I127@PURE_QUANTA.Q_RES(CHIPS)':
 'A': CDS_PINID='A';
NODE_NAME     U18 W20
 '@T6G_MB_LIB.T6G(SCH_1):PAGE80_I217@PURE_QUANTA.LCMXO3LF9400C5BG484C(CHIPS)':
 'PR30B': CDS_PINID='PR30B';
NET_NAME
'FM_FPGA_DEBUG_LED_CTRL'
 '@T6G_MB_LIB.T6G(SCH_1):FM_FPGA_DEBUG_LED_CTRL':
 C_SIGNAL='@t6g_mb_lib.t6g(sch_1):fm_fpga_debug_led_ctrl';
NODE_NAME     R371 2
 '@T6G_MB_LIB.T6G(SCH_1):PAGE80_I107@PURE_QUANTA.Q_RES(CHIPS)':
 'B': CDS_PINID='B';
NODE_NAME     U18 J17
 '@T6G_MB_LIB.T6G(SCH_1):PAGE80_I217@PURE_QUANTA.LCMXO3LF9400C5BG484C(CHIPS)':
 'PR11B': CDS_PINID='PR11B';
NET_NAME
'FM_FPGA_DEBUG_SW_SPARE'
 '@T6G_MB_LIB.T6G(SCH_1):FM_FPGA_DEBUG_SW_SPARE':
 C_SIGNAL='@t6g_mb_lib.t6g(sch_1):fm_fpga_debug_sw_spare';
NODE_NAME     R5099 2
 '@T6G_MB_LIB.T6G(SCH_1):PAGE80_I35@PURE_QUANTA.Q_RES(CHIPS)':
 'B': CDS_PINID='B';
NODE_NAME     U18 U8
 '@T6G_MB_LIB.T6G(SCH_1):PAGE80_I216@PURE_QUANTA.LCMXO3LF9400C5BG484C(CHIPS)':
 'PB13D': CDS_PINID='PB13D';
NET_NAME
'FM_G751_0_ALERT_N'
 '@T6G_MB_LIB.T6G(SCH_1):FM_G751_0_ALERT_N':
 C_SIGNAL='@t6g_mb_lib.t6g(sch_1):fm_g751_0_alert_n';
NODE_NAME     R4215 2
 '@T6G_MB_LIB.T6G(SCH_1):PAGE359_I79@PURE_QUANTA.Q_RES(CHIPS)':
 'B': CDS_PINID='B';
NODE_NAME     U270 3
 '@T6G_MB_LIB.T6G(SCH_1):PAGE359_I164@PURE_QUANTA.LM75BD(CHIPS)':
 'OS': CDS_PINID='OS';
NET_NAME
'FM_G751_1_ALERT_N'
 '@T6G_MB_LIB.T6G(SCH_1):FM_G751_1_ALERT_N':
 C_SIGNAL='@t6g_mb_lib.t6g(sch_1):fm_g751_1_alert_n';
NODE_NAME     R4214 2
 '@T6G_MB_LIB.T6G(SCH_1):PAGE359_I108@PURE_QUANTA.Q_RES(CHIPS)':
 'B': CDS_PINID='B';
NODE_NAME     U271 3
 '@T6G_MB_LIB.T6G(SCH_1):PAGE359_I165@PURE_QUANTA.LM75BD(CHIPS)':
 'OS': CDS_PINID='OS';
NET_NAME
'FM_GPU_HSC_EN'
 '@T6G_MB_LIB.T6G(SCH_1):FM_GPU_HSC_EN':
 C_SIGNAL='@t6g_mb_lib.t6g(sch_1):fm_gpu_hsc_en';
NODE_NAME     R2940 2
 '@T6G_MB_LIB.T6G(SCH_1):PAGE364_I28@PURE_QUANTA.Q_RES(CHIPS)':
 'B': CDS_PINID='B';
NODE_NAME     R2941 1
 '@T6G_MB_LIB.T6G(SCH_1):PAGE364_I29@PURE_QUANTA.Q_RES(CHIPS)':
 'A': CDS_PINID='A';
NODE_NAME     U278 1
 '@T6G_MB_LIB.T6G(SCH_1):PAGE364_I31@PURE_QUANTA.74LVC1G08W57(CHIPS)':
 'A': CDS_PINID='A';
NODE_NAME     R2939 1
 '@T6G_MB_LIB.T6G(SCH_1):PAGE80_I311@PURE_QUANTA.Q_RES(CHIPS)':
 'A': CDS_PINID='A';
NET_NAME
'FM_GPU_HSC_EN_BUF'
 '@T6G_MB_LIB.T6G(SCH_1):FM_GPU_HSC_EN_BUF':
 C_SIGNAL='@t6g_mb_lib.t6g(sch_1):fm_gpu_hsc_en_buf';
NODE_NAME     R2906 2
 '@T6G_MB_LIB.T6G(SCH_1):PAGE363_I440@PURE_QUANTA.Q_RES(CHIPS)':
 'B': CDS_PINID='B';
NODE_NAME     R2944 2
 '@T6G_MB_LIB.T6G(SCH_1):PAGE364_I24@PURE_QUANTA.Q_RES(CHIPS)':
 'B': CDS_PINID='B';
NET_NAME
'FM_GPU_HSC_EN_BUF_R'
 '@T6G_MB_LIB.T6G(SCH_1):FM_GPU_HSC_EN_BUF_R':
 C_SIGNAL='@t6g_mb_lib.t6g(sch_1):fm_gpu_hsc_en_buf_r';
NODE_NAME     R2944 1
 '@T6G_MB_LIB.T6G(SCH_1):PAGE364_I24@PURE_QUANTA.Q_RES(CHIPS)':
 'A': CDS_PINID='A';
NODE_NAME     R2946 2
 '@T6G_MB_LIB.T6G(SCH_1):PAGE364_I25@PURE_QUANTA.Q_RES(CHIPS)':
 'B': CDS_PINID='B';
NODE_NAME     R2948 1
 '@T6G_MB_LIB.T6G(SCH_1):PAGE364_I30@PURE_QUANTA.Q_RES(CHIPS)':
 'A': CDS_PINID='A';
NODE_NAME     U278 4
 '@T6G_MB_LIB.T6G(SCH_1):PAGE364_I31@PURE_QUANTA.74LVC1G08W57(CHIPS)':
 'Y': CDS_PINID='Y';
NET_NAME
'FM_GPU_HSC_EN_BUF_R1'
 '@T6G_MB_LIB.T6G(SCH_1):FM_GPU_HSC_EN_BUF_R1':
 C_SIGNAL='@t6g_mb_lib.t6g(sch_1):fm_gpu_hsc_en_buf_r1';
NODE_NAME     R2906 1
 '@T6G_MB_LIB.T6G(SCH_1):PAGE363_I440@PURE_QUANTA.Q_RES(CHIPS)':
 'A': CDS_PINID='A';
NODE_NAME     C67 1
 '@T6G_MB_LIB.T6G(SCH_1):PAGE363_I456@PURE_QUANTA.Q_CAP(CHIPS)':
 'A': CDS_PINID='A';
NODE_NAME     J45 D2
 '@T6G_MB_LIB.T6G(SCH_1):PAGE363_I466@PURE_QUANTA.CONN60_101062636003K02LF(CHIPS)':
 'D2': CDS_PINID='D2';
NET_NAME
'FM_GPU_HSC_EN_R'
 '@T6G_MB_LIB.T6G(SCH_1):FM_GPU_HSC_EN_R':
 C_SIGNAL='@t6g_mb_lib.t6g(sch_1):fm_gpu_hsc_en_r';
NODE_NAME     U18 T10
 '@T6G_MB_LIB.T6G(SCH_1):PAGE80_I216@PURE_QUANTA.LCMXO3LF9400C5BG484C(CHIPS)':
 'PB19C': CDS_PINID='PB19C';
NODE_NAME     R2939 2
 '@T6G_MB_LIB.T6G(SCH_1):PAGE80_I311@PURE_QUANTA.Q_RES(CHIPS)':
 'B': CDS_PINID='B';
NET_NAME
'FM_GPU_PWRGD'
 '@T6G_MB_LIB.T6G(SCH_1):FM_GPU_PWRGD':
 C_SIGNAL='@t6g_mb_lib.t6g(sch_1):fm_gpu_pwrgd';
NODE_NAME     Q72 2
 '@T6G_MB_LIB.T6G(SCH_1):PAGE333_I37@PURE_QUANTA.MOSFET_NCH_DUAL(CHIPS)':
 'G1': CDS_PINID='G1';
NODE_NAME     R3513 1
 '@T6G_MB_LIB.T6G(SCH_1):PAGE333_I173@PURE_QUANTA.Q_RES(CHIPS)':
 'A': CDS_PINID='A';
NODE_NAME     R3512 2
 '@T6G_MB_LIB.T6G(SCH_1):PAGE333_I174@PURE_QUANTA.Q_RES(CHIPS)':
 'B': CDS_PINID='B';
NODE_NAME     J111 N6
 '@T6G_MB_LIB.T6G(SCH_1):PAGE328_I38@PURE_QUANTA.CONN112_10137002101LF(CHIPS)':
 'N6': CDS_PINID='N6';
NET_NAME
'FM_GPU_PWRGD_ISO'
 '@T6G_MB_LIB.T6G(SCH_1):FM_GPU_PWRGD_ISO':
 C_SIGNAL='@t6g_mb_lib.t6g(sch_1):fm_gpu_pwrgd_iso';
NODE_NAME     C1756 1
 '@T6G_MB_LIB.T6G(SCH_1):PAGE333_I105@PURE_QUANTA.Q_CAP(CHIPS)':
 'A': CDS_PINID='A';
NODE_NAME     R2935 2
 '@T6G_MB_LIB.T6G(SCH_1):PAGE333_I109@PURE_QUANTA.Q_RES(CHIPS)':
 'B': CDS_PINID='B';
NODE_NAME     Q72 3
 '@T6G_MB_LIB.T6G(SCH_1):PAGE333_I119@PURE_QUANTA.MOSFET_NCH_DUAL(CHIPS)':
 'D2': CDS_PINID='D2';
NODE_NAME     R2664 2
 '@T6G_MB_LIB.T6G(SCH_1):PAGE80_I272@PURE_QUANTA.Q_RES(CHIPS)':
 'B': CDS_PINID='B';
NET_NAME
'FM_GPU_PWRGD_ISO_R'
 '@T6G_MB_LIB.T6G(SCH_1):FM_GPU_PWRGD_ISO_R':
 C_SIGNAL='@t6g_mb_lib.t6g(sch_1):fm_gpu_pwrgd_iso_r';
NODE_NAME     U18 AA18
 '@T6G_MB_LIB.T6G(SCH_1):PAGE80_I216@PURE_QUANTA.LCMXO3LF9400C5BG484C(CHIPS)':
 'PB41B': CDS_PINID='PB41B';
NODE_NAME     R2664 1
 '@T6G_MB_LIB.T6G(SCH_1):PAGE80_I272@PURE_QUANTA.Q_RES(CHIPS)':
 'A': CDS_PINID='A';
NET_NAME
'FM_GPU_PWRGD_N'
 '@T6G_MB_LIB.T6G(SCH_1):FM_GPU_PWRGD_N':
 C_SIGNAL='@t6g_mb_lib.t6g(sch_1):fm_gpu_pwrgd_n';
NODE_NAME     R2842 2
 '@T6G_MB_LIB.T6G(SCH_1):PAGE333_I30@PURE_QUANTA.Q_RES(CHIPS)':
 'B': CDS_PINID='B';
NODE_NAME     Q72 6
 '@T6G_MB_LIB.T6G(SCH_1):PAGE333_I37@PURE_QUANTA.MOSFET_NCH_DUAL(CHIPS)':
 'D1': CDS_PINID='D1';
NODE_NAME     Q72 5
 '@T6G_MB_LIB.T6G(SCH_1):PAGE333_I119@PURE_QUANTA.MOSFET_NCH_DUAL(CHIPS)':
 'G2': CDS_PINID='G2';
NET_NAME
'FM_GPU_PWR_EN'
 '@T6G_MB_LIB.T6G(SCH_1):FM_GPU_PWR_EN':
 C_SIGNAL='@t6g_mb_lib.t6g(sch_1):fm_gpu_pwr_en';
NODE_NAME     U18 W6
 '@T6G_MB_LIB.T6G(SCH_1):PAGE80_I216@PURE_QUANTA.LCMXO3LF9400C5BG484C(CHIPS)':
 'PB11C': CDS_PINID='PB11C';
NODE_NAME     R2262 2
 '@T6G_MB_LIB.T6G(SCH_1):PAGE80_I294@PURE_QUANTA.Q_RES(CHIPS)':
 'B': CDS_PINID='B';
NET_NAME
'FM_GPU_PWR_EN_R'
 '@T6G_MB_LIB.T6G(SCH_1):FM_GPU_PWR_EN_R':
 C_SIGNAL='@t6g_mb_lib.t6g(sch_1):fm_gpu_pwr_en_r';
NODE_NAME     U196 1
 '@T6G_MB_LIB.T6G(SCH_1):PAGE256_I127@PURE_QUANTA.74LVC2G17GW(CHIPS)':
 'A0': CDS_PINID='A0';
NODE_NAME     R2937 1
 '@T6G_MB_LIB.T6G(SCH_1):PAGE256_I160@PURE_QUANTA.Q_RES(CHIPS)':
 'A': CDS_PINID='A';
NODE_NAME     R2936 2
 '@T6G_MB_LIB.T6G(SCH_1):PAGE256_I162@PURE_QUANTA.Q_RES(CHIPS)':
 'B': CDS_PINID='B';
NODE_NAME     R2262 1
 '@T6G_MB_LIB.T6G(SCH_1):PAGE80_I294@PURE_QUANTA.Q_RES(CHIPS)':
 'A': CDS_PINID='A';
NET_NAME
'FM_GPU_PWR_EN_R1'
 '@T6G_MB_LIB.T6G(SCH_1):FM_GPU_PWR_EN_R1':
 C_SIGNAL='@t6g_mb_lib.t6g(sch_1):fm_gpu_pwr_en_r1';
NODE_NAME     U196 6
 '@T6G_MB_LIB.T6G(SCH_1):PAGE256_I127@PURE_QUANTA.74LVC2G17GW(CHIPS)':
 'B0': CDS_PINID='B0';
NODE_NAME     R2912 2
 '@T6G_MB_LIB.T6G(SCH_1):PAGE256_I147@PURE_QUANTA.Q_RES(CHIPS)':
 'B': CDS_PINID='B';
NODE_NAME     R2925 1
 '@T6G_MB_LIB.T6G(SCH_1):PAGE256_I156@PURE_QUANTA.Q_RES(CHIPS)':
 'A': CDS_PINID='A';
NODE_NAME     R3508 1
 '@T6G_MB_LIB.T6G(SCH_1):PAGE256_I194@PURE_QUANTA.Q_RES(CHIPS)':
 'A': CDS_PINID='A';
NET_NAME
'FM_GPU_PWR_EN_R_BUF'
 '@T6G_MB_LIB.T6G(SCH_1):FM_GPU_PWR_EN_R_BUF':
 C_SIGNAL='@t6g_mb_lib.t6g(sch_1):fm_gpu_pwr_en_r_buf';
NODE_NAME     R2925 2
 '@T6G_MB_LIB.T6G(SCH_1):PAGE256_I156@PURE_QUANTA.Q_RES(CHIPS)':
 'B': CDS_PINID='B';
NODE_NAME     J111 N4
 '@T6G_MB_LIB.T6G(SCH_1):PAGE328_I76@PURE_QUANTA.CONN112_10137002101LF(CHIPS)':
 'N4': CDS_PINID='N4';
NET_NAME
'FM_HDT_HDR_PWROK'
 '@T6G_MB_LIB.T6G(SCH_1):FM_HDT_HDR_PWROK':
 C_SIGNAL='@t6g_mb_lib.t6g(sch_1):fm_hdt_hdr_pwrok';
NODE_NAME     R708 1
 '@T6G_MB_LIB.T6G(SCH_1):PAGE80_I168@PURE_QUANTA.Q_RES(CHIPS)':
 'A': CDS_PINID='A';
NODE_NAME     U18 P16
 '@T6G_MB_LIB.T6G(SCH_1):PAGE80_I217@PURE_QUANTA.LCMXO3LF9400C5BG484C(CHIPS)':
 'PR24B': CDS_PINID='PR24B';
NET_NAME
'FM_HDT_HDR_RESET_N'
 '@T6G_MB_LIB.T6G(SCH_1):FM_HDT_HDR_RESET_N':
 C_SIGNAL='@t6g_mb_lib.t6g(sch_1):fm_hdt_hdr_reset_n';
NODE_NAME     R856 1
 '@T6G_MB_LIB.T6G(SCH_1):PAGE80_I167@PURE_QUANTA.Q_RES(CHIPS)':
 'A': CDS_PINID='A';
NODE_NAME     U18 U22
 '@T6G_MB_LIB.T6G(SCH_1):PAGE80_I217@PURE_QUANTA.LCMXO3LF9400C5BG484C(CHIPS)':
 'PR24C': CDS_PINID='PR24C';
NET_NAME
'FM_I3C_CPU0_MUX0_OE_N'
 '@T6G_MB_LIB.T6G(SCH_1):FM_I3C_CPU0_MUX0_OE_N':
 C_SIGNAL='@t6g_mb_lib.t6g(sch_1):fm_i3c_cpu0_mux0_oe_n';
NODE_NAME     U105 6
 '@T6G_MB_LIB.T6G(SCH_1):PAGE136_I47@PURE_QUANTA.PI3CSW12ZUAEX(CHIPS)':
 'OE#': CDS_PINID='\oe#\';
NODE_NAME     R163 2
 '@T6G_MB_LIB.T6G(SCH_1):PAGE79_I54@PURE_QUANTA.Q_RES(CHIPS)':
 'B': CDS_PINID='B';
NODE_NAME     R10 1
 '@T6G_MB_LIB.T6G(SCH_1):PAGE82_I93@PURE_QUANTA.Q_RES(CHIPS)':
 'A': CDS_PINID='A';
NET_NAME
'FM_I3C_CPU0_MUX0_OE_R_N'
 '@T6G_MB_LIB.T6G(SCH_1):FM_I3C_CPU0_MUX0_OE_R_N':
 C_SIGNAL='@t6g_mb_lib.t6g(sch_1):fm_i3c_cpu0_mux0_oe_r_n';
NODE_NAME     R163 1
 '@T6G_MB_LIB.T6G(SCH_1):PAGE79_I54@PURE_QUANTA.Q_RES(CHIPS)':
 'A': CDS_PINID='A';
NODE_NAME     U18 B1
 '@T6G_MB_LIB.T6G(SCH_1):PAGE79_I94@PURE_QUANTA.LCMXO3LF9400C5BG484C(CHIPS)':
 'PT9A||L_GPLLT': CDS_PINID='\pt9a||l_gpllt\';
NET_NAME
'FM_I3C_CPU0_MUX0_R_SEL'
 '@T6G_MB_LIB.T6G(SCH_1):FM_I3C_CPU0_MUX0_R_SEL':
 C_SIGNAL='@t6g_mb_lib.t6g(sch_1):fm_i3c_cpu0_mux0_r_sel';
NODE_NAME     R164 1
 '@T6G_MB_LIB.T6G(SCH_1):PAGE79_I50@PURE_QUANTA.Q_RES(CHIPS)':
 'A': CDS_PINID='A';
NODE_NAME     U18 C3
 '@T6G_MB_LIB.T6G(SCH_1):PAGE79_I94@PURE_QUANTA.LCMXO3LF9400C5BG484C(CHIPS)':
 'PT10C': CDS_PINID='PT10C';
NET_NAME
'FM_I3C_CPU0_MUX0_SEL'
 '@T6G_MB_LIB.T6G(SCH_1):FM_I3C_CPU0_MUX0_SEL':
 C_SIGNAL='@t6g_mb_lib.t6g(sch_1):fm_i3c_cpu0_mux0_sel';
NODE_NAME     U105 9
 '@T6G_MB_LIB.T6G(SCH_1):PAGE136_I47@PURE_QUANTA.PI3CSW12ZUAEX(CHIPS)':
 'S': CDS_PINID='S';
NODE_NAME     R164 2
 '@T6G_MB_LIB.T6G(SCH_1):PAGE79_I50@PURE_QUANTA.Q_RES(CHIPS)':
 'B': CDS_PINID='B';
NET_NAME
'FM_I3C_CPU0_MUX1_OE_N'
 '@T6G_MB_LIB.T6G(SCH_1):FM_I3C_CPU0_MUX1_OE_N':
 C_SIGNAL='@t6g_mb_lib.t6g(sch_1):fm_i3c_cpu0_mux1_oe_n';
NODE_NAME     U106 6
 '@T6G_MB_LIB.T6G(SCH_1):PAGE136_I54@PURE_QUANTA.PI3CSW12ZUAEX(CHIPS)':
 'OE#': CDS_PINID='\oe#\';
NODE_NAME     R165 2
 '@T6G_MB_LIB.T6G(SCH_1):PAGE79_I47@PURE_QUANTA.Q_RES(CHIPS)':
 'B': CDS_PINID='B';
NODE_NAME     R11 1
 '@T6G_MB_LIB.T6G(SCH_1):PAGE82_I94@PURE_QUANTA.Q_RES(CHIPS)':
 'A': CDS_PINID='A';
NET_NAME
'FM_I3C_CPU0_MUX1_OE_R_N'
 '@T6G_MB_LIB.T6G(SCH_1):FM_I3C_CPU0_MUX1_OE_R_N':
 C_SIGNAL='@t6g_mb_lib.t6g(sch_1):fm_i3c_cpu0_mux1_oe_r_n';
NODE_NAME     R165 1
 '@T6G_MB_LIB.T6G(SCH_1):PAGE79_I47@PURE_QUANTA.Q_RES(CHIPS)':
 'A': CDS_PINID='A';
NODE_NAME     U18 C4
 '@T6G_MB_LIB.T6G(SCH_1):PAGE79_I94@PURE_QUANTA.LCMXO3LF9400C5BG484C(CHIPS)':
 'PT10D': CDS_PINID='PT10D';
NET_NAME
'FM_I3C_CPU0_MUX1_R_SEL'
 '@T6G_MB_LIB.T6G(SCH_1):FM_I3C_CPU0_MUX1_R_SEL':
 C_SIGNAL='@t6g_mb_lib.t6g(sch_1):fm_i3c_cpu0_mux1_r_sel';
NODE_NAME     R166 1
 '@T6G_MB_LIB.T6G(SCH_1):PAGE79_I51@PURE_QUANTA.Q_RES(CHIPS)':
 'A': CDS_PINID='A';
NODE_NAME     U18 F7
 '@T6G_MB_LIB.T6G(SCH_1):PAGE79_I94@PURE_QUANTA.LCMXO3LF9400C5BG484C(CHIPS)':
 'PT9D': CDS_PINID='PT9D';
NET_NAME
'FM_I3C_CPU0_MUX1_SEL'
 '@T6G_MB_LIB.T6G(SCH_1):FM_I3C_CPU0_MUX1_SEL':
 C_SIGNAL='@t6g_mb_lib.t6g(sch_1):fm_i3c_cpu0_mux1_sel';
NODE_NAME     U106 9
 '@T6G_MB_LIB.T6G(SCH_1):PAGE136_I54@PURE_QUANTA.PI3CSW12ZUAEX(CHIPS)':
 'S': CDS_PINID='S';
NODE_NAME     R166 2
 '@T6G_MB_LIB.T6G(SCH_1):PAGE79_I51@PURE_QUANTA.Q_RES(CHIPS)':
 'B': CDS_PINID='B';
NET_NAME
'FM_I3C_CPU1_MUX0_OE_N'
 '@T6G_MB_LIB.T6G(SCH_1):FM_I3C_CPU1_MUX0_OE_N':
 C_SIGNAL='@t6g_mb_lib.t6g(sch_1):fm_i3c_cpu1_mux0_oe_n';
NODE_NAME     U107 6
 '@T6G_MB_LIB.T6G(SCH_1):PAGE136_I63@PURE_QUANTA.PI3CSW12ZUAEX(CHIPS)':
 'OE#': CDS_PINID='\oe#\';
NODE_NAME     R169 2
 '@T6G_MB_LIB.T6G(SCH_1):PAGE79_I48@PURE_QUANTA.Q_RES(CHIPS)':
 'B': CDS_PINID='B';
NODE_NAME     R12 1
 '@T6G_MB_LIB.T6G(SCH_1):PAGE82_I95@PURE_QUANTA.Q_RES(CHIPS)':
 'A': CDS_PINID='A';
NET_NAME
'FM_I3C_CPU1_MUX0_OE_R_N'
 '@T6G_MB_LIB.T6G(SCH_1):FM_I3C_CPU1_MUX0_OE_R_N':
 C_SIGNAL='@t6g_mb_lib.t6g(sch_1):fm_i3c_cpu1_mux0_oe_r_n';
NODE_NAME     R169 1
 '@T6G_MB_LIB.T6G(SCH_1):PAGE79_I48@PURE_QUANTA.Q_RES(CHIPS)':
 'A': CDS_PINID='A';
NODE_NAME     U18 B2
 '@T6G_MB_LIB.T6G(SCH_1):PAGE79_I94@PURE_QUANTA.LCMXO3LF9400C5BG484C(CHIPS)':
 'PT10A': CDS_PINID='PT10A';
NET_NAME
'FM_I3C_CPU1_MUX0_R_SEL'
 '@T6G_MB_LIB.T6G(SCH_1):FM_I3C_CPU1_MUX0_R_SEL':
 C_SIGNAL='@t6g_mb_lib.t6g(sch_1):fm_i3c_cpu1_mux0_r_sel';
NODE_NAME     R170 1
 '@T6G_MB_LIB.T6G(SCH_1):PAGE79_I53@PURE_QUANTA.Q_RES(CHIPS)':
 'A': CDS_PINID='A';
NODE_NAME     U18 A2
 '@T6G_MB_LIB.T6G(SCH_1):PAGE79_I94@PURE_QUANTA.LCMXO3LF9400C5BG484C(CHIPS)':
 'PT9B||L_GPLLC': CDS_PINID='\pt9b||l_gpllc\';
NET_NAME
'FM_I3C_CPU1_MUX0_SEL'
 '@T6G_MB_LIB.T6G(SCH_1):FM_I3C_CPU1_MUX0_SEL':
 C_SIGNAL='@t6g_mb_lib.t6g(sch_1):fm_i3c_cpu1_mux0_sel';
NODE_NAME     U107 9
 '@T6G_MB_LIB.T6G(SCH_1):PAGE136_I63@PURE_QUANTA.PI3CSW12ZUAEX(CHIPS)':
 'S': CDS_PINID='S';
NODE_NAME     R170 2
 '@T6G_MB_LIB.T6G(SCH_1):PAGE79_I53@PURE_QUANTA.Q_RES(CHIPS)':
 'B': CDS_PINID='B';
NET_NAME
'FM_I3C_CPU1_MUX1_OE_N'
 '@T6G_MB_LIB.T6G(SCH_1):FM_I3C_CPU1_MUX1_OE_N':
 C_SIGNAL='@t6g_mb_lib.t6g(sch_1):fm_i3c_cpu1_mux1_oe_n';
NODE_NAME     U108 6
 '@T6G_MB_LIB.T6G(SCH_1):PAGE136_I68@PURE_QUANTA.PI3CSW12ZUAEX(CHIPS)':
 'OE#': CDS_PINID='\oe#\';
NODE_NAME     R171 2
 '@T6G_MB_LIB.T6G(SCH_1):PAGE79_I52@PURE_QUANTA.Q_RES(CHIPS)':
 'B': CDS_PINID='B';
NODE_NAME     R25 1
 '@T6G_MB_LIB.T6G(SCH_1):PAGE82_I97@PURE_QUANTA.Q_RES(CHIPS)':
 'A': CDS_PINID='A';
NET_NAME
'FM_I3C_CPU1_MUX1_OE_R_N'
 '@T6G_MB_LIB.T6G(SCH_1):FM_I3C_CPU1_MUX1_OE_R_N':
 C_SIGNAL='@t6g_mb_lib.t6g(sch_1):fm_i3c_cpu1_mux1_oe_r_n';
NODE_NAME     R171 1
 '@T6G_MB_LIB.T6G(SCH_1):PAGE79_I52@PURE_QUANTA.Q_RES(CHIPS)':
 'A': CDS_PINID='A';
NODE_NAME     U18 E6
 '@T6G_MB_LIB.T6G(SCH_1):PAGE79_I94@PURE_QUANTA.LCMXO3LF9400C5BG484C(CHIPS)':
 'PT9C': CDS_PINID='PT9C';
NET_NAME
'FM_I3C_CPU1_MUX1_R_SEL'
 '@T6G_MB_LIB.T6G(SCH_1):FM_I3C_CPU1_MUX1_R_SEL':
 C_SIGNAL='@t6g_mb_lib.t6g(sch_1):fm_i3c_cpu1_mux1_r_sel';
NODE_NAME     R172 1
 '@T6G_MB_LIB.T6G(SCH_1):PAGE79_I43@PURE_QUANTA.Q_RES(CHIPS)':
 'A': CDS_PINID='A';
NODE_NAME     U18 D5
 '@T6G_MB_LIB.T6G(SCH_1):PAGE79_I94@PURE_QUANTA.LCMXO3LF9400C5BG484C(CHIPS)':
 'PT12C': CDS_PINID='PT12C';
NET_NAME
'FM_I3C_CPU1_MUX1_SEL'
 '@T6G_MB_LIB.T6G(SCH_1):FM_I3C_CPU1_MUX1_SEL':
 C_SIGNAL='@t6g_mb_lib.t6g(sch_1):fm_i3c_cpu1_mux1_sel';
NODE_NAME     U108 9
 '@T6G_MB_LIB.T6G(SCH_1):PAGE136_I68@PURE_QUANTA.PI3CSW12ZUAEX(CHIPS)':
 'S': CDS_PINID='S';
NODE_NAME     R172 2
 '@T6G_MB_LIB.T6G(SCH_1):PAGE79_I43@PURE_QUANTA.Q_RES(CHIPS)':
 'B': CDS_PINID='B';
NET_NAME
'FM_INT_CPU0_HP_UBM_N'
 '@T6G_MB_LIB.T6G(SCH_1):FM_INT_CPU0_HP_UBM_N':
 C_SIGNAL='@t6g_mb_lib.t6g(sch_1):fm_int_cpu0_hp_ubm_n';
NODE_NAME     R81 2
 '@T6G_MB_LIB.T6G(SCH_1):PAGE81_I106@PURE_QUANTA.Q_RES(CHIPS)':
 'B': CDS_PINID='B';
NODE_NAME     R207 1
 '@T6G_MB_LIB.T6G(SCH_1):PAGE28_I44@PURE_QUANTA.Q_RES(CHIPS)':
 'A': CDS_PINID='A';
NODE_NAME     U25 DJ35
 '@T6G_MB_LIB.T6G(SCH_1):PAGE28_I188@PURE_QUANTA.GENOA_SP5(CHIPS)':
 'GENINT_L||PM_INTR_L||UBM_CPRSNT_CHANGE_DET_L||AGPIO89': CDS_PINID='\genint_l||pm_intr_l||ubm_cprsnt_change_det_l||agpio89\';
NET_NAME
'FM_INT_CPU0_HP_UBM_R_N'
 '@T6G_MB_LIB.T6G(SCH_1):FM_INT_CPU0_HP_UBM_R_N':
 C_SIGNAL='@t6g_mb_lib.t6g(sch_1):fm_int_cpu0_hp_ubm_r_n';
NODE_NAME     U18 J3
 '@T6G_MB_LIB.T6G(SCH_1):PAGE81_I143@PURE_QUANTA.LCMXO3LF9400C5BG484C(CHIPS)':
 'PL11D': CDS_PINID='PL11D';
NODE_NAME     R81 1
 '@T6G_MB_LIB.T6G(SCH_1):PAGE81_I106@PURE_QUANTA.Q_RES(CHIPS)':
 'A': CDS_PINID='A';
NET_NAME
'FM_JTAG_BMC_OE'
 '@T6G_MB_LIB.T6G(SCH_1):FM_JTAG_BMC_OE':
 C_SIGNAL='@t6g_mb_lib.t6g(sch_1):fm_jtag_bmc_oe';
NODE_NAME     U18 R22
 '@T6G_MB_LIB.T6G(SCH_1):PAGE80_I217@PURE_QUANTA.LCMXO3LF9400C5BG484C(CHIPS)':
 'PR20A': CDS_PINID='PR20A';
NODE_NAME     R8021 1
 '@T6G_MB_LIB.T6G(SCH_1):PAGE80_I318@PURE_QUANTA.Q_RES(CHIPS)':
 'A': CDS_PINID='A';
NET_NAME
'FM_JTAG_BMC_R_OE'
 '@T6G_MB_LIB.T6G(SCH_1):FM_JTAG_BMC_R_OE':
 C_SIGNAL='@t6g_mb_lib.t6g(sch_1):fm_jtag_bmc_r_oe';
NODE_NAME     U124 2
 '@T6G_MB_LIB.T6G(SCH_1):PAGE144_I38@PURE_QUANTA.SN74LVC1G07DBVR(CHIPS)':
 'A': CDS_PINID='A';
NODE_NAME     R733 2
 '@T6G_MB_LIB.T6G(SCH_1):PAGE144_I50@PURE_QUANTA.Q_RES(CHIPS)':
 'B': CDS_PINID='B';
NODE_NAME     R8021 2
 '@T6G_MB_LIB.T6G(SCH_1):PAGE80_I318@PURE_QUANTA.Q_RES(CHIPS)':
 'B': CDS_PINID='B';
NODE_NAME     R8019 2
 '@T6G_MB_LIB.T6G(SCH_1):PAGE144_I89@PURE_QUANTA.Q_RES(CHIPS)':
 'B': CDS_PINID='B';
NET_NAME
'FM_LED_ACTIVE_E1S_0'
 '@T6G_MB_LIB.T6G(SCH_1):FM_LED_ACTIVE_E1S_0':
 C_SIGNAL='@t6g_mb_lib.t6g(sch_1):fm_led_active_e1s_0';
NODE_NAME     R955 1
 '@T6G_MB_LIB.T6G(SCH_1):PAGE297_I94@PURE_QUANTA.Q_RES(CHIPS)':
 'A': CDS_PINID='A';
NODE_NAME     U18 E10
 '@T6G_MB_LIB.T6G(SCH_1):PAGE79_I94@PURE_QUANTA.LCMXO3LF9400C5BG484C(CHIPS)':
 'PT22B': CDS_PINID='PT22B';
NET_NAME
'FM_LED_ACTIVE_E1S_0_BUF'
 '@T6G_MB_LIB.T6G(SCH_1):FM_LED_ACTIVE_E1S_0_BUF':
 C_SIGNAL='@t6g_mb_lib.t6g(sch_1):fm_led_active_e1s_0_buf';
NODE_NAME     J90 A10
 '@T6G_MB_LIB.T6G(SCH_1):PAGE297_I90@PURE_QUANTA.SCONN56_123276793(CHIPS)':
 'LED#_ACTIVITY': CDS_PINID='\led#_activity\';
NODE_NAME     R1038 2
 '@T6G_MB_LIB.T6G(SCH_1):PAGE297_I101@PURE_QUANTA.Q_RES(CHIPS)':
 'B': CDS_PINID='B';
NODE_NAME     R1000 1
 '@T6G_MB_LIB.T6G(SCH_1):PAGE297_I102@PURE_QUANTA.Q_RES(CHIPS)':
 'A': CDS_PINID='A';
NET_NAME
'FM_LED_ACTIVE_E1S_0_R'
 '@T6G_MB_LIB.T6G(SCH_1):FM_LED_ACTIVE_E1S_0_R':
 C_SIGNAL='@t6g_mb_lib.t6g(sch_1):fm_led_active_e1s_0_r';
NODE_NAME     R955 2
 '@T6G_MB_LIB.T6G(SCH_1):PAGE297_I94@PURE_QUANTA.Q_RES(CHIPS)':
 'B': CDS_PINID='B';
NODE_NAME     R999 1
 '@T6G_MB_LIB.T6G(SCH_1):PAGE297_I95@PURE_QUANTA.Q_RES(CHIPS)':
 'A': CDS_PINID='A';
NODE_NAME     U44 2
 '@T6G_MB_LIB.T6G(SCH_1):PAGE297_I97@PURE_QUANTA.74LVC1G17GW(CHIPS)':
 'A': CDS_PINID='A';
NET_NAME
'FM_LED_ACTIVE_E1S_0_R_BUF'
 '@T6G_MB_LIB.T6G(SCH_1):FM_LED_ACTIVE_E1S_0_R_BUF':
 C_SIGNAL='@t6g_mb_lib.t6g(sch_1):fm_led_active_e1s_0_r_buf';
NODE_NAME     U44 4
 '@T6G_MB_LIB.T6G(SCH_1):PAGE297_I97@PURE_QUANTA.74LVC1G17GW(CHIPS)':
 'Y': CDS_PINID='Y';
NODE_NAME     R1038 1
 '@T6G_MB_LIB.T6G(SCH_1):PAGE297_I101@PURE_QUANTA.Q_RES(CHIPS)':
 'A': CDS_PINID='A';
NET_NAME
'FM_LED_PWRGD_PVDD11_S3_P0'
 '@T6G_MB_LIB.T6G(SCH_1):FM_LED_PWRGD_PVDD11_S3_P0':
 C_SIGNAL='@t6g_mb_lib.t6g(sch_1):fm_led_pwrgd_pvdd11_s3_p0';
NODE_NAME     U18 Y12
 '@T6G_MB_LIB.T6G(SCH_1):PAGE80_I216@PURE_QUANTA.LCMXO3LF9400C5BG484C(CHIPS)':
 'PB27A': CDS_PINID='PB27A';
NODE_NAME     Q81 5
 '@T6G_MB_LIB.T6G(SCH_1):PAGE374_I27@PURE_QUANTA.MOSFET_NCH_DUAL(CHIPS)':
 'G2': CDS_PINID='G2';
NET_NAME
'FM_LED_PWRGD_PVDD11_S3_P1'
 '@T6G_MB_LIB.T6G(SCH_1):FM_LED_PWRGD_PVDD11_S3_P1':
 C_SIGNAL='@t6g_mb_lib.t6g(sch_1):fm_led_pwrgd_pvdd11_s3_p1';
NODE_NAME     U18 B19
 '@T6G_MB_LIB.T6G(SCH_1):PAGE79_I94@PURE_QUANTA.LCMXO3LF9400C5BG484C(CHIPS)':
 'PT41B': CDS_PINID='PT41B';
NODE_NAME     Q86 2
 '@T6G_MB_LIB.T6G(SCH_1):PAGE375_I30@PURE_QUANTA.MOSFET_NCH_DUAL(CHIPS)':
 'G1': CDS_PINID='G1';
NET_NAME
'FM_LED_PWRGD_PVDD18_S5_P0'
 '@T6G_MB_LIB.T6G(SCH_1):FM_LED_PWRGD_PVDD18_S5_P0':
 C_SIGNAL='@t6g_mb_lib.t6g(sch_1):fm_led_pwrgd_pvdd18_s5_p0';
NODE_NAME     U18 AB11
 '@T6G_MB_LIB.T6G(SCH_1):PAGE80_I216@PURE_QUANTA.LCMXO3LF9400C5BG484C(CHIPS)':
 'PB24B': CDS_PINID='PB24B';
NODE_NAME     Q83 2
 '@T6G_MB_LIB.T6G(SCH_1):PAGE374_I23@PURE_QUANTA.MOSFET_NCH_DUAL(CHIPS)':
 'G1': CDS_PINID='G1';
NET_NAME
'FM_LED_PWRGD_PVDD18_S5_P1'
 '@T6G_MB_LIB.T6G(SCH_1):FM_LED_PWRGD_PVDD18_S5_P1':
 C_SIGNAL='@t6g_mb_lib.t6g(sch_1):fm_led_pwrgd_pvdd18_s5_p1';
NODE_NAME     U18 A19
 '@T6G_MB_LIB.T6G(SCH_1):PAGE79_I94@PURE_QUANTA.LCMXO3LF9400C5BG484C(CHIPS)':
 'PT42A': CDS_PINID='PT42A';
NODE_NAME     Q86 5
 '@T6G_MB_LIB.T6G(SCH_1):PAGE375_I29@PURE_QUANTA.MOSFET_NCH_DUAL(CHIPS)':
 'G2': CDS_PINID='G2';
NET_NAME
'FM_LED_PWRGD_PVDD33_S5'
 '@T6G_MB_LIB.T6G(SCH_1):FM_LED_PWRGD_PVDD33_S5':
 C_SIGNAL='@t6g_mb_lib.t6g(sch_1):fm_led_pwrgd_pvdd33_s5';
NODE_NAME     U18 T11
 '@T6G_MB_LIB.T6G(SCH_1):PAGE80_I216@PURE_QUANTA.LCMXO3LF9400C5BG484C(CHIPS)':
 'PB22C': CDS_PINID='PB22C';
NODE_NAME     Q79 2
 '@T6G_MB_LIB.T6G(SCH_1):PAGE374_I18@PURE_QUANTA.MOSFET_NCH_DUAL(CHIPS)':
 'G1': CDS_PINID='G1';
NET_NAME
'FM_LED_PWRGD_PVDDCR_CPU0_P0'
 '@T6G_MB_LIB.T6G(SCH_1):FM_LED_PWRGD_PVDDCR_CPU0_P0':
 C_SIGNAL='@t6g_mb_lib.t6g(sch_1):fm_led_pwrgd_pvddcr_cpu0_p0';
NODE_NAME     U18 U5
 '@T6G_MB_LIB.T6G(SCH_1):PAGE81_I143@PURE_QUANTA.LCMXO3LF9400C5BG484C(CHIPS)':
 'PL28D': CDS_PINID='PL28D';
NODE_NAME     Q79 5
 '@T6G_MB_LIB.T6G(SCH_1):PAGE374_I8@PURE_QUANTA.MOSFET_NCH_DUAL(CHIPS)':
 'G2': CDS_PINID='G2';
NET_NAME
'FM_LED_PWRGD_PVDDCR_CPU0_P1'
 '@T6G_MB_LIB.T6G(SCH_1):FM_LED_PWRGD_PVDDCR_CPU0_P1':
 C_SIGNAL='@t6g_mb_lib.t6g(sch_1):fm_led_pwrgd_pvddcr_cpu0_p1';
NODE_NAME     U18 V10
 '@T6G_MB_LIB.T6G(SCH_1):PAGE80_I216@PURE_QUANTA.LCMXO3LF9400C5BG484C(CHIPS)':
 'PB21A': CDS_PINID='PB21A';
NODE_NAME     Q84 2
 '@T6G_MB_LIB.T6G(SCH_1):PAGE375_I11@PURE_QUANTA.MOSFET_NCH_DUAL(CHIPS)':
 'G1': CDS_PINID='G1';
NET_NAME
'FM_LED_PWRGD_PVDDCR_CPU1_P0'
 '@T6G_MB_LIB.T6G(SCH_1):FM_LED_PWRGD_PVDDCR_CPU1_P0':
 C_SIGNAL='@t6g_mb_lib.t6g(sch_1):fm_led_pwrgd_pvddcr_cpu1_p0';
NODE_NAME     U18 R5
 '@T6G_MB_LIB.T6G(SCH_1):PAGE81_I143@PURE_QUANTA.LCMXO3LF9400C5BG484C(CHIPS)':
 'PL24C': CDS_PINID='PL24C';
NODE_NAME     Q80 5
 '@T6G_MB_LIB.T6G(SCH_1):PAGE374_I3@PURE_QUANTA.MOSFET_NCH_DUAL(CHIPS)':
 'G2': CDS_PINID='G2';
NET_NAME
'FM_LED_PWRGD_PVDDCR_CPU1_P1'
 '@T6G_MB_LIB.T6G(SCH_1):FM_LED_PWRGD_PVDDCR_CPU1_P1':
 C_SIGNAL='@t6g_mb_lib.t6g(sch_1):fm_led_pwrgd_pvddcr_cpu1_p1';
NODE_NAME     U18 E16
 '@T6G_MB_LIB.T6G(SCH_1):PAGE79_I94@PURE_QUANTA.LCMXO3LF9400C5BG484C(CHIPS)':
 'PT40C': CDS_PINID='PT40C';
NODE_NAME     Q85 2
 '@T6G_MB_LIB.T6G(SCH_1):PAGE375_I7@PURE_QUANTA.MOSFET_NCH_DUAL(CHIPS)':
 'G1': CDS_PINID='G1';
NET_NAME
'FM_LED_PWRGD_PVDDCR_SOC_P0'
 '@T6G_MB_LIB.T6G(SCH_1):FM_LED_PWRGD_PVDDCR_SOC_P0':
 C_SIGNAL='@t6g_mb_lib.t6g(sch_1):fm_led_pwrgd_pvddcr_soc_p0';
NODE_NAME     U18 V4
 '@T6G_MB_LIB.T6G(SCH_1):PAGE81_I143@PURE_QUANTA.LCMXO3LF9400C5BG484C(CHIPS)':
 'PL28C': CDS_PINID='PL28C';
NODE_NAME     Q80 2
 '@T6G_MB_LIB.T6G(SCH_1):PAGE374_I6@PURE_QUANTA.MOSFET_NCH_DUAL(CHIPS)':
 'G1': CDS_PINID='G1';
NET_NAME
'FM_LED_PWRGD_PVDDCR_SOC_P1'
 '@T6G_MB_LIB.T6G(SCH_1):FM_LED_PWRGD_PVDDCR_SOC_P1':
 C_SIGNAL='@t6g_mb_lib.t6g(sch_1):fm_led_pwrgd_pvddcr_soc_p1';
NODE_NAME     U18 B18
 '@T6G_MB_LIB.T6G(SCH_1):PAGE79_I94@PURE_QUANTA.LCMXO3LF9400C5BG484C(CHIPS)':
 'PT40B': CDS_PINID='PT40B';
NODE_NAME     Q84 5
 '@T6G_MB_LIB.T6G(SCH_1):PAGE375_I10@PURE_QUANTA.MOSFET_NCH_DUAL(CHIPS)':
 'G2': CDS_PINID='G2';
NET_NAME
'FM_LED_PWRGD_PVDDIO_P0'
 '@T6G_MB_LIB.T6G(SCH_1):FM_LED_PWRGD_PVDDIO_P0':
 C_SIGNAL='@t6g_mb_lib.t6g(sch_1):fm_led_pwrgd_pvddio_p0';
NODE_NAME     U18 Y11
 '@T6G_MB_LIB.T6G(SCH_1):PAGE80_I216@PURE_QUANTA.LCMXO3LF9400C5BG484C(CHIPS)':
 'PB24D': CDS_PINID='PB24D';
NODE_NAME     Q81 2
 '@T6G_MB_LIB.T6G(SCH_1):PAGE374_I35@PURE_QUANTA.MOSFET_NCH_DUAL(CHIPS)':
 'G1': CDS_PINID='G1';
NET_NAME
'FM_LED_PWRGD_PVDDIO_P1'
 '@T6G_MB_LIB.T6G(SCH_1):FM_LED_PWRGD_PVDDIO_P1':
 C_SIGNAL='@t6g_mb_lib.t6g(sch_1):fm_led_pwrgd_pvddio_p1';
NODE_NAME     U18 A18
 '@T6G_MB_LIB.T6G(SCH_1):PAGE79_I94@PURE_QUANTA.LCMXO3LF9400C5BG484C(CHIPS)':
 'PT41A': CDS_PINID='PT41A';
NODE_NAME     Q85 5
 '@T6G_MB_LIB.T6G(SCH_1):PAGE375_I2@PURE_QUANTA.MOSFET_NCH_DUAL(CHIPS)':
 'G2': CDS_PINID='G2';
NET_NAME
'FM_LM75_2_ALERT_N'
 '@T6G_MB_LIB.T6G(SCH_1):FM_LM75_2_ALERT_N':
 C_SIGNAL='@t6g_mb_lib.t6g(sch_1):fm_lm75_2_alert_n';
NODE_NAME     R4213 2
 '@T6G_MB_LIB.T6G(SCH_1):PAGE359_I115@PURE_QUANTA.Q_RES(CHIPS)':
 'B': CDS_PINID='B';
NODE_NAME     U272 3
 '@T6G_MB_LIB.T6G(SCH_1):PAGE359_I166@PURE_QUANTA.LM75BD(CHIPS)':
 'OS': CDS_PINID='OS';
NET_NAME
'FM_LM75_3_ALERT_N'
 '@T6G_MB_LIB.T6G(SCH_1):FM_LM75_3_ALERT_N':
 C_SIGNAL='@t6g_mb_lib.t6g(sch_1):fm_lm75_3_alert_n';
NODE_NAME     R4212 2
 '@T6G_MB_LIB.T6G(SCH_1):PAGE359_I135@PURE_QUANTA.Q_RES(CHIPS)':
 'B': CDS_PINID='B';
NODE_NAME     U273 3
 '@T6G_MB_LIB.T6G(SCH_1):PAGE359_I167@PURE_QUANTA.LM75BD(CHIPS)':
 'OS': CDS_PINID='OS';
NET_NAME
'FM_LPC_ESPI_SEL'
 '@T6G_MB_LIB.T6G(SCH_1):FM_LPC_ESPI_SEL':
 C_SIGNAL='@t6g_mb_lib.t6g(sch_1):fm_lpc_espi_sel';
NODE_NAME     J41 B9
 '@T6G_MB_LIB.T6G(SCH_1):PAGE348_I176@PURE_QUANTA.SCONN168_ME1016810202011(CHIPS)':
 'BIF2#': CDS_PINID='\bif2#\';
NODE_NAME     R6028 1
 '@T6G_MB_LIB.T6G(SCH_1):PAGE348_I174@PURE_QUANTA.Q_RES(CHIPS)':
 'A': CDS_PINID='A';
NET_NAME
'FM_M2_SSD_0_PEDET'
 '@T6G_MB_LIB.T6G(SCH_1):FM_M2_SSD_0_PEDET':
 C_SIGNAL='@t6g_mb_lib.t6g(sch_1):fm_m2_ssd_0_pedet';
NODE_NAME     J59 69
 '@T6G_MB_LIB.T6G(SCH_1):PAGE345_I88@PURE_QUANTA.SCONN75K_APCI0155P004A(CHIPS)':
 'PEDET': CDS_PINID='PEDET';
NODE_NAME     R1396 1
 '@T6G_MB_LIB.T6G(SCH_1):PAGE345_I66@PURE_QUANTA.Q_RES(CHIPS)':
 'A': CDS_PINID='A';
NET_NAME
'FM_NCSI_OCP_SFF_R_OE'
 '@T6G_MB_LIB.T6G(SCH_1):FM_NCSI_OCP_SFF_R_OE':
 C_SIGNAL='@t6g_mb_lib.t6g(sch_1):fm_ncsi_ocp_sff_r_oe';
NODE_NAME     R1282 1
 '@T6G_MB_LIB.T6G(SCH_1):PAGE80_I29@PURE_QUANTA.Q_RES(CHIPS)':
 'A': CDS_PINID='A';
NODE_NAME     R2474 1
 '@T6G_MB_LIB.T6G(SCH_1):PAGE336_I165@PURE_QUANTA.Q_RES(CHIPS)':
 'A': CDS_PINID='A';
NET_NAME
'FM_NCSI_OCP_V3_2_R_OE'
 '@T6G_MB_LIB.T6G(SCH_1):FM_NCSI_OCP_V3_2_R_OE':
 C_SIGNAL='@t6g_mb_lib.t6g(sch_1):fm_ncsi_ocp_v3_2_r_oe';
NODE_NAME     U18 U16
 '@T6G_MB_LIB.T6G(SCH_1):PAGE80_I216@PURE_QUANTA.LCMXO3LF9400C5BG484C(CHIPS)':
 'PB43D': CDS_PINID='PB43D';
NODE_NAME     R3206 1
 '@T6G_MB_LIB.T6G(SCH_1):PAGE307_I85@PURE_QUANTA.Q_RES(CHIPS)':
 'A': CDS_PINID='A';
NET_NAME
'FM_OCP_SFF_PWR_GOOD'
 '@T6G_MB_LIB.T6G(SCH_1):FM_OCP_SFF_PWR_GOOD':
 C_SIGNAL='@t6g_mb_lib.t6g(sch_1):fm_ocp_sff_pwr_good';
NODE_NAME     R3132 2
 '@T6G_MB_LIB.T6G(SCH_1):PAGE335_I6@PURE_QUANTA.Q_RES(CHIPS)':
 'B': CDS_PINID='B';
NODE_NAME     J38 OB1
 '@T6G_MB_LIB.T6G(SCH_1):PAGE335_I168@PURE_QUANTA.SCONN168_ME1016810202011(CHIPS)':
 'NIC_PWR_GOOD': CDS_PINID='NIC_PWR_GOOD';
NODE_NAME     U66 2
 '@T6G_MB_LIB.T6G(SCH_1):PAGE336_I157@PURE_QUANTA.74LVC1G126SE7(CHIPS)':
 'A': CDS_PINID='A';
NODE_NAME     R6054 1
 '@T6G_MB_LIB.T6G(SCH_1):PAGE81_I83@PURE_QUANTA.Q_RES(CHIPS)':
 'A': CDS_PINID='A';
NET_NAME
'FM_OCP_V3_2_AUX_PWR_EN'
 '@T6G_MB_LIB.T6G(SCH_1):FM_OCP_V3_2_AUX_PWR_EN':
 C_SIGNAL='@t6g_mb_lib.t6g(sch_1):fm_ocp_v3_2_aux_pwr_en';
NODE_NAME     U18 C18
 '@T6G_MB_LIB.T6G(SCH_1):PAGE79_I94@PURE_QUANTA.LCMXO3LF9400C5BG484C(CHIPS)':
 'PT41C': CDS_PINID='PT41C';
NODE_NAME     R1179 2
 '@T6G_MB_LIB.T6G(SCH_1):PAGE79_I155@PURE_QUANTA.Q_RES(CHIPS)':
 'B': CDS_PINID='B';
NET_NAME
'FM_OCP_V3_2_AUX_PWR_R_EN'
 '@T6G_MB_LIB.T6G(SCH_1):FM_OCP_V3_2_AUX_PWR_R_EN':
 C_SIGNAL='@t6g_mb_lib.t6g(sch_1):fm_ocp_v3_2_aux_pwr_r_en';
NODE_NAME     R1176 2
 '@T6G_MB_LIB.T6G(SCH_1):PAGE257_I10@PURE_QUANTA.Q_RES(CHIPS)':
 'B': CDS_PINID='B';
NODE_NAME     R1147 2
 '@T6G_MB_LIB.T6G(SCH_1):PAGE257_I39@PURE_QUANTA.Q_RES(CHIPS)':
 'B': CDS_PINID='B';
NODE_NAME     U37 2
 '@T6G_MB_LIB.T6G(SCH_1):PAGE257_I40@PURE_QUANTA.74LVC1G32GW(CHIPS)':
 'I1': CDS_PINID='I1';
NODE_NAME     R1179 1
 '@T6G_MB_LIB.T6G(SCH_1):PAGE79_I155@PURE_QUANTA.Q_RES(CHIPS)':
 'A': CDS_PINID='A';
NET_NAME
'FM_OCP_V3_2_PWR_GOOD'
 '@T6G_MB_LIB.T6G(SCH_1):FM_OCP_V3_2_PWR_GOOD':
 C_SIGNAL='@t6g_mb_lib.t6g(sch_1):fm_ocp_v3_2_pwr_good';
NODE_NAME     U286 2
 '@T6G_MB_LIB.T6G(SCH_1):PAGE307_I80@PURE_QUANTA.74LVC1G126SE7(CHIPS)':
 'A': CDS_PINID='A';
NODE_NAME     R8413 2
 '@T6G_MB_LIB.T6G(SCH_1):PAGE341_I33@PURE_QUANTA.Q_RES(CHIPS)':
 'B': CDS_PINID='B';
NODE_NAME     J35 OB1
 '@T6G_MB_LIB.T6G(SCH_1):PAGE341_I168@PURE_QUANTA.SCONN168_ME1016810202011(CHIPS)':
 'NIC_PWR_GOOD': CDS_PINID='NIC_PWR_GOOD';
NODE_NAME     U18 B22
 '@T6G_MB_LIB.T6G(SCH_1):PAGE79_I94@PURE_QUANTA.LCMXO3LF9400C5BG484C(CHIPS)':
 'PT44B||R_GPLLC': CDS_PINID='\pt44b||r_gpllc\';
NET_NAME
'FM_P0_PCC0_N'
 '@T6G_MB_LIB.T6G(SCH_1):FM_P0_PCC0_N':
 C_SIGNAL='@t6g_mb_lib.t6g(sch_1):fm_p0_pcc0_n';
NODE_NAME     U25 C22
 '@T6G_MB_LIB.T6G(SCH_1):PAGE27_I227@PURE_QUANTA.GENOA_SP5(CHIPS)':
 'PCC0_L': CDS_PINID='PCC0_L';
NODE_NAME     R1280 1
 '@T6G_MB_LIB.T6G(SCH_1):PAGE80_I102@PURE_QUANTA.Q_RES(CHIPS)':
 'A': CDS_PINID='A';
NODE_NAME     R1287 1
 '@T6G_MB_LIB.T6G(SCH_1):PAGE82_I74@PURE_QUANTA.Q_RES(CHIPS)':
 'A': CDS_PINID='A';
NET_NAME
'FM_P0_PCC0_R_N'
 '@T6G_MB_LIB.T6G(SCH_1):FM_P0_PCC0_R_N':
 C_SIGNAL='@t6g_mb_lib.t6g(sch_1):fm_p0_pcc0_r_n';
NODE_NAME     R1280 2
 '@T6G_MB_LIB.T6G(SCH_1):PAGE80_I102@PURE_QUANTA.Q_RES(CHIPS)':
 'B': CDS_PINID='B';
NODE_NAME     U18 K17
 '@T6G_MB_LIB.T6G(SCH_1):PAGE80_I217@PURE_QUANTA.LCMXO3LF9400C5BG484C(CHIPS)':
 'PR13C': CDS_PINID='PR13C';
NET_NAME
'FM_P0_PCC1_N'
 '@T6G_MB_LIB.T6G(SCH_1):FM_P0_PCC1_N':
 C_SIGNAL='@t6g_mb_lib.t6g(sch_1):fm_p0_pcc1_n';
NODE_NAME     U25 DG72
 '@T6G_MB_LIB.T6G(SCH_1):PAGE27_I227@PURE_QUANTA.GENOA_SP5(CHIPS)':
 'PCC1_L': CDS_PINID='PCC1_L';
NODE_NAME     R1281 1
 '@T6G_MB_LIB.T6G(SCH_1):PAGE80_I101@PURE_QUANTA.Q_RES(CHIPS)':
 'A': CDS_PINID='A';
NODE_NAME     R1288 1
 '@T6G_MB_LIB.T6G(SCH_1):PAGE82_I73@PURE_QUANTA.Q_RES(CHIPS)':
 'A': CDS_PINID='A';
NET_NAME
'FM_P0_PCC1_R_N'
 '@T6G_MB_LIB.T6G(SCH_1):FM_P0_PCC1_R_N':
 C_SIGNAL='@t6g_mb_lib.t6g(sch_1):fm_p0_pcc1_r_n';
NODE_NAME     R1281 2
 '@T6G_MB_LIB.T6G(SCH_1):PAGE80_I101@PURE_QUANTA.Q_RES(CHIPS)':
 'B': CDS_PINID='B';
NODE_NAME     U18 K18
 '@T6G_MB_LIB.T6G(SCH_1):PAGE80_I217@PURE_QUANTA.LCMXO3LF9400C5BG484C(CHIPS)':
 'PR13B': CDS_PINID='PR13B';
NET_NAME
'FM_P12V_HSC_EN_N'
 '@T6G_MB_LIB.T6G(SCH_1):FM_P12V_HSC_EN_N':
 C_SIGNAL='@t6g_mb_lib.t6g(sch_1):fm_p12v_hsc_en_n';
NODE_NAME     U158 D
 '@T6G_MB_LIB.T6G(SCH_1):PAGE365_I6@PURE_QUANTA.MOSFET_NCH_GDS_ESD_PROTECTED(CHIPS)':
 'D': CDS_PINID='D';
NODE_NAME     R2529 1
 '@T6G_MB_LIB.T6G(SCH_1):PAGE365_I7@PURE_QUANTA.Q_RES(CHIPS)':
 'A': CDS_PINID='A';
NODE_NAME     R2528 2
 '@T6G_MB_LIB.T6G(SCH_1):PAGE365_I8@PURE_QUANTA.Q_RES(CHIPS)':
 'B': CDS_PINID='B';
NET_NAME
'FM_P12V_HSC_EN_R'
 '@T6G_MB_LIB.T6G(SCH_1):FM_P12V_HSC_EN_R':
 C_SIGNAL='@t6g_mb_lib.t6g(sch_1):fm_p12v_hsc_en_r';
NODE_NAME     R2531 2
 '@T6G_MB_LIB.T6G(SCH_1):PAGE365_I3@PURE_QUANTA.Q_RES(CHIPS)':
 'B': CDS_PINID='B';
NODE_NAME     U158 G
 '@T6G_MB_LIB.T6G(SCH_1):PAGE365_I6@PURE_QUANTA.MOSFET_NCH_GDS_ESD_PROTECTED(CHIPS)':
 'G': CDS_PINID='G';
NET_NAME
'FM_P12V_HSC_EN_R_N'
 '@T6G_MB_LIB.T6G(SCH_1):FM_P12V_HSC_EN_R_N':
 C_SIGNAL='@t6g_mb_lib.t6g(sch_1):fm_p12v_hsc_en_r_n';
NODE_NAME     R2529 2
 '@T6G_MB_LIB.T6G(SCH_1):PAGE365_I7@PURE_QUANTA.Q_RES(CHIPS)':
 'B': CDS_PINID='B';
NODE_NAME     Q54 G
 '@T6G_MB_LIB.T6G(SCH_1):PAGE365_I14@PURE_QUANTA.MOSFET_NCH_GDS_ESD_PROTECTED(CHIPS)':
 'G': CDS_PINID='G';
NET_NAME
'FM_P1_PCC0_N'
 '@T6G_MB_LIB.T6G(SCH_1):FM_P1_PCC0_N':
 C_SIGNAL='@t6g_mb_lib.t6g(sch_1):fm_p1_pcc0_n';
NODE_NAME     U26 C22
 '@T6G_MB_LIB.T6G(SCH_1):PAGE54_I190@PURE_QUANTA.GENOA_SP5(CHIPS)':
 'PCC0_L': CDS_PINID='PCC0_L';
NODE_NAME     R1278 1
 '@T6G_MB_LIB.T6G(SCH_1):PAGE80_I105@PURE_QUANTA.Q_RES(CHIPS)':
 'A': CDS_PINID='A';
NODE_NAME     R1285 1
 '@T6G_MB_LIB.T6G(SCH_1):PAGE82_I77@PURE_QUANTA.Q_RES(CHIPS)':
 'A': CDS_PINID='A';
NET_NAME
'FM_P1_PCC0_R_N'
 '@T6G_MB_LIB.T6G(SCH_1):FM_P1_PCC0_R_N':
 C_SIGNAL='@t6g_mb_lib.t6g(sch_1):fm_p1_pcc0_r_n';
NODE_NAME     R1278 2
 '@T6G_MB_LIB.T6G(SCH_1):PAGE80_I105@PURE_QUANTA.Q_RES(CHIPS)':
 'B': CDS_PINID='B';
NODE_NAME     U18 J19
 '@T6G_MB_LIB.T6G(SCH_1):PAGE80_I217@PURE_QUANTA.LCMXO3LF9400C5BG484C(CHIPS)':
 'PR11D': CDS_PINID='PR11D';
NET_NAME
'FM_P1_PCC1_N'
 '@T6G_MB_LIB.T6G(SCH_1):FM_P1_PCC1_N':
 C_SIGNAL='@t6g_mb_lib.t6g(sch_1):fm_p1_pcc1_n';
NODE_NAME     U26 DG72
 '@T6G_MB_LIB.T6G(SCH_1):PAGE54_I190@PURE_QUANTA.GENOA_SP5(CHIPS)':
 'PCC1_L': CDS_PINID='PCC1_L';
NODE_NAME     R1279 1
 '@T6G_MB_LIB.T6G(SCH_1):PAGE80_I103@PURE_QUANTA.Q_RES(CHIPS)':
 'A': CDS_PINID='A';
NODE_NAME     R1286 1
 '@T6G_MB_LIB.T6G(SCH_1):PAGE82_I76@PURE_QUANTA.Q_RES(CHIPS)':
 'A': CDS_PINID='A';
NET_NAME
'FM_P1_PCC1_R_N'
 '@T6G_MB_LIB.T6G(SCH_1):FM_P1_PCC1_R_N':
 C_SIGNAL='@t6g_mb_lib.t6g(sch_1):fm_p1_pcc1_r_n';
NODE_NAME     R1279 2
 '@T6G_MB_LIB.T6G(SCH_1):PAGE80_I103@PURE_QUANTA.Q_RES(CHIPS)':
 'B': CDS_PINID='B';
NODE_NAME     U18 J20
 '@T6G_MB_LIB.T6G(SCH_1):PAGE80_I217@PURE_QUANTA.LCMXO3LF9400C5BG484C(CHIPS)':
 'PR12C': CDS_PINID='PR12C';
NET_NAME
'FM_P2E_BUF2_EQA0'
 '@T6G_MB_LIB.T6G(SCH_1):FM_P2E_BUF2_EQA0':
 C_SIGNAL='@t6g_mb_lib.t6g(sch_1):fm_p2e_buf2_eqa0';
NODE_NAME     U6000 10
 '@T6G_MB_LIB.T6G(SCH_1):PAGE111_I1@PURE_QUANTA.DS125BR111RTWR(CHIPS)':
 'EQA0||AD0': CDS_PINID='\eqa0||ad0\';
NODE_NAME     R6173 2
 '@T6G_MB_LIB.T6G(SCH_1):PAGE111_I44@PURE_QUANTA.Q_RES(CHIPS)':
 'B': CDS_PINID='B';
NODE_NAME     R6174 1
 '@T6G_MB_LIB.T6G(SCH_1):PAGE111_I45@PURE_QUANTA.Q_RES(CHIPS)':
 'A': CDS_PINID='A';
NET_NAME
'FM_P2E_BUF2_EQA1'
 '@T6G_MB_LIB.T6G(SCH_1):FM_P2E_BUF2_EQA1':
 C_SIGNAL='@t6g_mb_lib.t6g(sch_1):fm_p2e_buf2_eqa1';
NODE_NAME     U6000 9
 '@T6G_MB_LIB.T6G(SCH_1):PAGE111_I1@PURE_QUANTA.DS125BR111RTWR(CHIPS)':
 'EQA1||AD1': CDS_PINID='\eqa1||ad1\';
NODE_NAME     R6171 2
 '@T6G_MB_LIB.T6G(SCH_1):PAGE111_I48@PURE_QUANTA.Q_RES(CHIPS)':
 'B': CDS_PINID='B';
NODE_NAME     R6172 1
 '@T6G_MB_LIB.T6G(SCH_1):PAGE111_I49@PURE_QUANTA.Q_RES(CHIPS)':
 'A': CDS_PINID='A';
NET_NAME
'FM_P2E_BUF2_EQB0'
 '@T6G_MB_LIB.T6G(SCH_1):FM_P2E_BUF2_EQB0':
 C_SIGNAL='@t6g_mb_lib.t6g(sch_1):fm_p2e_buf2_eqb0';
NODE_NAME     U6000 1
 '@T6G_MB_LIB.T6G(SCH_1):PAGE111_I1@PURE_QUANTA.DS125BR111RTWR(CHIPS)':
 'EQB0||AD3': CDS_PINID='\eqb0||ad3\';
NODE_NAME     R6166 1
 '@T6G_MB_LIB.T6G(SCH_1):PAGE111_I40@PURE_QUANTA.Q_RES(CHIPS)':
 'A': CDS_PINID='A';
NODE_NAME     R6165 2
 '@T6G_MB_LIB.T6G(SCH_1):PAGE111_I41@PURE_QUANTA.Q_RES(CHIPS)':
 'B': CDS_PINID='B';
NET_NAME
'FM_P2E_BUF2_EQB1'
 '@T6G_MB_LIB.T6G(SCH_1):FM_P2E_BUF2_EQB1':
 C_SIGNAL='@t6g_mb_lib.t6g(sch_1):fm_p2e_buf2_eqb1';
NODE_NAME     U6000 2
 '@T6G_MB_LIB.T6G(SCH_1):PAGE111_I1@PURE_QUANTA.DS125BR111RTWR(CHIPS)':
 'EQB1||AD2': CDS_PINID='\eqb1||ad2\';
NODE_NAME     R6164 1
 '@T6G_MB_LIB.T6G(SCH_1):PAGE111_I32@PURE_QUANTA.Q_RES(CHIPS)':
 'A': CDS_PINID='A';
NODE_NAME     R6163 2
 '@T6G_MB_LIB.T6G(SCH_1):PAGE111_I39@PURE_QUANTA.Q_RES(CHIPS)':
 'B': CDS_PINID='B';
NET_NAME
'FM_P2E_BUF2_RXDET'
 '@T6G_MB_LIB.T6G(SCH_1):FM_P2E_BUF2_RXDET':
 C_SIGNAL='@t6g_mb_lib.t6g(sch_1):fm_p2e_buf2_rxdet';
NODE_NAME     U6000 18
 '@T6G_MB_LIB.T6G(SCH_1):PAGE111_I1@PURE_QUANTA.DS125BR111RTWR(CHIPS)':
 'RXDET||DONE#': CDS_PINID='\rxdet||done#\';
NODE_NAME     R6175 2
 '@T6G_MB_LIB.T6G(SCH_1):PAGE111_I63@PURE_QUANTA.Q_RES(CHIPS)':
 'B': CDS_PINID='B';
NODE_NAME     R6176 1
 '@T6G_MB_LIB.T6G(SCH_1):PAGE111_I64@PURE_QUANTA.Q_RES(CHIPS)':
 'A': CDS_PINID='A';
NET_NAME
'FM_P2E_BUF2_SD_TH'
 '@T6G_MB_LIB.T6G(SCH_1):FM_P2E_BUF2_SD_TH':
 C_SIGNAL='@t6g_mb_lib.t6g(sch_1):fm_p2e_buf2_sd_th';
NODE_NAME     U6000 14
 '@T6G_MB_LIB.T6G(SCH_1):PAGE111_I1@PURE_QUANTA.DS125BR111RTWR(CHIPS)':
 'SD_TH': CDS_PINID='SD_TH';
NODE_NAME     R6178 1
 '@T6G_MB_LIB.T6G(SCH_1):PAGE111_I68@PURE_QUANTA.Q_RES(CHIPS)':
 'A': CDS_PINID='A';
NODE_NAME     R6177 2
 '@T6G_MB_LIB.T6G(SCH_1):PAGE111_I77@PURE_QUANTA.Q_RES(CHIPS)':
 'B': CDS_PINID='B';
NET_NAME
'FM_P2E_BUF2_VODA_DB'
 '@T6G_MB_LIB.T6G(SCH_1):FM_P2E_BUF2_VODA_DB':
 C_SIGNAL='@t6g_mb_lib.t6g(sch_1):fm_p2e_buf2_voda_db';
NODE_NAME     U6000 4
 '@T6G_MB_LIB.T6G(SCH_1):PAGE111_I1@PURE_QUANTA.DS125BR111RTWR(CHIPS)':
 'SDA||VODA_DB': CDS_PINID='\sda||voda_db\';
NODE_NAME     R6169 2
 '@T6G_MB_LIB.T6G(SCH_1):PAGE111_I53@PURE_QUANTA.Q_RES(CHIPS)':
 'B': CDS_PINID='B';
NODE_NAME     R6170 1
 '@T6G_MB_LIB.T6G(SCH_1):PAGE111_I60@PURE_QUANTA.Q_RES(CHIPS)':
 'A': CDS_PINID='A';
NET_NAME
'FM_P2E_BUF2_VODB_DB'
 '@T6G_MB_LIB.T6G(SCH_1):FM_P2E_BUF2_VODB_DB':
 C_SIGNAL='@t6g_mb_lib.t6g(sch_1):fm_p2e_buf2_vodb_db';
NODE_NAME     U6000 5
 '@T6G_MB_LIB.T6G(SCH_1):PAGE111_I1@PURE_QUANTA.DS125BR111RTWR(CHIPS)':
 'SCL||VODB_DB': CDS_PINID='\scl||vodb_db\';
NODE_NAME     R6167 2
 '@T6G_MB_LIB.T6G(SCH_1):PAGE111_I57@PURE_QUANTA.Q_RES(CHIPS)':
 'B': CDS_PINID='B';
NODE_NAME     R6168 1
 '@T6G_MB_LIB.T6G(SCH_1):PAGE111_I58@PURE_QUANTA.Q_RES(CHIPS)':
 'A': CDS_PINID='A';
NET_NAME
'FM_P2E_BUF2_VOD_SEL'
 '@T6G_MB_LIB.T6G(SCH_1):FM_P2E_BUF2_VOD_SEL':
 C_SIGNAL='@t6g_mb_lib.t6g(sch_1):fm_p2e_buf2_vod_sel';
NODE_NAME     U6000 17
 '@T6G_MB_LIB.T6G(SCH_1):PAGE111_I1@PURE_QUANTA.DS125BR111RTWR(CHIPS)':
 'VOD_SEL||READEN#': CDS_PINID='\vod_sel||readen#\';
NODE_NAME     R6180 1
 '@T6G_MB_LIB.T6G(SCH_1):PAGE111_I73@PURE_QUANTA.Q_RES(CHIPS)':
 'A': CDS_PINID='A';
NODE_NAME     R6179 2
 '@T6G_MB_LIB.T6G(SCH_1):PAGE111_I78@PURE_QUANTA.Q_RES(CHIPS)':
 'B': CDS_PINID='B';
NET_NAME
'FM_P2E_EN2_N'
 '@T6G_MB_LIB.T6G(SCH_1):FM_P2E_EN2_N':
 C_SIGNAL='@t6g_mb_lib.t6g(sch_1):fm_p2e_en2_n';
NODE_NAME     U6000 6
 '@T6G_MB_LIB.T6G(SCH_1):PAGE111_I1@PURE_QUANTA.DS125BR111RTWR(CHIPS)':
 'PWDN': CDS_PINID='PWDN';
NODE_NAME     R6162 1
 '@T6G_MB_LIB.T6G(SCH_1):PAGE111_I23@PURE_QUANTA.Q_RES(CHIPS)':
 'A': CDS_PINID='A';
NET_NAME
'FM_P2E_EN_N'
 '@T6G_MB_LIB.T6G(SCH_1):FM_P2E_EN_N':
 C_SIGNAL='@t6g_mb_lib.t6g(sch_1):fm_p2e_en_n';
NODE_NAME     U237 11
 '@T6G_MB_LIB.T6G(SCH_1):PAGE110_I63@PURE_QUANTA.PI3EQX12902AZLEX(CHIPS)':
 'EN#': CDS_PINID='\en#\';
NODE_NAME     R4537 1
 '@T6G_MB_LIB.T6G(SCH_1):PAGE110_I67@PURE_QUANTA.Q_RES(CHIPS)':
 'A': CDS_PINID='A';
NET_NAME
'FM_P2E_EQA0'
 '@T6G_MB_LIB.T6G(SCH_1):FM_P2E_EQA0':
 C_SIGNAL='@t6g_mb_lib.t6g(sch_1):fm_p2e_eqa0';
NODE_NAME     R3274 1
 '@T6G_MB_LIB.T6G(SCH_1):PAGE110_I16@PURE_QUANTA.Q_RES(CHIPS)':
 'A': CDS_PINID='A';
NODE_NAME     R3278 1
 '@T6G_MB_LIB.T6G(SCH_1):PAGE110_I18@PURE_QUANTA.Q_RES(CHIPS)':
 'A': CDS_PINID='A';
NODE_NAME     R3277 2
 '@T6G_MB_LIB.T6G(SCH_1):PAGE110_I19@PURE_QUANTA.Q_RES(CHIPS)':
 'B': CDS_PINID='B';
NODE_NAME     U237 21
 '@T6G_MB_LIB.T6G(SCH_1):PAGE110_I63@PURE_QUANTA.PI3EQX12902AZLEX(CHIPS)':
 'EQA0': CDS_PINID='EQA0';
NET_NAME
'FM_P2E_EQA1'
 '@T6G_MB_LIB.T6G(SCH_1):FM_P2E_EQA1':
 C_SIGNAL='@t6g_mb_lib.t6g(sch_1):fm_p2e_eqa1';
NODE_NAME     R3268 1
 '@T6G_MB_LIB.T6G(SCH_1):PAGE110_I2@PURE_QUANTA.Q_RES(CHIPS)':
 'A': CDS_PINID='A';
NODE_NAME     R3272 1
 '@T6G_MB_LIB.T6G(SCH_1):PAGE110_I4@PURE_QUANTA.Q_RES(CHIPS)':
 'A': CDS_PINID='A';
NODE_NAME     R3271 2
 '@T6G_MB_LIB.T6G(SCH_1):PAGE110_I5@PURE_QUANTA.Q_RES(CHIPS)':
 'B': CDS_PINID='B';
NODE_NAME     U237 26
 '@T6G_MB_LIB.T6G(SCH_1):PAGE110_I63@PURE_QUANTA.PI3EQX12902AZLEX(CHIPS)':
 'EQA1': CDS_PINID='EQA1';
NET_NAME
'FM_P2E_EQB0'
 '@T6G_MB_LIB.T6G(SCH_1):FM_P2E_EQB0':
 C_SIGNAL='@t6g_mb_lib.t6g(sch_1):fm_p2e_eqb0';
NODE_NAME     R3282 1
 '@T6G_MB_LIB.T6G(SCH_1):PAGE110_I34@PURE_QUANTA.Q_RES(CHIPS)':
 'A': CDS_PINID='A';
NODE_NAME     R3284 1
 '@T6G_MB_LIB.T6G(SCH_1):PAGE110_I36@PURE_QUANTA.Q_RES(CHIPS)':
 'A': CDS_PINID='A';
NODE_NAME     R3283 2
 '@T6G_MB_LIB.T6G(SCH_1):PAGE110_I37@PURE_QUANTA.Q_RES(CHIPS)':
 'B': CDS_PINID='B';
NODE_NAME     U237 20
 '@T6G_MB_LIB.T6G(SCH_1):PAGE110_I63@PURE_QUANTA.PI3EQX12902AZLEX(CHIPS)':
 'EQB0': CDS_PINID='EQB0';
NET_NAME
'FM_P2E_EQB1'
 '@T6G_MB_LIB.T6G(SCH_1):FM_P2E_EQB1':
 C_SIGNAL='@t6g_mb_lib.t6g(sch_1):fm_p2e_eqb1';
NODE_NAME     R3279 1
 '@T6G_MB_LIB.T6G(SCH_1):PAGE110_I22@PURE_QUANTA.Q_RES(CHIPS)':
 'A': CDS_PINID='A';
NODE_NAME     R3281 1
 '@T6G_MB_LIB.T6G(SCH_1):PAGE110_I25@PURE_QUANTA.Q_RES(CHIPS)':
 'A': CDS_PINID='A';
NODE_NAME     R3280 2
 '@T6G_MB_LIB.T6G(SCH_1):PAGE110_I26@PURE_QUANTA.Q_RES(CHIPS)':
 'B': CDS_PINID='B';
NODE_NAME     U237 15
 '@T6G_MB_LIB.T6G(SCH_1):PAGE110_I63@PURE_QUANTA.PI3EQX12902AZLEX(CHIPS)':
 'EQB1': CDS_PINID='EQB1';
NET_NAME
'FM_P2E_FGA'
 '@T6G_MB_LIB.T6G(SCH_1):FM_P2E_FGA':
 C_SIGNAL='@t6g_mb_lib.t6g(sch_1):fm_p2e_fga';
NODE_NAME     R3273 1
 '@T6G_MB_LIB.T6G(SCH_1):PAGE110_I12@PURE_QUANTA.Q_RES(CHIPS)':
 'A': CDS_PINID='A';
NODE_NAME     R3276 1
 '@T6G_MB_LIB.T6G(SCH_1):PAGE110_I29@PURE_QUANTA.Q_RES(CHIPS)':
 'A': CDS_PINID='A';
NODE_NAME     R3275 2
 '@T6G_MB_LIB.T6G(SCH_1):PAGE110_I32@PURE_QUANTA.Q_RES(CHIPS)':
 'B': CDS_PINID='B';
NODE_NAME     U237 27
 '@T6G_MB_LIB.T6G(SCH_1):PAGE110_I63@PURE_QUANTA.PI3EQX12902AZLEX(CHIPS)':
 'FGA': CDS_PINID='FGA';
NET_NAME
'FM_P2E_FGB'
 '@T6G_MB_LIB.T6G(SCH_1):FM_P2E_FGB':
 C_SIGNAL='@t6g_mb_lib.t6g(sch_1):fm_p2e_fgb';
NODE_NAME     R3267 1
 '@T6G_MB_LIB.T6G(SCH_1):PAGE110_I8@PURE_QUANTA.Q_RES(CHIPS)':
 'A': CDS_PINID='A';
NODE_NAME     R3270 1
 '@T6G_MB_LIB.T6G(SCH_1):PAGE110_I9@PURE_QUANTA.Q_RES(CHIPS)':
 'A': CDS_PINID='A';
NODE_NAME     R3269 2
 '@T6G_MB_LIB.T6G(SCH_1):PAGE110_I14@PURE_QUANTA.Q_RES(CHIPS)':
 'B': CDS_PINID='B';
NODE_NAME     U237 14
 '@T6G_MB_LIB.T6G(SCH_1):PAGE110_I63@PURE_QUANTA.PI3EQX12902AZLEX(CHIPS)':
 'FGB': CDS_PINID='FGB';
NET_NAME
'FM_P2E_MODE'
 '@T6G_MB_LIB.T6G(SCH_1):FM_P2E_MODE':
 C_SIGNAL='@t6g_mb_lib.t6g(sch_1):fm_p2e_mode';
NODE_NAME     U237 30
 '@T6G_MB_LIB.T6G(SCH_1):PAGE110_I63@PURE_QUANTA.PI3EQX12902AZLEX(CHIPS)':
 'MODE': CDS_PINID='MODE';
NODE_NAME     R3293 1
 '@T6G_MB_LIB.T6G(SCH_1):PAGE110_I92@PURE_QUANTA.Q_RES(CHIPS)':
 'A': CDS_PINID='A';
NODE_NAME     R3266 2
 '@T6G_MB_LIB.T6G(SCH_1):PAGE110_I93@PURE_QUANTA.Q_RES(CHIPS)':
 'B': CDS_PINID='B';
NET_NAME
'FM_P2E_SWA'
 '@T6G_MB_LIB.T6G(SCH_1):FM_P2E_SWA':
 C_SIGNAL='@t6g_mb_lib.t6g(sch_1):fm_p2e_swa';
NODE_NAME     U237 29
 '@T6G_MB_LIB.T6G(SCH_1):PAGE110_I63@PURE_QUANTA.PI3EQX12902AZLEX(CHIPS)':
 'SWA': CDS_PINID='SWA';
NODE_NAME     R3288 1
 '@T6G_MB_LIB.T6G(SCH_1):PAGE110_I74@PURE_QUANTA.Q_RES(CHIPS)':
 'A': CDS_PINID='A';
NODE_NAME     R3290 1
 '@T6G_MB_LIB.T6G(SCH_1):PAGE110_I76@PURE_QUANTA.Q_RES(CHIPS)':
 'A': CDS_PINID='A';
NODE_NAME     R3289 2
 '@T6G_MB_LIB.T6G(SCH_1):PAGE110_I77@PURE_QUANTA.Q_RES(CHIPS)':
 'B': CDS_PINID='B';
NET_NAME
'FM_P2E_SWB'
 '@T6G_MB_LIB.T6G(SCH_1):FM_P2E_SWB':
 C_SIGNAL='@t6g_mb_lib.t6g(sch_1):fm_p2e_swb';
NODE_NAME     R3285 1
 '@T6G_MB_LIB.T6G(SCH_1):PAGE110_I42@PURE_QUANTA.Q_RES(CHIPS)':
 'A': CDS_PINID='A';
NODE_NAME     R3287 1
 '@T6G_MB_LIB.T6G(SCH_1):PAGE110_I44@PURE_QUANTA.Q_RES(CHIPS)':
 'A': CDS_PINID='A';
NODE_NAME     R3286 2
 '@T6G_MB_LIB.T6G(SCH_1):PAGE110_I45@PURE_QUANTA.Q_RES(CHIPS)':
 'B': CDS_PINID='B';
NODE_NAME     U237 12
 '@T6G_MB_LIB.T6G(SCH_1):PAGE110_I63@PURE_QUANTA.PI3EQX12902AZLEX(CHIPS)':
 'SWB': CDS_PINID='SWB';
NET_NAME
'FM_P5V_EN'
 '@T6G_MB_LIB.T6G(SCH_1):FM_P5V_EN':
 C_SIGNAL='@t6g_mb_lib.t6g(sch_1):fm_p5v_en';
NODE_NAME     R333 1
 '@T6G_MB_LIB.T6G(SCH_1):PAGE273_I4@PURE_QUANTA.Q_RES(CHIPS)':
 'A': CDS_PINID='A';
NODE_NAME     U18 T16
 '@T6G_MB_LIB.T6G(SCH_1):PAGE80_I216@PURE_QUANTA.LCMXO3LF9400C5BG484C(CHIPS)':
 'PB46D': CDS_PINID='PB46D';
NET_NAME
'FM_PASSWORD_CLEAR_N'
 '@T6G_MB_LIB.T6G(SCH_1):FM_PASSWORD_CLEAR_N':
 C_SIGNAL='@t6g_mb_lib.t6g(sch_1):fm_password_clear_n';
NODE_NAME     R1358 2
 '@T6G_MB_LIB.T6G(SCH_1):PAGE144_I72@PURE_QUANTA.Q_RES(CHIPS)':
 'B': CDS_PINID='B';
NODE_NAME     R1205 2
 '@T6G_MB_LIB.T6G(SCH_1):PAGE28_I100@PURE_QUANTA.Q_RES(CHIPS)':
 'B': CDS_PINID='B';
NODE_NAME     R6106 2
 '@T6G_MB_LIB.T6G(SCH_1):PAGE144_I81@PURE_QUANTA.Q_RES(CHIPS)':
 'B': CDS_PINID='B';
NODE_NAME     SW1 19
 '@T6G_MB_LIB.T6G(SCH_1):PAGE144_I90@PURE_QUANTA.SW20S_DHNF10FQTR(CHIPS)':
 '19': CDS_PINID='\19\';
NET_NAME
'FM_PASSWORD_CLEAR_R_N'
 '@T6G_MB_LIB.T6G(SCH_1):FM_PASSWORD_CLEAR_R_N':
 C_SIGNAL='@t6g_mb_lib.t6g(sch_1):fm_password_clear_r_n';
NODE_NAME     R1205 1
 '@T6G_MB_LIB.T6G(SCH_1):PAGE28_I100@PURE_QUANTA.Q_RES(CHIPS)':
 'A': CDS_PINID='A';
NODE_NAME     U25 DF36
 '@T6G_MB_LIB.T6G(SCH_1):PAGE28_I188@PURE_QUANTA.GENOA_SP5(CHIPS)':
 'AGPIO4||SATA_ACT_L': CDS_PINID='\agpio4||sata_act_l\';
NET_NAME
'FM_PDB_BUF_EN_N'
 '@T6G_MB_LIB.T6G(SCH_1):FM_PDB_BUF_EN_N':
 C_SIGNAL='@t6g_mb_lib.t6g(sch_1):fm_pdb_buf_en_n';
NODE_NAME     U18 T5
 '@T6G_MB_LIB.T6G(SCH_1):PAGE81_I143@PURE_QUANTA.LCMXO3LF9400C5BG484C(CHIPS)':
 'PL26C': CDS_PINID='PL26C';
NODE_NAME     R6073 2
 '@T6G_MB_LIB.T6G(SCH_1):PAGE81_I146@PURE_QUANTA.Q_RES(CHIPS)':
 'B': CDS_PINID='B';
NET_NAME
'FM_PDB_BUF_EN_R1'
 '@T6G_MB_LIB.T6G(SCH_1):FM_PDB_BUF_EN_R1':
 C_SIGNAL='@t6g_mb_lib.t6g(sch_1):fm_pdb_buf_en_r1';
NODE_NAME     R3063 1
 '@T6G_MB_LIB.T6G(SCH_1):PAGE256_I171@PURE_QUANTA.Q_RES(CHIPS)':
 'A': CDS_PINID='A';
NODE_NAME     U190 D
 '@T6G_MB_LIB.T6G(SCH_1):PAGE363_I392@PURE_QUANTA.MOSFET_NCH_GDS_ESD_PROTECTED(CHIPS)':
 'D': CDS_PINID='D';
NODE_NAME     R2794 2
 '@T6G_MB_LIB.T6G(SCH_1):PAGE363_I396@PURE_QUANTA.Q_RES(CHIPS)':
 'B': CDS_PINID='B';
NODE_NAME     R2796 1
 '@T6G_MB_LIB.T6G(SCH_1):PAGE363_I420@PURE_QUANTA.Q_RES(CHIPS)':
 'A': CDS_PINID='A';
NET_NAME
'FM_PDB_BUF_EN_R1_N'
 '@T6G_MB_LIB.T6G(SCH_1):FM_PDB_BUF_EN_R1_N':
 C_SIGNAL='@t6g_mb_lib.t6g(sch_1):fm_pdb_buf_en_r1_n';
NODE_NAME     U190 G
 '@T6G_MB_LIB.T6G(SCH_1):PAGE363_I392@PURE_QUANTA.MOSFET_NCH_GDS_ESD_PROTECTED(CHIPS)':
 'G': CDS_PINID='G';
NODE_NAME     R2793 2
 '@T6G_MB_LIB.T6G(SCH_1):PAGE363_I394@PURE_QUANTA.Q_RES(CHIPS)':
 'B': CDS_PINID='B';
NODE_NAME     R2950 2
 '@T6G_MB_LIB.T6G(SCH_1):PAGE363_I475@PURE_QUANTA.Q_RES(CHIPS)':
 'B': CDS_PINID='B';
NET_NAME
'FM_PDB_BUF_EN_R_N'
 '@T6G_MB_LIB.T6G(SCH_1):FM_PDB_BUF_EN_R_N':
 C_SIGNAL='@t6g_mb_lib.t6g(sch_1):fm_pdb_buf_en_r_n';
NODE_NAME     R2793 1
 '@T6G_MB_LIB.T6G(SCH_1):PAGE363_I394@PURE_QUANTA.Q_RES(CHIPS)':
 'A': CDS_PINID='A';
NODE_NAME     R6073 1
 '@T6G_MB_LIB.T6G(SCH_1):PAGE81_I146@PURE_QUANTA.Q_RES(CHIPS)':
 'A': CDS_PINID='A';
NET_NAME
'FM_PLD_CPU0_PRSNT_HDT'
 '@T6G_MB_LIB.T6G(SCH_1):FM_PLD_CPU0_PRSNT_HDT':
 C_SIGNAL='@t6g_mb_lib.t6g(sch_1):fm_pld_cpu0_prsnt_hdt';
NODE_NAME     R158 1
 '@T6G_MB_LIB.T6G(SCH_1):PAGE80_I154@PURE_QUANTA.Q_RES(CHIPS)':
 'A': CDS_PINID='A';
NODE_NAME     U18 U18
 '@T6G_MB_LIB.T6G(SCH_1):PAGE80_I217@PURE_QUANTA.LCMXO3LF9400C5BG484C(CHIPS)':
 'PR28D': CDS_PINID='PR28D';
NET_NAME
'FM_PLD_CPU0_PRSNT_HDT_N'
 '@T6G_MB_LIB.T6G(SCH_1):FM_PLD_CPU0_PRSNT_HDT_N':
 C_SIGNAL='@t6g_mb_lib.t6g(sch_1):fm_pld_cpu0_prsnt_hdt_n';
NODE_NAME     U153 3
 '@T6G_MB_LIB.T6G(SCH_1):PAGE151_I1@PURE_QUANTA.SN74AUC2G66DCTR(CHIPS)':
 '2C': CDS_PINID='\2c\';
NODE_NAME     R1647 2
 '@T6G_MB_LIB.T6G(SCH_1):PAGE151_I11@PURE_QUANTA.Q_RES(CHIPS)':
 'B': CDS_PINID='B';
NODE_NAME     U13 3
 '@T6G_MB_LIB.T6G(SCH_1):PAGE151_I17@PURE_QUANTA.SN74AUC2G66DCTR(CHIPS)':
 '2C': CDS_PINID='\2c\';
NODE_NAME     Q63 D
 '@T6G_MB_LIB.T6G(SCH_1):PAGE151_I45@PURE_QUANTA.MOSFET_N(CHIPS)':
 'DRAIN': CDS_PINID='DRAIN';
NET_NAME
'FM_PLD_CPU1_PRSNT_HDT'
 '@T6G_MB_LIB.T6G(SCH_1):FM_PLD_CPU1_PRSNT_HDT':
 C_SIGNAL='@t6g_mb_lib.t6g(sch_1):fm_pld_cpu1_prsnt_hdt';
NODE_NAME     R173 1
 '@T6G_MB_LIB.T6G(SCH_1):PAGE80_I163@PURE_QUANTA.Q_RES(CHIPS)':
 'A': CDS_PINID='A';
NODE_NAME     U18 R17
 '@T6G_MB_LIB.T6G(SCH_1):PAGE80_I217@PURE_QUANTA.LCMXO3LF9400C5BG484C(CHIPS)':
 'PR26B': CDS_PINID='PR26B';
NET_NAME
'FM_PLD_CPU1_PRSNT_HDT_N'
 '@T6G_MB_LIB.T6G(SCH_1):FM_PLD_CPU1_PRSNT_HDT_N':
 C_SIGNAL='@t6g_mb_lib.t6g(sch_1):fm_pld_cpu1_prsnt_hdt_n';
NODE_NAME     U14 3
 '@T6G_MB_LIB.T6G(SCH_1):PAGE151_I23@PURE_QUANTA.SN74AUC2G66DCTR(CHIPS)':
 '2C': CDS_PINID='\2c\';
NODE_NAME     R1650 2
 '@T6G_MB_LIB.T6G(SCH_1):PAGE151_I27@PURE_QUANTA.Q_RES(CHIPS)':
 'B': CDS_PINID='B';
NODE_NAME     U154 3
 '@T6G_MB_LIB.T6G(SCH_1):PAGE151_I31@PURE_QUANTA.SN74AUC2G66DCTR(CHIPS)':
 '2C': CDS_PINID='\2c\';
NODE_NAME     Q64 D
 '@T6G_MB_LIB.T6G(SCH_1):PAGE151_I46@PURE_QUANTA.MOSFET_N(CHIPS)':
 'DRAIN': CDS_PINID='DRAIN';
NET_NAME
'FM_PLD_OCP_SFF_AUX_PWR_EN'
 '@T6G_MB_LIB.T6G(SCH_1):FM_PLD_OCP_SFF_AUX_PWR_EN':
 C_SIGNAL='@t6g_mb_lib.t6g(sch_1):fm_pld_ocp_sff_aux_pwr_en';
NODE_NAME     R958 1
 '@T6G_MB_LIB.T6G(SCH_1):PAGE81_I86@PURE_QUANTA.Q_RES(CHIPS)':
 'A': CDS_PINID='A';
NODE_NAME     R9032 2
 '@T6G_MB_LIB.T6G(SCH_1):PAGE340_I2@PURE_QUANTA.Q_RES(CHIPS)':
 'B': CDS_PINID='B';
NODE_NAME     R9030 2
 '@T6G_MB_LIB.T6G(SCH_1):PAGE340_I15@PURE_QUANTA.Q_RES(CHIPS)':
 'B': CDS_PINID='B';
NODE_NAME     U9002 2
 '@T6G_MB_LIB.T6G(SCH_1):PAGE340_I74@PURE_QUANTA.74LVC1G32GW(CHIPS)':
 'I1': CDS_PINID='I1';
NET_NAME
'FM_PLD_OCP_SFF_AUX_PWR_R_EN'
 '@T6G_MB_LIB.T6G(SCH_1):FM_PLD_OCP_SFF_AUX_PWR_R_EN':
 C_SIGNAL='@t6g_mb_lib.t6g(sch_1):fm_pld_ocp_sff_aux_pwr_r_en';
NODE_NAME     U18 M6
 '@T6G_MB_LIB.T6G(SCH_1):PAGE81_I143@PURE_QUANTA.LCMXO3LF9400C5BG484C(CHIPS)':
 'PL17C': CDS_PINID='PL17C';
NODE_NAME     R958 2
 '@T6G_MB_LIB.T6G(SCH_1):PAGE81_I86@PURE_QUANTA.Q_RES(CHIPS)':
 'B': CDS_PINID='B';
NET_NAME
'FM_PLD_OCP_SFF_MAIN_PWR_EN_R'
 '@T6G_MB_LIB.T6G(SCH_1):FM_PLD_OCP_SFF_MAIN_PWR_EN_R':
 C_SIGNAL='@t6g_mb_lib.t6g(sch_1):fm_pld_ocp_sff_main_pwr_en_r';
NODE_NAME     R959 2
 '@T6G_MB_LIB.T6G(SCH_1):PAGE81_I81@PURE_QUANTA.Q_RES(CHIPS)':
 'B': CDS_PINID='B';
NODE_NAME     U18 M7
 '@T6G_MB_LIB.T6G(SCH_1):PAGE81_I143@PURE_QUANTA.LCMXO3LF9400C5BG484C(CHIPS)':
 'PL19D': CDS_PINID='PL19D';
NET_NAME
'FM_PLD_OCP_SFF_PWR_GOOD_R'
 '@T6G_MB_LIB.T6G(SCH_1):FM_PLD_OCP_SFF_PWR_GOOD_R':
 C_SIGNAL='@t6g_mb_lib.t6g(sch_1):fm_pld_ocp_sff_pwr_good_r';
NODE_NAME     R1282 2
 '@T6G_MB_LIB.T6G(SCH_1):PAGE80_I29@PURE_QUANTA.Q_RES(CHIPS)':
 'B': CDS_PINID='B';
NODE_NAME     U18 W10
 '@T6G_MB_LIB.T6G(SCH_1):PAGE80_I216@PURE_QUANTA.LCMXO3LF9400C5BG484C(CHIPS)':
 'PB21B': CDS_PINID='PB21B';
NET_NAME
'FM_PRSNT_CPU0_N'
 '@T6G_MB_LIB.T6G(SCH_1):FM_PRSNT_CPU0_N':
 C_SIGNAL='@t6g_mb_lib.t6g(sch_1):fm_prsnt_cpu0_n';
NODE_NAME     R734 2
 '@T6G_MB_LIB.T6G(SCH_1):PAGE144_I19@PURE_QUANTA.Q_RES(CHIPS)':
 'B': CDS_PINID='B';
NODE_NAME     R1356 2
 '@T6G_MB_LIB.T6G(SCH_1):PAGE144_I77@PURE_QUANTA.Q_RES(CHIPS)':
 'B': CDS_PINID='B';
NODE_NAME     R182 2
 '@T6G_MB_LIB.T6G(SCH_1):PAGE81_I101@PURE_QUANTA.Q_RES(CHIPS)':
 'B': CDS_PINID='B';
NODE_NAME     SW1 17
 '@T6G_MB_LIB.T6G(SCH_1):PAGE144_I90@PURE_QUANTA.SW20S_DHNF10FQTR(CHIPS)':
 '17': CDS_PINID='\17\';
NET_NAME
'FM_PRSNT_CPU0_R_N'
 '@T6G_MB_LIB.T6G(SCH_1):FM_PRSNT_CPU0_R_N':
 C_SIGNAL='@t6g_mb_lib.t6g(sch_1):fm_prsnt_cpu0_r_n';
NODE_NAME     R182 1
 '@T6G_MB_LIB.T6G(SCH_1):PAGE81_I101@PURE_QUANTA.Q_RES(CHIPS)':
 'A': CDS_PINID='A';
NODE_NAME     U18 V1
 '@T6G_MB_LIB.T6G(SCH_1):PAGE81_I143@PURE_QUANTA.LCMXO3LF9400C5BG484C(CHIPS)':
 'PL27B||PCLKC3_0': CDS_PINID='\pl27b||pclkc3_0\';
NET_NAME
'FM_PRSNT_CPU1_N'
 '@T6G_MB_LIB.T6G(SCH_1):FM_PRSNT_CPU1_N':
 C_SIGNAL='@t6g_mb_lib.t6g(sch_1):fm_prsnt_cpu1_n';
NODE_NAME     R744 2
 '@T6G_MB_LIB.T6G(SCH_1):PAGE144_I17@PURE_QUANTA.Q_RES(CHIPS)':
 'B': CDS_PINID='B';
NODE_NAME     R1357 2
 '@T6G_MB_LIB.T6G(SCH_1):PAGE144_I74@PURE_QUANTA.Q_RES(CHIPS)':
 'B': CDS_PINID='B';
NODE_NAME     R271 2
 '@T6G_MB_LIB.T6G(SCH_1):PAGE81_I104@PURE_QUANTA.Q_RES(CHIPS)':
 'B': CDS_PINID='B';
NODE_NAME     SW1 18
 '@T6G_MB_LIB.T6G(SCH_1):PAGE144_I90@PURE_QUANTA.SW20S_DHNF10FQTR(CHIPS)':
 '18': CDS_PINID='\18\';
NET_NAME
'FM_PRSNT_CPU1_R_N'
 '@T6G_MB_LIB.T6G(SCH_1):FM_PRSNT_CPU1_R_N':
 C_SIGNAL='@t6g_mb_lib.t6g(sch_1):fm_prsnt_cpu1_r_n';
NODE_NAME     U18 V5
 '@T6G_MB_LIB.T6G(SCH_1):PAGE81_I143@PURE_QUANTA.LCMXO3LF9400C5BG484C(CHIPS)':
 'PL30C': CDS_PINID='PL30C';
NODE_NAME     R271 1
 '@T6G_MB_LIB.T6G(SCH_1):PAGE81_I104@PURE_QUANTA.Q_RES(CHIPS)':
 'A': CDS_PINID='A';
NET_NAME
'FM_PVDD11_S3_P0_EN'
 '@T6G_MB_LIB.T6G(SCH_1):FM_PVDD11_S3_P0_EN':
 C_SIGNAL='@t6g_mb_lib.t6g(sch_1):fm_pvdd11_s3_p0_en';
NODE_NAME     R227 1
 '@T6G_MB_LIB.T6G(SCH_1):PAGE81_I103@PURE_QUANTA.Q_RES(CHIPS)':
 'A': CDS_PINID='A';
NODE_NAME     U18 W4
 '@T6G_MB_LIB.T6G(SCH_1):PAGE81_I143@PURE_QUANTA.LCMXO3LF9400C5BG484C(CHIPS)':
 'PL30B': CDS_PINID='PL30B';
NET_NAME
'FM_PVDD11_S3_P0_OCP_N'
 '@T6G_MB_LIB.T6G(SCH_1):FM_PVDD11_S3_P0_OCP_N':
 C_SIGNAL='@t6g_mb_lib.t6g(sch_1):fm_pvdd11_s3_p0_ocp_n';
NODE_NAME     U18 H3
 '@T6G_MB_LIB.T6G(SCH_1):PAGE81_I143@PURE_QUANTA.LCMXO3LF9400C5BG484C(CHIPS)':
 'PL7D': CDS_PINID='PL7D';
NODE_NAME     R226 1
 '@T6G_MB_LIB.T6G(SCH_1):PAGE81_I111@PURE_QUANTA.Q_RES(CHIPS)':
 'A': CDS_PINID='A';
NET_NAME
'FM_PVDD11_S3_P1_EN'
 '@T6G_MB_LIB.T6G(SCH_1):FM_PVDD11_S3_P1_EN':
 C_SIGNAL='@t6g_mb_lib.t6g(sch_1):fm_pvdd11_s3_p1_en';
NODE_NAME     R279 2
 '@T6G_MB_LIB.T6G(SCH_1):PAGE80_I58@PURE_QUANTA.Q_RES(CHIPS)':
 'B': CDS_PINID='B';
NODE_NAME     U18 AA7
 '@T6G_MB_LIB.T6G(SCH_1):PAGE80_I216@PURE_QUANTA.LCMXO3LF9400C5BG484C(CHIPS)':
 'PB13A': CDS_PINID='PB13A';
NET_NAME
'FM_PVDD11_S3_P1_OCP_N'
 '@T6G_MB_LIB.T6G(SCH_1):FM_PVDD11_S3_P1_OCP_N':
 C_SIGNAL='@t6g_mb_lib.t6g(sch_1):fm_pvdd11_s3_p1_ocp_n';
NODE_NAME     U18 H4
 '@T6G_MB_LIB.T6G(SCH_1):PAGE81_I143@PURE_QUANTA.LCMXO3LF9400C5BG484C(CHIPS)':
 'PL7C': CDS_PINID='PL7C';
NODE_NAME     R278 1
 '@T6G_MB_LIB.T6G(SCH_1):PAGE81_I113@PURE_QUANTA.Q_RES(CHIPS)':
 'A': CDS_PINID='A';
NET_NAME
'FM_PVDD18_S5_P0_EN'
 '@T6G_MB_LIB.T6G(SCH_1):FM_PVDD18_S5_P0_EN':
 C_SIGNAL='@t6g_mb_lib.t6g(sch_1):fm_pvdd18_s5_p0_en';
NODE_NAME     R176 2
 '@T6G_MB_LIB.T6G(SCH_1):PAGE80_I33@PURE_QUANTA.Q_RES(CHIPS)':
 'B': CDS_PINID='B';
NODE_NAME     U18 AA8
 '@T6G_MB_LIB.T6G(SCH_1):PAGE80_I216@PURE_QUANTA.LCMXO3LF9400C5BG484C(CHIPS)':
 'PB18A': CDS_PINID='PB18A';
NET_NAME
'FM_PVDD33_S5_EN'
 '@T6G_MB_LIB.T6G(SCH_1):FM_PVDD33_S5_EN':
 C_SIGNAL='@t6g_mb_lib.t6g(sch_1):fm_pvdd33_s5_en';
NODE_NAME     R224 2
 '@T6G_MB_LIB.T6G(SCH_1):PAGE80_I36@PURE_QUANTA.Q_RES(CHIPS)':
 'B': CDS_PINID='B';
NODE_NAME     U18 V9
 '@T6G_MB_LIB.T6G(SCH_1):PAGE80_I216@PURE_QUANTA.LCMXO3LF9400C5BG484C(CHIPS)':
 'PB16C': CDS_PINID='PB16C';
NET_NAME
'FM_PVDDCR_CPU0_P0_OCP_N'
 '@T6G_MB_LIB.T6G(SCH_1):FM_PVDDCR_CPU0_P0_OCP_N':
 C_SIGNAL='@t6g_mb_lib.t6g(sch_1):fm_pvddcr_cpu0_p0_ocp_n';
NODE_NAME     R231 2
 '@T6G_MB_LIB.T6G(SCH_1):PAGE81_I60@PURE_QUANTA.Q_RES(CHIPS)':
 'B': CDS_PINID='B';
NODE_NAME     U18 F1
 '@T6G_MB_LIB.T6G(SCH_1):PAGE81_I143@PURE_QUANTA.LCMXO3LF9400C5BG484C(CHIPS)':
 'PL6B': CDS_PINID='PL6B';
NET_NAME
'FM_PVDDCR_CPU0_P1_OCP_N'
 '@T6G_MB_LIB.T6G(SCH_1):FM_PVDDCR_CPU0_P1_OCP_N':
 C_SIGNAL='@t6g_mb_lib.t6g(sch_1):fm_pvddcr_cpu0_p1_ocp_n';
NODE_NAME     U18 G2
 '@T6G_MB_LIB.T6G(SCH_1):PAGE81_I143@PURE_QUANTA.LCMXO3LF9400C5BG484C(CHIPS)':
 'PL7A||PCLKT5_0': CDS_PINID='\pl7a||pclkt5_0\';
NODE_NAME     R284 1
 '@T6G_MB_LIB.T6G(SCH_1):PAGE81_I140@PURE_QUANTA.Q_RES(CHIPS)':
 'A': CDS_PINID='A';
NET_NAME
'FM_PVDDCR_CPU0_P1_R_EN'
 '@T6G_MB_LIB.T6G(SCH_1):FM_PVDDCR_CPU0_P1_R_EN':
 C_SIGNAL='@t6g_mb_lib.t6g(sch_1):fm_pvddcr_cpu0_p1_r_en';
NODE_NAME     R208 2
 '@T6G_MB_LIB.T6G(SCH_1):PAGE80_I65@PURE_QUANTA.Q_RES(CHIPS)':
 'B': CDS_PINID='B';
NODE_NAME     U18 W5
 '@T6G_MB_LIB.T6G(SCH_1):PAGE80_I216@PURE_QUANTA.LCMXO3LF9400C5BG484C(CHIPS)':
 'PB7D': CDS_PINID='PB7D';
NET_NAME
'FM_PVDDCR_CPU1_P0_EN'
 '@T6G_MB_LIB.T6G(SCH_1):FM_PVDDCR_CPU1_P0_EN':
 C_SIGNAL='@t6g_mb_lib.t6g(sch_1):fm_pvddcr_cpu1_p0_en';
NODE_NAME     R232 1
 '@T6G_MB_LIB.T6G(SCH_1):PAGE81_I51@PURE_QUANTA.Q_RES(CHIPS)':
 'A': CDS_PINID='A';
NODE_NAME     R8058 1
 '@T6G_MB_LIB.T6G(SCH_1):PAGE175_I88@PURE_QUANTA.Q_RES(CHIPS)':
 'A': CDS_PINID='A';
NET_NAME
'FM_PVDDCR_CPU1_P0_OCP_N'
 '@T6G_MB_LIB.T6G(SCH_1):FM_PVDDCR_CPU1_P0_OCP_N':
 C_SIGNAL='@t6g_mb_lib.t6g(sch_1):fm_pvddcr_cpu1_p0_ocp_n';
NODE_NAME     R137 2
 '@T6G_MB_LIB.T6G(SCH_1):PAGE81_I59@PURE_QUANTA.Q_RES(CHIPS)':
 'B': CDS_PINID='B';
NODE_NAME     U18 G3
 '@T6G_MB_LIB.T6G(SCH_1):PAGE81_I143@PURE_QUANTA.LCMXO3LF9400C5BG484C(CHIPS)':
 'PL6C': CDS_PINID='PL6C';
NET_NAME
'FM_PVDDCR_CPU1_P0_R_EN'
 '@T6G_MB_LIB.T6G(SCH_1):FM_PVDDCR_CPU1_P0_R_EN':
 C_SIGNAL='@t6g_mb_lib.t6g(sch_1):fm_pvddcr_cpu1_p0_r_en';
NODE_NAME     R232 2
 '@T6G_MB_LIB.T6G(SCH_1):PAGE81_I51@PURE_QUANTA.Q_RES(CHIPS)':
 'B': CDS_PINID='B';
NODE_NAME     U18 P7
 '@T6G_MB_LIB.T6G(SCH_1):PAGE81_I143@PURE_QUANTA.LCMXO3LF9400C5BG484C(CHIPS)':
 'PL24D': CDS_PINID='PL24D';
NET_NAME
'FM_PVDDCR_CPU1_P1_EN'
 '@T6G_MB_LIB.T6G(SCH_1):FM_PVDDCR_CPU1_P1_EN':
 C_SIGNAL='@t6g_mb_lib.t6g(sch_1):fm_pvddcr_cpu1_p1_en';
NODE_NAME     R8235 1
 '@T6G_MB_LIB.T6G(SCH_1):PAGE192_I87@PURE_QUANTA.Q_RES(CHIPS)':
 'A': CDS_PINID='A';
NODE_NAME     R285 2
 '@T6G_MB_LIB.T6G(SCH_1):PAGE81_I105@PURE_QUANTA.Q_RES(CHIPS)':
 'B': CDS_PINID='B';
NET_NAME
'FM_PVDDCR_CPU1_P1_OCP_N'
 '@T6G_MB_LIB.T6G(SCH_1):FM_PVDDCR_CPU1_P1_OCP_N':
 C_SIGNAL='@t6g_mb_lib.t6g(sch_1):fm_pvddcr_cpu1_p1_ocp_n';
NODE_NAME     R141 2
 '@T6G_MB_LIB.T6G(SCH_1):PAGE81_I57@PURE_QUANTA.Q_RES(CHIPS)':
 'B': CDS_PINID='B';
NODE_NAME     U18 G4
 '@T6G_MB_LIB.T6G(SCH_1):PAGE81_I143@PURE_QUANTA.LCMXO3LF9400C5BG484C(CHIPS)':
 'PL6D': CDS_PINID='PL6D';
NET_NAME
'FM_PVDDCR_CPU1_P1_R_EN'
 '@T6G_MB_LIB.T6G(SCH_1):FM_PVDDCR_CPU1_P1_R_EN':
 C_SIGNAL='@t6g_mb_lib.t6g(sch_1):fm_pvddcr_cpu1_p1_r_en';
NODE_NAME     U18 T7
 '@T6G_MB_LIB.T6G(SCH_1):PAGE81_I143@PURE_QUANTA.LCMXO3LF9400C5BG484C(CHIPS)':
 'PL30D': CDS_PINID='PL30D';
NODE_NAME     R285 1
 '@T6G_MB_LIB.T6G(SCH_1):PAGE81_I105@PURE_QUANTA.Q_RES(CHIPS)':
 'A': CDS_PINID='A';
NET_NAME
'FM_PVDDIO_P0_EN'
 '@T6G_MB_LIB.T6G(SCH_1):FM_PVDDIO_P0_EN':
 C_SIGNAL='@t6g_mb_lib.t6g(sch_1):fm_pvddio_p0_en';
NODE_NAME     R229 2
 '@T6G_MB_LIB.T6G(SCH_1):PAGE80_I68@PURE_QUANTA.Q_RES(CHIPS)':
 'B': CDS_PINID='B';
NODE_NAME     U18 V6
 '@T6G_MB_LIB.T6G(SCH_1):PAGE80_I216@PURE_QUANTA.LCMXO3LF9400C5BG484C(CHIPS)':
 'PB5C': CDS_PINID='PB5C';
NET_NAME
'FM_PVDDIO_P1_EN'
 '@T6G_MB_LIB.T6G(SCH_1):FM_PVDDIO_P1_EN':
 C_SIGNAL='@t6g_mb_lib.t6g(sch_1):fm_pvddio_p1_en';
NODE_NAME     R282 2
 '@T6G_MB_LIB.T6G(SCH_1):PAGE80_I31@PURE_QUANTA.Q_RES(CHIPS)':
 'B': CDS_PINID='B';
NODE_NAME     U18 AA9
 '@T6G_MB_LIB.T6G(SCH_1):PAGE80_I216@PURE_QUANTA.LCMXO3LF9400C5BG484C(CHIPS)':
 'PB19A': CDS_PINID='PB19A';
NET_NAME
'FM_PWRGD_CPU0_PWROK'
 '@T6G_MB_LIB.T6G(SCH_1):FM_PWRGD_CPU0_PWROK':
 C_SIGNAL='@t6g_mb_lib.t6g(sch_1):fm_pwrgd_cpu0_pwrok';
NODE_NAME     R242 2
 '@T6G_MB_LIB.T6G(SCH_1):PAGE80_I110@PURE_QUANTA.Q_RES(CHIPS)':
 'B': CDS_PINID='B';
NODE_NAME     U18 H19
 '@T6G_MB_LIB.T6G(SCH_1):PAGE80_I217@PURE_QUANTA.LCMXO3LF9400C5BG484C(CHIPS)':
 'PR10A': CDS_PINID='PR10A';
NET_NAME
'FM_PWRGD_CPU1_PWROK'
 '@T6G_MB_LIB.T6G(SCH_1):FM_PWRGD_CPU1_PWROK':
 C_SIGNAL='@t6g_mb_lib.t6g(sch_1):fm_pwrgd_cpu1_pwrok';
NODE_NAME     R203 2
 '@T6G_MB_LIB.T6G(SCH_1):PAGE80_I106@PURE_QUANTA.Q_RES(CHIPS)':
 'B': CDS_PINID='B';
NODE_NAME     U18 J18
 '@T6G_MB_LIB.T6G(SCH_1):PAGE80_I217@PURE_QUANTA.LCMXO3LF9400C5BG484C(CHIPS)':
 'PR11C': CDS_PINID='PR11C';
NET_NAME
'FM_PWRGD_P1V8_RETIMER_CPU0'
 '@T6G_MB_LIB.T6G(SCH_1):FM_PWRGD_P1V8_RETIMER_CPU0':
 C_SIGNAL='@t6g_mb_lib.t6g(sch_1):fm_pwrgd_p1v8_retimer_cpu0';
NODE_NAME     U18 T9
 '@T6G_MB_LIB.T6G(SCH_1):PAGE80_I216@PURE_QUANTA.LCMXO3LF9400C5BG484C(CHIPS)':
 'PB16A||MCLK||CCLK': CDS_PINID='\pb16a||mclk||cclk\';
NODE_NAME     R6506 2
 '@T6G_MB_LIB.T6G(SCH_1):PAGE469_I37@PURE_QUANTA.Q_RES(CHIPS)':
 'B': CDS_PINID='B';
NODE_NAME     C6758 1
 '@T6G_MB_LIB.T6G(SCH_1):PAGE469_I42@PURE_QUANTA.Q_CAP(CHIPS)':
 'A': CDS_PINID='A';
NET_NAME
'FM_PWRGD_P1V8_RETIMER_CPU1'
 '@T6G_MB_LIB.T6G(SCH_1):FM_PWRGD_P1V8_RETIMER_CPU1':
 C_SIGNAL='@t6g_mb_lib.t6g(sch_1):fm_pwrgd_p1v8_retimer_cpu1';
NODE_NAME     U18 U9
 '@T6G_MB_LIB.T6G(SCH_1):PAGE80_I216@PURE_QUANTA.LCMXO3LF9400C5BG484C(CHIPS)':
 'PB16B||SO||SPISO': CDS_PINID='\pb16b||so||spiso\';
NODE_NAME     R645 2
 '@T6G_MB_LIB.T6G(SCH_1):PAGE470_I36@PURE_QUANTA.Q_RES(CHIPS)':
 'B': CDS_PINID='B';
NODE_NAME     C109 1
 '@T6G_MB_LIB.T6G(SCH_1):PAGE470_I39@PURE_QUANTA.Q_CAP(CHIPS)':
 'A': CDS_PINID='A';
NET_NAME
'FM_PWRGD_PVDD11_S3_P0'
 '@T6G_MB_LIB.T6G(SCH_1):FM_PWRGD_PVDD11_S3_P0':
 C_SIGNAL='@t6g_mb_lib.t6g(sch_1):fm_pwrgd_pvdd11_s3_p0';
NODE_NAME     R228 2
 '@T6G_MB_LIB.T6G(SCH_1):PAGE80_I66@PURE_QUANTA.Q_RES(CHIPS)':
 'B': CDS_PINID='B';
NODE_NAME     U18 Y4
 '@T6G_MB_LIB.T6G(SCH_1):PAGE80_I216@PURE_QUANTA.LCMXO3LF9400C5BG484C(CHIPS)':
 'PB7C': CDS_PINID='PB7C';
NET_NAME
'FM_PWRGD_PVDD11_S3_P1'
 '@T6G_MB_LIB.T6G(SCH_1):FM_PWRGD_PVDD11_S3_P1':
 C_SIGNAL='@t6g_mb_lib.t6g(sch_1):fm_pwrgd_pvdd11_s3_p1';
NODE_NAME     R280 2
 '@T6G_MB_LIB.T6G(SCH_1):PAGE80_I59@PURE_QUANTA.Q_RES(CHIPS)':
 'B': CDS_PINID='B';
NODE_NAME     U18 AB7
 '@T6G_MB_LIB.T6G(SCH_1):PAGE80_I216@PURE_QUANTA.LCMXO3LF9400C5BG484C(CHIPS)':
 'PB13B': CDS_PINID='PB13B';
NET_NAME
'FM_PWRGD_PVDD18_S5_P0'
 '@T6G_MB_LIB.T6G(SCH_1):FM_PWRGD_PVDD18_S5_P0':
 C_SIGNAL='@t6g_mb_lib.t6g(sch_1):fm_pwrgd_pvdd18_s5_p0';
NODE_NAME     R177 2
 '@T6G_MB_LIB.T6G(SCH_1):PAGE184_I52@PURE_QUANTA.Q_RES(CHIPS)':
 'B': CDS_PINID='B';
NODE_NAME     U18 AB8
 '@T6G_MB_LIB.T6G(SCH_1):PAGE80_I216@PURE_QUANTA.LCMXO3LF9400C5BG484C(CHIPS)':
 'PB18B': CDS_PINID='PB18B';
NODE_NAME     C5001 1
 '@T6G_MB_LIB.T6G(SCH_1):PAGE184_I56@PURE_QUANTA.Q_CAP(CHIPS)':
 'A': CDS_PINID='A';
NET_NAME
'FM_PWRGD_PVDD33_S5'
 '@T6G_MB_LIB.T6G(SCH_1):FM_PWRGD_PVDD33_S5':
 C_SIGNAL='@t6g_mb_lib.t6g(sch_1):fm_pwrgd_pvdd33_s5';
NODE_NAME     R225 2
 '@T6G_MB_LIB.T6G(SCH_1):PAGE167_I33@PURE_QUANTA.Q_RES(CHIPS)':
 'B': CDS_PINID='B';
NODE_NAME     U18 AB6
 '@T6G_MB_LIB.T6G(SCH_1):PAGE80_I216@PURE_QUANTA.LCMXO3LF9400C5BG484C(CHIPS)':
 'PB11B': CDS_PINID='PB11B';
NODE_NAME     C5002 1
 '@T6G_MB_LIB.T6G(SCH_1):PAGE167_I43@PURE_QUANTA.Q_CAP(CHIPS)':
 'A': CDS_PINID='A';
NET_NAME
'FM_PWRGD_PVDDCR_CPU0_P1'
 '@T6G_MB_LIB.T6G(SCH_1):FM_PWRGD_PVDDCR_CPU0_P1':
 C_SIGNAL='@t6g_mb_lib.t6g(sch_1):fm_pwrgd_pvddcr_cpu0_p1';
NODE_NAME     R209 2
 '@T6G_MB_LIB.T6G(SCH_1):PAGE80_I61@PURE_QUANTA.Q_RES(CHIPS)':
 'B': CDS_PINID='B';
NODE_NAME     U18 Y5
 '@T6G_MB_LIB.T6G(SCH_1):PAGE80_I216@PURE_QUANTA.LCMXO3LF9400C5BG484C(CHIPS)':
 'PB10C': CDS_PINID='PB10C';
NET_NAME
'FM_PWRGD_PVDDCR_CPU1_P0'
 '@T6G_MB_LIB.T6G(SCH_1):FM_PWRGD_PVDDCR_CPU1_P0':
 C_SIGNAL='@t6g_mb_lib.t6g(sch_1):fm_pwrgd_pvddcr_cpu1_p0';
NODE_NAME     R233 2
 '@T6G_MB_LIB.T6G(SCH_1):PAGE81_I54@PURE_QUANTA.Q_RES(CHIPS)':
 'B': CDS_PINID='B';
NODE_NAME     U18 R7
 '@T6G_MB_LIB.T6G(SCH_1):PAGE81_I143@PURE_QUANTA.LCMXO3LF9400C5BG484C(CHIPS)':
 'PL25D': CDS_PINID='PL25D';
NET_NAME
'FM_PWRGD_PVDDCR_CPU1_P1'
 '@T6G_MB_LIB.T6G(SCH_1):FM_PWRGD_PVDDCR_CPU1_P1':
 C_SIGNAL='@t6g_mb_lib.t6g(sch_1):fm_pwrgd_pvddcr_cpu1_p1';
NODE_NAME     R286 2
 '@T6G_MB_LIB.T6G(SCH_1):PAGE80_I62@PURE_QUANTA.Q_RES(CHIPS)':
 'B': CDS_PINID='B';
NODE_NAME     U18 T8
 '@T6G_MB_LIB.T6G(SCH_1):PAGE80_I216@PURE_QUANTA.LCMXO3LF9400C5BG484C(CHIPS)':
 'PB8D': CDS_PINID='PB8D';
NET_NAME
'FM_PWRGD_PVDDIO_P0'
 '@T6G_MB_LIB.T6G(SCH_1):FM_PWRGD_PVDDIO_P0':
 C_SIGNAL='@t6g_mb_lib.t6g(sch_1):fm_pwrgd_pvddio_p0';
NODE_NAME     R230 2
 '@T6G_MB_LIB.T6G(SCH_1):PAGE80_I67@PURE_QUANTA.Q_RES(CHIPS)':
 'B': CDS_PINID='B';
NODE_NAME     U18 U6
 '@T6G_MB_LIB.T6G(SCH_1):PAGE80_I216@PURE_QUANTA.LCMXO3LF9400C5BG484C(CHIPS)':
 'PB5D': CDS_PINID='PB5D';
NET_NAME
'FM_PWRGD_PVDDIO_P1'
 '@T6G_MB_LIB.T6G(SCH_1):FM_PWRGD_PVDDIO_P1':
 C_SIGNAL='@t6g_mb_lib.t6g(sch_1):fm_pwrgd_pvddio_p1';
NODE_NAME     R283 2
 '@T6G_MB_LIB.T6G(SCH_1):PAGE80_I30@PURE_QUANTA.Q_RES(CHIPS)':
 'B': CDS_PINID='B';
NODE_NAME     U18 AB9
 '@T6G_MB_LIB.T6G(SCH_1):PAGE80_I216@PURE_QUANTA.LCMXO3LF9400C5BG484C(CHIPS)':
 'PB19B': CDS_PINID='PB19B';
NET_NAME
'FM_ROM_LS_EN'
 '@T6G_MB_LIB.T6G(SCH_1):FM_ROM_LS_EN':
 C_SIGNAL='@t6g_mb_lib.t6g(sch_1):fm_rom_ls_en';
NODE_NAME     R1564 1
 '@T6G_MB_LIB.T6G(SCH_1):PAGE80_I156@PURE_QUANTA.Q_RES(CHIPS)':
 'A': CDS_PINID='A';
NODE_NAME     U18 Y22
 '@T6G_MB_LIB.T6G(SCH_1):PAGE80_I217@PURE_QUANTA.LCMXO3LF9400C5BG484C(CHIPS)':
 'PR28A': CDS_PINID='PR28A';
NET_NAME
'FM_ROM_SD_LS_OE'
 '@T6G_MB_LIB.T6G(SCH_1):FM_ROM_SD_LS_OE':
 C_SIGNAL='@t6g_mb_lib.t6g(sch_1):fm_rom_sd_ls_oe';
NODE_NAME     R1616 1
 '@T6G_MB_LIB.T6G(SCH_1):PAGE80_I157@PURE_QUANTA.Q_RES(CHIPS)':
 'A': CDS_PINID='A';
NODE_NAME     U18 W21
 '@T6G_MB_LIB.T6G(SCH_1):PAGE80_I217@PURE_QUANTA.LCMXO3LF9400C5BG484C(CHIPS)':
 'PR28B': CDS_PINID='PR28B';
NET_NAME
'FM_RST_CPU0_RESETL_N'
 '@T6G_MB_LIB.T6G(SCH_1):FM_RST_CPU0_RESETL_N':
 C_SIGNAL='@t6g_mb_lib.t6g(sch_1):fm_rst_cpu0_resetl_n';
NODE_NAME     R241 2
 '@T6G_MB_LIB.T6G(SCH_1):PAGE80_I114@PURE_QUANTA.Q_RES(CHIPS)':
 'B': CDS_PINID='B';
NODE_NAME     U18 H22
 '@T6G_MB_LIB.T6G(SCH_1):PAGE80_I217@PURE_QUANTA.LCMXO3LF9400C5BG484C(CHIPS)':
 'PR7A': CDS_PINID='PR7A';
NET_NAME
'FM_RST_CPU1_RESETL_N'
 '@T6G_MB_LIB.T6G(SCH_1):FM_RST_CPU1_RESETL_N':
 C_SIGNAL='@t6g_mb_lib.t6g(sch_1):fm_rst_cpu1_resetl_n';
NODE_NAME     R57 2
 '@T6G_MB_LIB.T6G(SCH_1):PAGE80_I113@PURE_QUANTA.Q_RES(CHIPS)':
 'B': CDS_PINID='B';
NODE_NAME     U18 H21
 '@T6G_MB_LIB.T6G(SCH_1):PAGE80_I217@PURE_QUANTA.LCMXO3LF9400C5BG484C(CHIPS)':
 'PR7B': CDS_PINID='PR7B';
NET_NAME
'FM_RST_PERST_SCM_N'
 '@T6G_MB_LIB.T6G(SCH_1):FM_RST_PERST_SCM_N':
 C_SIGNAL='@t6g_mb_lib.t6g(sch_1):fm_rst_perst_scm_n';
NODE_NAME     J41 A51
 '@T6G_MB_LIB.T6G(SCH_1):PAGE348_I176@PURE_QUANTA.SCONN168_ME1016810202011(CHIPS)':
 'PERP10': CDS_PINID='PERP10';
NODE_NAME     R957 2
 '@T6G_MB_LIB.T6G(SCH_1):PAGE80_I130@PURE_QUANTA.Q_RES(CHIPS)':
 'B': CDS_PINID='B';
NET_NAME
'FM_RST_PERST_SCM_R_N'
 '@T6G_MB_LIB.T6G(SCH_1):FM_RST_PERST_SCM_R_N':
 C_SIGNAL='@t6g_mb_lib.t6g(sch_1):fm_rst_perst_scm_r_n';
NODE_NAME     R957 1
 '@T6G_MB_LIB.T6G(SCH_1):PAGE80_I130@PURE_QUANTA.Q_RES(CHIPS)':
 'A': CDS_PINID='A';
NODE_NAME     U18 AB13
 '@T6G_MB_LIB.T6G(SCH_1):PAGE80_I216@PURE_QUANTA.LCMXO3LF9400C5BG484C(CHIPS)':
 'PB30A': CDS_PINID='PB30A';
NET_NAME
'FM_SCM_PRSNT1_N'
 '@T6G_MB_LIB.T6G(SCH_1):FM_SCM_PRSNT1_N':
 C_SIGNAL='@t6g_mb_lib.t6g(sch_1):fm_scm_prsnt1_n';
NODE_NAME     R1854 2
 '@T6G_MB_LIB.T6G(SCH_1):PAGE350_I2@PURE_QUANTA.Q_RES(CHIPS)':
 'B': CDS_PINID='B';
NODE_NAME     R1856 1
 '@T6G_MB_LIB.T6G(SCH_1):PAGE350_I3@PURE_QUANTA.Q_RES(CHIPS)':
 'A': CDS_PINID='A';
NODE_NAME     J41 A57
 '@T6G_MB_LIB.T6G(SCH_1):PAGE348_I176@PURE_QUANTA.SCONN168_ME1016810202011(CHIPS)':
 'PERP12': CDS_PINID='PERP12';
NODE_NAME     U18 M2
 '@T6G_MB_LIB.T6G(SCH_1):PAGE81_I143@PURE_QUANTA.LCMXO3LF9400C5BG484C(CHIPS)':
 'PL16B||PCLKC4_0': CDS_PINID='\pl16b||pclkc4_0\';
NET_NAME
'FM_SCM_PRSNT1_R_N'
 '@T6G_MB_LIB.T6G(SCH_1):FM_SCM_PRSNT1_R_N':
 C_SIGNAL='@t6g_mb_lib.t6g(sch_1):fm_scm_prsnt1_r_n';
NODE_NAME     R1856 2
 '@T6G_MB_LIB.T6G(SCH_1):PAGE350_I3@PURE_QUANTA.Q_RES(CHIPS)':
 'B': CDS_PINID='B';
NODE_NAME     Q39 G
 '@T6G_MB_LIB.T6G(SCH_1):PAGE350_I9@PURE_QUANTA.MOSFET_NCH_GDS_ESD_PROTECTED(CHIPS)':
 'G': CDS_PINID='G';
NET_NAME
'FM_SEC_MUX_OE_N'
 '@T6G_MB_LIB.T6G(SCH_1):FM_SEC_MUX_OE_N':
 C_SIGNAL='@t6g_mb_lib.t6g(sch_1):fm_sec_mux_oe_n';
NODE_NAME     U6 6
 '@T6G_MB_LIB.T6G(SCH_1):PAGE138_I67@PURE_QUANTA.PI3CSW12ZUAEX(CHIPS)':
 'OE#': CDS_PINID='\oe#\';
NODE_NAME     R6183 1
 '@T6G_MB_LIB.T6G(SCH_1):PAGE81_I164@PURE_QUANTA.Q_RES(CHIPS)':
 'A': CDS_PINID='A';
NODE_NAME     R6185 1
 '@T6G_MB_LIB.T6G(SCH_1):PAGE82_I143@PURE_QUANTA.Q_RES(CHIPS)':
 'A': CDS_PINID='A';
NODE_NAME     R6186 1
 '@T6G_MB_LIB.T6G(SCH_1):PAGE82_I146@PURE_QUANTA.Q_RES(CHIPS)':
 'A': CDS_PINID='A';
NET_NAME
'FM_SEC_MUX_OE_R_N'
 '@T6G_MB_LIB.T6G(SCH_1):FM_SEC_MUX_OE_R_N':
 C_SIGNAL='@t6g_mb_lib.t6g(sch_1):fm_sec_mux_oe_r_n';
NODE_NAME     U18 K2
 '@T6G_MB_LIB.T6G(SCH_1):PAGE81_I143@PURE_QUANTA.LCMXO3LF9400C5BG484C(CHIPS)':
 'PL14A': CDS_PINID='PL14A';
NODE_NAME     R6183 2
 '@T6G_MB_LIB.T6G(SCH_1):PAGE81_I164@PURE_QUANTA.Q_RES(CHIPS)':
 'B': CDS_PINID='B';
NET_NAME
'FM_SEC_MUX_R_SEL'
 '@T6G_MB_LIB.T6G(SCH_1):FM_SEC_MUX_R_SEL':
 C_SIGNAL='@t6g_mb_lib.t6g(sch_1):fm_sec_mux_r_sel';
NODE_NAME     U18 K1
 '@T6G_MB_LIB.T6G(SCH_1):PAGE81_I143@PURE_QUANTA.LCMXO3LF9400C5BG484C(CHIPS)':
 'PL14B': CDS_PINID='PL14B';
NODE_NAME     R6184 2
 '@T6G_MB_LIB.T6G(SCH_1):PAGE81_I165@PURE_QUANTA.Q_RES(CHIPS)':
 'B': CDS_PINID='B';
NET_NAME
'FM_SEC_MUX_SEL'
 '@T6G_MB_LIB.T6G(SCH_1):FM_SEC_MUX_SEL':
 C_SIGNAL='@t6g_mb_lib.t6g(sch_1):fm_sec_mux_sel';
NODE_NAME     U6 9
 '@T6G_MB_LIB.T6G(SCH_1):PAGE138_I67@PURE_QUANTA.PI3CSW12ZUAEX(CHIPS)':
 'S': CDS_PINID='S';
NODE_NAME     R6184 1
 '@T6G_MB_LIB.T6G(SCH_1):PAGE81_I165@PURE_QUANTA.Q_RES(CHIPS)':
 'A': CDS_PINID='A';
NODE_NAME     R6187 1
 '@T6G_MB_LIB.T6G(SCH_1):PAGE82_I151@PURE_QUANTA.Q_RES(CHIPS)':
 'A': CDS_PINID='A';
NODE_NAME     R6188 1
 '@T6G_MB_LIB.T6G(SCH_1):PAGE82_I152@PURE_QUANTA.Q_RES(CHIPS)':
 'A': CDS_PINID='A';
NET_NAME
'FM_SMB_1_ALERT_GPU'
 '@T6G_MB_LIB.T6G(SCH_1):FM_SMB_1_ALERT_GPU':
 C_SIGNAL='@t6g_mb_lib.t6g(sch_1):fm_smb_1_alert_gpu';
NODE_NAME     R3029 2
 '@T6G_MB_LIB.T6G(SCH_1):PAGE333_I144@PURE_QUANTA.Q_RES(CHIPS)':
 'B': CDS_PINID='B';
NODE_NAME     Q75 5
 '@T6G_MB_LIB.T6G(SCH_1):PAGE333_I151@PURE_QUANTA.MOSFET_NCH_DUAL(CHIPS)':
 'G2': CDS_PINID='G2';
NODE_NAME     Q75 6
 '@T6G_MB_LIB.T6G(SCH_1):PAGE333_I152@PURE_QUANTA.MOSFET_NCH_DUAL(CHIPS)':
 'D1': CDS_PINID='D1';
NET_NAME
'FM_SMB_1_ALERT_GPU_ISO_N'
 '@T6G_MB_LIB.T6G(SCH_1):FM_SMB_1_ALERT_GPU_ISO_N':
 C_SIGNAL='@t6g_mb_lib.t6g(sch_1):fm_smb_1_alert_gpu_iso_n';
NODE_NAME     C1802 1
 '@T6G_MB_LIB.T6G(SCH_1):PAGE333_I148@PURE_QUANTA.Q_CAP(CHIPS)':
 'A': CDS_PINID='A';
NODE_NAME     Q75 3
 '@T6G_MB_LIB.T6G(SCH_1):PAGE333_I151@PURE_QUANTA.MOSFET_NCH_DUAL(CHIPS)':
 'D2': CDS_PINID='D2';
NODE_NAME     R3066 2
 '@T6G_MB_LIB.T6G(SCH_1):PAGE80_I268@PURE_QUANTA.Q_RES(CHIPS)':
 'B': CDS_PINID='B';
NODE_NAME     R3030 2
 '@T6G_MB_LIB.T6G(SCH_1):PAGE333_I178@PURE_QUANTA.Q_RES(CHIPS)':
 'B': CDS_PINID='B';
NET_NAME
'FM_SMB_1_ALERT_GPU_ISO_R_N'
 '@T6G_MB_LIB.T6G(SCH_1):FM_SMB_1_ALERT_GPU_ISO_R_N':
 C_SIGNAL='@t6g_mb_lib.t6g(sch_1):fm_smb_1_alert_gpu_iso_r_n';
NODE_NAME     U18 AA17
 '@T6G_MB_LIB.T6G(SCH_1):PAGE80_I216@PURE_QUANTA.LCMXO3LF9400C5BG484C(CHIPS)':
 'PB40B': CDS_PINID='PB40B';
NODE_NAME     R3066 1
 '@T6G_MB_LIB.T6G(SCH_1):PAGE80_I268@PURE_QUANTA.Q_RES(CHIPS)':
 'A': CDS_PINID='A';
NET_NAME
'FM_SMB_1_ALERT_GPU_N'
 '@T6G_MB_LIB.T6G(SCH_1):FM_SMB_1_ALERT_GPU_N':
 C_SIGNAL='@t6g_mb_lib.t6g(sch_1):fm_smb_1_alert_gpu_n';
NODE_NAME     R3028 1
 '@T6G_MB_LIB.T6G(SCH_1):PAGE333_I139@PURE_QUANTA.Q_RES(CHIPS)':
 'A': CDS_PINID='A';
NODE_NAME     Q75 2
 '@T6G_MB_LIB.T6G(SCH_1):PAGE333_I152@PURE_QUANTA.MOSFET_NCH_DUAL(CHIPS)':
 'G1': CDS_PINID='G1';
NODE_NAME     R3510 2
 '@T6G_MB_LIB.T6G(SCH_1):PAGE333_I176@PURE_QUANTA.Q_RES(CHIPS)':
 'B': CDS_PINID='B';
NODE_NAME     J110 N4
 '@T6G_MB_LIB.T6G(SCH_1):PAGE318_I76@PURE_QUANTA.CONN112_10137002101LF(CHIPS)':
 'N4': CDS_PINID='N4';
NET_NAME
'FM_SMB_2_ALERT_GPU'
 '@T6G_MB_LIB.T6G(SCH_1):FM_SMB_2_ALERT_GPU':
 C_SIGNAL='@t6g_mb_lib.t6g(sch_1):fm_smb_2_alert_gpu';
NODE_NAME     Q74 6
 '@T6G_MB_LIB.T6G(SCH_1):PAGE333_I121@PURE_QUANTA.MOSFET_NCH_DUAL(CHIPS)':
 'D1': CDS_PINID='D1';
NODE_NAME     Q74 5
 '@T6G_MB_LIB.T6G(SCH_1):PAGE333_I122@PURE_QUANTA.MOSFET_NCH_DUAL(CHIPS)':
 'G2': CDS_PINID='G2';
NODE_NAME     R3034 2
 '@T6G_MB_LIB.T6G(SCH_1):PAGE333_I129@PURE_QUANTA.Q_RES(CHIPS)':
 'B': CDS_PINID='B';
NET_NAME
'FM_SMB_2_ALERT_GPU_ISO_N'
 '@T6G_MB_LIB.T6G(SCH_1):FM_SMB_2_ALERT_GPU_ISO_N':
 C_SIGNAL='@t6g_mb_lib.t6g(sch_1):fm_smb_2_alert_gpu_iso_n';
NODE_NAME     Q74 3
 '@T6G_MB_LIB.T6G(SCH_1):PAGE333_I122@PURE_QUANTA.MOSFET_NCH_DUAL(CHIPS)':
 'D2': CDS_PINID='D2';
NODE_NAME     C1804 1
 '@T6G_MB_LIB.T6G(SCH_1):PAGE333_I125@PURE_QUANTA.Q_CAP(CHIPS)':
 'A': CDS_PINID='A';
NODE_NAME     R11667 2
 '@T6G_MB_LIB.T6G(SCH_1):PAGE80_I274@PURE_QUANTA.Q_RES(CHIPS)':
 'B': CDS_PINID='B';
NODE_NAME     R3035 2
 '@T6G_MB_LIB.T6G(SCH_1):PAGE333_I179@PURE_QUANTA.Q_RES(CHIPS)':
 'B': CDS_PINID='B';
NET_NAME
'FM_SMB_2_ALERT_GPU_ISO_R_N'
 '@T6G_MB_LIB.T6G(SCH_1):FM_SMB_2_ALERT_GPU_ISO_R_N':
 C_SIGNAL='@t6g_mb_lib.t6g(sch_1):fm_smb_2_alert_gpu_iso_r_n';
NODE_NAME     U18 Y18
 '@T6G_MB_LIB.T6G(SCH_1):PAGE80_I216@PURE_QUANTA.LCMXO3LF9400C5BG484C(CHIPS)':
 'PB41C': CDS_PINID='PB41C';
NODE_NAME     R11667 1
 '@T6G_MB_LIB.T6G(SCH_1):PAGE80_I274@PURE_QUANTA.Q_RES(CHIPS)':
 'A': CDS_PINID='A';
NET_NAME
'FM_SMB_2_ALERT_GPU_N'
 '@T6G_MB_LIB.T6G(SCH_1):FM_SMB_2_ALERT_GPU_N':
 C_SIGNAL='@t6g_mb_lib.t6g(sch_1):fm_smb_2_alert_gpu_n';
NODE_NAME     Q74 2
 '@T6G_MB_LIB.T6G(SCH_1):PAGE333_I121@PURE_QUANTA.MOSFET_NCH_DUAL(CHIPS)':
 'G1': CDS_PINID='G1';
NODE_NAME     R3032 1
 '@T6G_MB_LIB.T6G(SCH_1):PAGE333_I134@PURE_QUANTA.Q_RES(CHIPS)':
 'A': CDS_PINID='A';
NODE_NAME     R3514 2
 '@T6G_MB_LIB.T6G(SCH_1):PAGE333_I175@PURE_QUANTA.Q_RES(CHIPS)':
 'B': CDS_PINID='B';
NODE_NAME     J110 N6
 '@T6G_MB_LIB.T6G(SCH_1):PAGE318_I16@PURE_QUANTA.CONN112_10137002101LF(CHIPS)':
 'N6': CDS_PINID='N6';
NET_NAME
'FM_SMB_RST_E1S_0_N'
 '@T6G_MB_LIB.T6G(SCH_1):FM_SMB_RST_E1S_0_N':
 C_SIGNAL='@t6g_mb_lib.t6g(sch_1):fm_smb_rst_e1s_0_n';
NODE_NAME     U18 P2
 '@T6G_MB_LIB.T6G(SCH_1):PAGE81_I143@PURE_QUANTA.LCMXO3LF9400C5BG484C(CHIPS)':
 'PL19A': CDS_PINID='PL19A';
NODE_NAME     R1303 1
 '@T6G_MB_LIB.T6G(SCH_1):PAGE84_I5@PURE_QUANTA.Q_RES(CHIPS)':
 'A': CDS_PINID='A';
NODE_NAME     R1036 1
 '@T6G_MB_LIB.T6G(SCH_1):PAGE84_I6@PURE_QUANTA.Q_RES(CHIPS)':
 'A': CDS_PINID='A';
NET_NAME
'FM_SMB_RST_E1S_0_R_N'
 '@T6G_MB_LIB.T6G(SCH_1):FM_SMB_RST_E1S_0_R_N':
 C_SIGNAL='@t6g_mb_lib.t6g(sch_1):fm_smb_rst_e1s_0_r_n';
NODE_NAME     R3775 1
 '@T6G_MB_LIB.T6G(SCH_1):PAGE297_I2@PURE_QUANTA.Q_RES(CHIPS)':
 'A': CDS_PINID='A';
NODE_NAME     R1036 2
 '@T6G_MB_LIB.T6G(SCH_1):PAGE84_I6@PURE_QUANTA.Q_RES(CHIPS)':
 'B': CDS_PINID='B';
NET_NAME
'FM_SMB_RT_ROM_MUX1_SEL'
 '@T6G_MB_LIB.T6G(SCH_1):FM_SMB_RT_ROM_MUX1_SEL':
 C_SIGNAL='@t6g_mb_lib.t6g(sch_1):fm_smb_rt_rom_mux1_sel';
NODE_NAME     U45 9
 '@T6G_MB_LIB.T6G(SCH_1):PAGE376_I22@PURE_QUANTA.PI3CSW12ZUAEX(CHIPS)':
 'S': CDS_PINID='S';
NODE_NAME     R1201 2
 '@T6G_MB_LIB.T6G(SCH_1):PAGE376_I30@PURE_QUANTA.Q_RES(CHIPS)':
 'B': CDS_PINID='B';
NET_NAME
'FM_SMB_RT_ROM_MUX2_SEL'
 '@T6G_MB_LIB.T6G(SCH_1):FM_SMB_RT_ROM_MUX2_SEL':
 C_SIGNAL='@t6g_mb_lib.t6g(sch_1):fm_smb_rt_rom_mux2_sel';
NODE_NAME     U42 9
 '@T6G_MB_LIB.T6G(SCH_1):PAGE376_I31@PURE_QUANTA.PI3CSW12ZUAEX(CHIPS)':
 'S': CDS_PINID='S';
NODE_NAME     R1199 2
 '@T6G_MB_LIB.T6G(SCH_1):PAGE376_I40@PURE_QUANTA.Q_RES(CHIPS)':
 'B': CDS_PINID='B';
NET_NAME
'FM_SMB_RT_ROM_MUX3_SEL'
 '@T6G_MB_LIB.T6G(SCH_1):FM_SMB_RT_ROM_MUX3_SEL':
 C_SIGNAL='@t6g_mb_lib.t6g(sch_1):fm_smb_rt_rom_mux3_sel';
NODE_NAME     U41 9
 '@T6G_MB_LIB.T6G(SCH_1):PAGE376_I46@PURE_QUANTA.PI3CSW12ZUAEX(CHIPS)':
 'S': CDS_PINID='S';
NODE_NAME     R1198 2
 '@T6G_MB_LIB.T6G(SCH_1):PAGE376_I53@PURE_QUANTA.Q_RES(CHIPS)':
 'B': CDS_PINID='B';
NET_NAME
'FM_SMB_RT_ROM_MUX4_SEL'
 '@T6G_MB_LIB.T6G(SCH_1):FM_SMB_RT_ROM_MUX4_SEL':
 C_SIGNAL='@t6g_mb_lib.t6g(sch_1):fm_smb_rt_rom_mux4_sel';
NODE_NAME     U43 9
 '@T6G_MB_LIB.T6G(SCH_1):PAGE376_I61@PURE_QUANTA.PI3CSW12ZUAEX(CHIPS)':
 'S': CDS_PINID='S';
NODE_NAME     R1200 2
 '@T6G_MB_LIB.T6G(SCH_1):PAGE376_I68@PURE_QUANTA.Q_RES(CHIPS)':
 'B': CDS_PINID='B';
NET_NAME
'FM_SMB_RT_ROM_MUX5_SEL'
 '@T6G_MB_LIB.T6G(SCH_1):FM_SMB_RT_ROM_MUX5_SEL':
 C_SIGNAL='@t6g_mb_lib.t6g(sch_1):fm_smb_rt_rom_mux5_sel';
NODE_NAME     U49 9
 '@T6G_MB_LIB.T6G(SCH_1):PAGE376_I85@PURE_QUANTA.PI3CSW12ZUAEX(CHIPS)':
 'S': CDS_PINID='S';
NODE_NAME     R1211 2
 '@T6G_MB_LIB.T6G(SCH_1):PAGE376_I86@PURE_QUANTA.Q_RES(CHIPS)':
 'B': CDS_PINID='B';
NET_NAME
'FM_SMB_RT_ROM_MUX6_SEL'
 '@T6G_MB_LIB.T6G(SCH_1):FM_SMB_RT_ROM_MUX6_SEL':
 C_SIGNAL='@t6g_mb_lib.t6g(sch_1):fm_smb_rt_rom_mux6_sel';
NODE_NAME     U48 9
 '@T6G_MB_LIB.T6G(SCH_1):PAGE376_I76@PURE_QUANTA.PI3CSW12ZUAEX(CHIPS)':
 'S': CDS_PINID='S';
NODE_NAME     R1210 2
 '@T6G_MB_LIB.T6G(SCH_1):PAGE376_I109@PURE_QUANTA.Q_RES(CHIPS)':
 'B': CDS_PINID='B';
NET_NAME
'FM_SMB_RT_ROM_MUX7_SEL'
 '@T6G_MB_LIB.T6G(SCH_1):FM_SMB_RT_ROM_MUX7_SEL':
 C_SIGNAL='@t6g_mb_lib.t6g(sch_1):fm_smb_rt_rom_mux7_sel';
NODE_NAME     U46 9
 '@T6G_MB_LIB.T6G(SCH_1):PAGE376_I108@PURE_QUANTA.PI3CSW12ZUAEX(CHIPS)':
 'S': CDS_PINID='S';
NODE_NAME     R1206 2
 '@T6G_MB_LIB.T6G(SCH_1):PAGE376_I115@PURE_QUANTA.Q_RES(CHIPS)':
 'B': CDS_PINID='B';
NET_NAME
'FM_SMB_RT_ROM_MUX8_SEL'
 '@T6G_MB_LIB.T6G(SCH_1):FM_SMB_RT_ROM_MUX8_SEL':
 C_SIGNAL='@t6g_mb_lib.t6g(sch_1):fm_smb_rt_rom_mux8_sel';
NODE_NAME     U47 9
 '@T6G_MB_LIB.T6G(SCH_1):PAGE376_I121@PURE_QUANTA.PI3CSW12ZUAEX(CHIPS)':
 'S': CDS_PINID='S';
NODE_NAME     R1209 2
 '@T6G_MB_LIB.T6G(SCH_1):PAGE376_I123@PURE_QUANTA.Q_RES(CHIPS)':
 'B': CDS_PINID='B';
NET_NAME
'FM_SMERR_BUF_LED_N'
 '@T6G_MB_LIB.T6G(SCH_1):FM_SMERR_BUF_LED_N':
 C_SIGNAL='@t6g_mb_lib.t6g(sch_1):fm_smerr_buf_led_n';
NODE_NAME     R936 1
 '@T6G_MB_LIB.T6G(SCH_1):PAGE143_I22@PURE_QUANTA.Q_RES(CHIPS)':
 'A': CDS_PINID='A';
NODE_NAME     U86 4
 '@T6G_MB_LIB.T6G(SCH_1):PAGE143_I31@PURE_QUANTA.SN74LVC1G07DBVR(CHIPS)':
 'Y': CDS_PINID='Y';
NET_NAME
'FM_SMERR_BUF_R_LED_N'
 '@T6G_MB_LIB.T6G(SCH_1):FM_SMERR_BUF_R_LED_N':
 C_SIGNAL='@t6g_mb_lib.t6g(sch_1):fm_smerr_buf_r_led_n';
NODE_NAME     R945 2
 '@T6G_MB_LIB.T6G(SCH_1):PAGE143_I18@PURE_QUANTA.Q_RES(CHIPS)':
 'B': CDS_PINID='B';
NODE_NAME     Q11 2
 '@T6G_MB_LIB.T6G(SCH_1):PAGE143_I19@PURE_QUANTA.MOSFET_DUAL_6P(CHIPS)':
 'G1': CDS_PINID='G1';
NODE_NAME     R936 2
 '@T6G_MB_LIB.T6G(SCH_1):PAGE143_I22@PURE_QUANTA.Q_RES(CHIPS)':
 'B': CDS_PINID='B';
NET_NAME
'FM_SMERR_LED_N'
 '@T6G_MB_LIB.T6G(SCH_1):FM_SMERR_LED_N':
 C_SIGNAL='@t6g_mb_lib.t6g(sch_1):fm_smerr_led_n';
NODE_NAME     U86 2
 '@T6G_MB_LIB.T6G(SCH_1):PAGE143_I31@PURE_QUANTA.SN74LVC1G07DBVR(CHIPS)':
 'A': CDS_PINID='A';
NODE_NAME     R933 2
 '@T6G_MB_LIB.T6G(SCH_1):PAGE80_I215@PURE_QUANTA.Q_RES(CHIPS)':
 'B': CDS_PINID='B';
NET_NAME
'FM_SMERR_LED_R_N'
 '@T6G_MB_LIB.T6G(SCH_1):FM_SMERR_LED_R_N':
 C_SIGNAL='@t6g_mb_lib.t6g(sch_1):fm_smerr_led_r_n';
NODE_NAME     R933 1
 '@T6G_MB_LIB.T6G(SCH_1):PAGE80_I215@PURE_QUANTA.Q_RES(CHIPS)':
 'A': CDS_PINID='A';
NODE_NAME     U18 M22
 '@T6G_MB_LIB.T6G(SCH_1):PAGE80_I217@PURE_QUANTA.LCMXO3LF9400C5BG484C(CHIPS)':
 'PR17A||PCLKT1_0': CDS_PINID='\pr17a||pclkt1_0\';
NET_NAME
'FM_SMM_CRASHDUMP'
 '@T6G_MB_LIB.T6G(SCH_1):FM_SMM_CRASHDUMP':
 C_SIGNAL='@t6g_mb_lib.t6g(sch_1):fm_smm_crashdump';
NODE_NAME     R243 1
 '@T6G_MB_LIB.T6G(SCH_1):PAGE81_I63@PURE_QUANTA.Q_RES(CHIPS)':
 'A': CDS_PINID='A';
NODE_NAME     R5026 2
 '@T6G_MB_LIB.T6G(SCH_1):PAGE28_I40@PURE_QUANTA.Q_RES(CHIPS)':
 'B': CDS_PINID='B';
NODE_NAME     R444 1
 '@T6G_MB_LIB.T6G(SCH_1):PAGE28_I43@PURE_QUANTA.Q_RES(CHIPS)':
 'A': CDS_PINID='A';
NODE_NAME     U25 DF40
 '@T6G_MB_LIB.T6G(SCH_1):PAGE28_I188@PURE_QUANTA.GENOA_SP5(CHIPS)':
 'AGPIO5||DEVSLP0||SATA_ZP0_L': CDS_PINID='\agpio5||devslp0||sata_zp0_l\';
NET_NAME
'FM_SMM_CRASHDUMP_R'
 '@T6G_MB_LIB.T6G(SCH_1):FM_SMM_CRASHDUMP_R':
 C_SIGNAL='@t6g_mb_lib.t6g(sch_1):fm_smm_crashdump_r';
NODE_NAME     R243 2
 '@T6G_MB_LIB.T6G(SCH_1):PAGE81_I63@PURE_QUANTA.Q_RES(CHIPS)':
 'B': CDS_PINID='B';
NODE_NAME     U18 D1
 '@T6G_MB_LIB.T6G(SCH_1):PAGE81_I143@PURE_QUANTA.LCMXO3LF9400C5BG484C(CHIPS)':
 'PL5A': CDS_PINID='PL5A';
NET_NAME
'FM_SOL_UART_CH_SEL'
 '@T6G_MB_LIB.T6G(SCH_1):FM_SOL_UART_CH_SEL':
 C_SIGNAL='@t6g_mb_lib.t6g(sch_1):fm_sol_uart_ch_sel';
NODE_NAME     U18 B20
 '@T6G_MB_LIB.T6G(SCH_1):PAGE79_I94@PURE_QUANTA.LCMXO3LF9400C5BG484C(CHIPS)':
 'PT42B': CDS_PINID='PT42B';
NODE_NAME     R3778 2
 '@T6G_MB_LIB.T6G(SCH_1):PAGE348_I169@PURE_QUANTA.Q_RES(CHIPS)':
 'B': CDS_PINID='B';
NET_NAME
'FM_SOL_UART_CH_SEL_R'
 '@T6G_MB_LIB.T6G(SCH_1):FM_SOL_UART_CH_SEL_R':
 C_SIGNAL='@t6g_mb_lib.t6g(sch_1):fm_sol_uart_ch_sel_r';
NODE_NAME     J41 OB14
 '@T6G_MB_LIB.T6G(SCH_1):PAGE348_I176@PURE_QUANTA.SCONN168_ME1016810202011(CHIPS)':
 'RBT_CRS_DV': CDS_PINID='RBT_CRS_DV';
NODE_NAME     R3778 1
 '@T6G_MB_LIB.T6G(SCH_1):PAGE348_I169@PURE_QUANTA.Q_RES(CHIPS)':
 'A': CDS_PINID='A';
NET_NAME
'FM_SPD_CPU0_SWITCH_CTRL_N'
 '@T6G_MB_LIB.T6G(SCH_1):FM_SPD_CPU0_SWITCH_CTRL_N':
 C_SIGNAL='@t6g_mb_lib.t6g(sch_1):fm_spd_cpu0_switch_ctrl_n';
NODE_NAME     R395 2
 '@T6G_MB_LIB.T6G(SCH_1):PAGE80_I155@PURE_QUANTA.Q_RES(CHIPS)':
 'B': CDS_PINID='B';
NODE_NAME     R1261 2
 '@T6G_MB_LIB.T6G(SCH_1):PAGE144_I15@PURE_QUANTA.Q_RES(CHIPS)':
 'B': CDS_PINID='B';
NODE_NAME     SW1 11
 '@T6G_MB_LIB.T6G(SCH_1):PAGE144_I90@PURE_QUANTA.SW20S_DHNF10FQTR(CHIPS)':
 '11': CDS_PINID='\11\';
NET_NAME
'FM_SPD_CPU0_SWITCH_CTRL_R_N'
 '@T6G_MB_LIB.T6G(SCH_1):FM_SPD_CPU0_SWITCH_CTRL_R_N':
 C_SIGNAL='@t6g_mb_lib.t6g(sch_1):fm_spd_cpu0_switch_ctrl_r_n';
NODE_NAME     R395 1
 '@T6G_MB_LIB.T6G(SCH_1):PAGE80_I155@PURE_QUANTA.Q_RES(CHIPS)':
 'A': CDS_PINID='A';
NODE_NAME     U18 U19
 '@T6G_MB_LIB.T6G(SCH_1):PAGE80_I217@PURE_QUANTA.LCMXO3LF9400C5BG484C(CHIPS)':
 'PR28C': CDS_PINID='PR28C';
NET_NAME
'FM_SWB_BIC_READY'
 '@T6G_MB_LIB.T6G(SCH_1):FM_SWB_BIC_READY':
 C_SIGNAL='@t6g_mb_lib.t6g(sch_1):fm_swb_bic_ready';
NODE_NAME     R2836 2
 '@T6G_MB_LIB.T6G(SCH_1):PAGE333_I19@PURE_QUANTA.Q_RES(CHIPS)':
 'B': CDS_PINID='B';
NODE_NAME     Q70 6
 '@T6G_MB_LIB.T6G(SCH_1):PAGE333_I35@PURE_QUANTA.MOSFET_NCH_DUAL(CHIPS)':
 'D1': CDS_PINID='D1';
NODE_NAME     Q70 5
 '@T6G_MB_LIB.T6G(SCH_1):PAGE333_I120@PURE_QUANTA.MOSFET_NCH_DUAL(CHIPS)':
 'G2': CDS_PINID='G2';
NET_NAME
'FM_SWB_BIC_READY_ISO_N'
 '@T6G_MB_LIB.T6G(SCH_1):FM_SWB_BIC_READY_ISO_N':
 C_SIGNAL='@t6g_mb_lib.t6g(sch_1):fm_swb_bic_ready_iso_n';
NODE_NAME     C1754 1
 '@T6G_MB_LIB.T6G(SCH_1):PAGE333_I92@PURE_QUANTA.Q_CAP(CHIPS)':
 'A': CDS_PINID='A';
NODE_NAME     Q70 3
 '@T6G_MB_LIB.T6G(SCH_1):PAGE333_I120@PURE_QUANTA.MOSFET_NCH_DUAL(CHIPS)':
 'D2': CDS_PINID='D2';
NODE_NAME     R2844 2
 '@T6G_MB_LIB.T6G(SCH_1):PAGE80_I263@PURE_QUANTA.Q_RES(CHIPS)':
 'B': CDS_PINID='B';
NODE_NAME     R2933 2
 '@T6G_MB_LIB.T6G(SCH_1):PAGE333_I180@PURE_QUANTA.Q_RES(CHIPS)':
 'B': CDS_PINID='B';
NET_NAME
'FM_SWB_BIC_READY_ISO_R_N'
 '@T6G_MB_LIB.T6G(SCH_1):FM_SWB_BIC_READY_ISO_R_N':
 C_SIGNAL='@t6g_mb_lib.t6g(sch_1):fm_swb_bic_ready_iso_r_n';
NODE_NAME     U18 AB17
 '@T6G_MB_LIB.T6G(SCH_1):PAGE80_I216@PURE_QUANTA.LCMXO3LF9400C5BG484C(CHIPS)':
 'PB40A': CDS_PINID='PB40A';
NODE_NAME     R2844 1
 '@T6G_MB_LIB.T6G(SCH_1):PAGE80_I263@PURE_QUANTA.Q_RES(CHIPS)':
 'A': CDS_PINID='A';
NET_NAME
'FM_SWB_BIC_READY_N'
 '@T6G_MB_LIB.T6G(SCH_1):FM_SWB_BIC_READY_N':
 C_SIGNAL='@t6g_mb_lib.t6g(sch_1):fm_swb_bic_ready_n';
NODE_NAME     Q70 2
 '@T6G_MB_LIB.T6G(SCH_1):PAGE333_I35@PURE_QUANTA.MOSFET_NCH_DUAL(CHIPS)':
 'G1': CDS_PINID='G1';
NODE_NAME     R2833 1
 '@T6G_MB_LIB.T6G(SCH_1):PAGE333_I60@PURE_QUANTA.Q_RES(CHIPS)':
 'A': CDS_PINID='A';
NODE_NAME     R2832 2
 '@T6G_MB_LIB.T6G(SCH_1):PAGE333_I67@PURE_QUANTA.Q_RES(CHIPS)':
 'B': CDS_PINID='B';
NODE_NAME     J105 N4
 '@T6G_MB_LIB.T6G(SCH_1):PAGE326_I75@PURE_QUANTA.CONN112_10137002101LF(CHIPS)':
 'N4': CDS_PINID='N4';
NET_NAME
'FM_SWB_PWRGD'
 '@T6G_MB_LIB.T6G(SCH_1):FM_SWB_PWRGD':
 C_SIGNAL='@t6g_mb_lib.t6g(sch_1):fm_swb_pwrgd';
NODE_NAME     R2838 1
 '@T6G_MB_LIB.T6G(SCH_1):PAGE333_I62@PURE_QUANTA.Q_RES(CHIPS)':
 'A': CDS_PINID='A';
NODE_NAME     R2837 2
 '@T6G_MB_LIB.T6G(SCH_1):PAGE333_I80@PURE_QUANTA.Q_RES(CHIPS)':
 'B': CDS_PINID='B';
NODE_NAME     Q71 2
 '@T6G_MB_LIB.T6G(SCH_1):PAGE333_I118@PURE_QUANTA.MOSFET_NCH_DUAL(CHIPS)':
 'G1': CDS_PINID='G1';
NODE_NAME     J106 A3
 '@T6G_MB_LIB.T6G(SCH_1):PAGE327_I74@PURE_QUANTA.CONN112_10137002101LF(CHIPS)':
 'A3': CDS_PINID='A3';
NET_NAME
'FM_SWB_PWRGD_ISO'
 '@T6G_MB_LIB.T6G(SCH_1):FM_SWB_PWRGD_ISO':
 C_SIGNAL='@t6g_mb_lib.t6g(sch_1):fm_swb_pwrgd_iso';
NODE_NAME     Q71 3
 '@T6G_MB_LIB.T6G(SCH_1):PAGE333_I100@PURE_QUANTA.MOSFET_NCH_DUAL(CHIPS)':
 'D2': CDS_PINID='D2';
NODE_NAME     R2934 2
 '@T6G_MB_LIB.T6G(SCH_1):PAGE333_I101@PURE_QUANTA.Q_RES(CHIPS)':
 'B': CDS_PINID='B';
NODE_NAME     C1774 1
 '@T6G_MB_LIB.T6G(SCH_1):PAGE333_I111@PURE_QUANTA.Q_CAP(CHIPS)':
 'A': CDS_PINID='A';
NODE_NAME     R2663 2
 '@T6G_MB_LIB.T6G(SCH_1):PAGE80_I271@PURE_QUANTA.Q_RES(CHIPS)':
 'B': CDS_PINID='B';
NET_NAME
'FM_SWB_PWRGD_ISO_R'
 '@T6G_MB_LIB.T6G(SCH_1):FM_SWB_PWRGD_ISO_R':
 C_SIGNAL='@t6g_mb_lib.t6g(sch_1):fm_swb_pwrgd_iso_r';
NODE_NAME     U18 AB18
 '@T6G_MB_LIB.T6G(SCH_1):PAGE80_I216@PURE_QUANTA.LCMXO3LF9400C5BG484C(CHIPS)':
 'PB41A': CDS_PINID='PB41A';
NODE_NAME     R2663 1
 '@T6G_MB_LIB.T6G(SCH_1):PAGE80_I271@PURE_QUANTA.Q_RES(CHIPS)':
 'A': CDS_PINID='A';
NET_NAME
'FM_SWB_PWRGD_N'
 '@T6G_MB_LIB.T6G(SCH_1):FM_SWB_PWRGD_N':
 C_SIGNAL='@t6g_mb_lib.t6g(sch_1):fm_swb_pwrgd_n';
NODE_NAME     R2841 2
 '@T6G_MB_LIB.T6G(SCH_1):PAGE333_I24@PURE_QUANTA.Q_RES(CHIPS)':
 'B': CDS_PINID='B';
NODE_NAME     Q71 5
 '@T6G_MB_LIB.T6G(SCH_1):PAGE333_I100@PURE_QUANTA.MOSFET_NCH_DUAL(CHIPS)':
 'G2': CDS_PINID='G2';
NODE_NAME     Q71 6
 '@T6G_MB_LIB.T6G(SCH_1):PAGE333_I118@PURE_QUANTA.MOSFET_NCH_DUAL(CHIPS)':
 'D1': CDS_PINID='D1';
NET_NAME
'FM_SWB_PWR_EN'
 '@T6G_MB_LIB.T6G(SCH_1):FM_SWB_PWR_EN':
 C_SIGNAL='@t6g_mb_lib.t6g(sch_1):fm_swb_pwr_en';
NODE_NAME     U18 AA2
 '@T6G_MB_LIB.T6G(SCH_1):PAGE80_I216@PURE_QUANTA.LCMXO3LF9400C5BG484C(CHIPS)':
 'PB5A': CDS_PINID='PB5A';
NODE_NAME     R2261 2
 '@T6G_MB_LIB.T6G(SCH_1):PAGE80_I284@PURE_QUANTA.Q_RES(CHIPS)':
 'B': CDS_PINID='B';
NET_NAME
'FM_SWB_PWR_EN_R'
 '@T6G_MB_LIB.T6G(SCH_1):FM_SWB_PWR_EN_R':
 C_SIGNAL='@t6g_mb_lib.t6g(sch_1):fm_swb_pwr_en_r';
NODE_NAME     U256 3
 '@T6G_MB_LIB.T6G(SCH_1):PAGE334_I173@PURE_QUANTA.74LVC2G17GW(CHIPS)':
 'A1': CDS_PINID='A1';
NODE_NAME     R2910 2
 '@T6G_MB_LIB.T6G(SCH_1):PAGE334_I187@PURE_QUANTA.Q_RES(CHIPS)':
 'B': CDS_PINID='B';
NODE_NAME     R2918 1
 '@T6G_MB_LIB.T6G(SCH_1):PAGE334_I188@PURE_QUANTA.Q_RES(CHIPS)':
 'A': CDS_PINID='A';
NODE_NAME     R2261 1
 '@T6G_MB_LIB.T6G(SCH_1):PAGE80_I284@PURE_QUANTA.Q_RES(CHIPS)':
 'A': CDS_PINID='A';
NET_NAME
'FM_SWB_PWR_EN_R1_BUF'
 '@T6G_MB_LIB.T6G(SCH_1):FM_SWB_PWR_EN_R1_BUF':
 C_SIGNAL='@t6g_mb_lib.t6g(sch_1):fm_swb_pwr_en_r1_buf';
NODE_NAME     U256 4
 '@T6G_MB_LIB.T6G(SCH_1):PAGE334_I173@PURE_QUANTA.74LVC2G17GW(CHIPS)':
 'B1': CDS_PINID='B1';
NODE_NAME     R2914 2
 '@T6G_MB_LIB.T6G(SCH_1):PAGE334_I192@PURE_QUANTA.Q_RES(CHIPS)':
 'B': CDS_PINID='B';
NODE_NAME     R3515 1
 '@T6G_MB_LIB.T6G(SCH_1):PAGE334_I193@PURE_QUANTA.Q_RES(CHIPS)':
 'A': CDS_PINID='A';
NODE_NAME     R2932 1
 '@T6G_MB_LIB.T6G(SCH_1):PAGE334_I195@PURE_QUANTA.Q_RES(CHIPS)':
 'A': CDS_PINID='A';
NET_NAME
'FM_SWB_PWR_EN_R_BUF'
 '@T6G_MB_LIB.T6G(SCH_1):FM_SWB_PWR_EN_R_BUF':
 C_SIGNAL='@t6g_mb_lib.t6g(sch_1):fm_swb_pwr_en_r_buf';
NODE_NAME     R3515 2
 '@T6G_MB_LIB.T6G(SCH_1):PAGE334_I193@PURE_QUANTA.Q_RES(CHIPS)':
 'B': CDS_PINID='B';
NODE_NAME     J105 N2
 '@T6G_MB_LIB.T6G(SCH_1):PAGE326_I75@PURE_QUANTA.CONN112_10137002101LF(CHIPS)':
 'N2': CDS_PINID='N2';
NET_NAME
'FM_SYS_THROTTLE_N'
 '@T6G_MB_LIB.T6G(SCH_1):FM_SYS_THROTTLE_N':
 C_SIGNAL='@t6g_mb_lib.t6g(sch_1):fm_sys_throttle_n';
NODE_NAME     R992 2
 '@T6G_MB_LIB.T6G(SCH_1):PAGE79_I17@PURE_QUANTA.Q_RES(CHIPS)':
 'B': CDS_PINID='B';
NODE_NAME     R993 1
 '@T6G_MB_LIB.T6G(SCH_1):PAGE82_I53@PURE_QUANTA.Q_RES(CHIPS)':
 'A': CDS_PINID='A';
NODE_NAME     U104 2
 '@T6G_MB_LIB.T6G(SCH_1):PAGE337_I38@PURE_QUANTA.74LVC1G07GV(CHIPS)':
 'A': CDS_PINID='A';
NODE_NAME     U218 2
 '@T6G_MB_LIB.T6G(SCH_1):PAGE342_I22@PURE_QUANTA.74LVC1G07GV(CHIPS)':
 'A': CDS_PINID='A';
NET_NAME
'FM_SYS_THROTTLE_R_N'
 '@T6G_MB_LIB.T6G(SCH_1):FM_SYS_THROTTLE_R_N':
 C_SIGNAL='@t6g_mb_lib.t6g(sch_1):fm_sys_throttle_r_n';
NODE_NAME     R992 1
 '@T6G_MB_LIB.T6G(SCH_1):PAGE79_I17@PURE_QUANTA.Q_RES(CHIPS)':
 'A': CDS_PINID='A';
NODE_NAME     U18 E11
 '@T6G_MB_LIB.T6G(SCH_1):PAGE79_I94@PURE_QUANTA.LCMXO3LF9400C5BG484C(CHIPS)':
 'PT24C': CDS_PINID='PT24C';
NET_NAME
'FM_THERMAL_ALERT_N'
 '@T6G_MB_LIB.T6G(SCH_1):FM_THERMAL_ALERT_N':
 C_SIGNAL='@t6g_mb_lib.t6g(sch_1):fm_thermal_alert_n';
NODE_NAME     R4215 1
 '@T6G_MB_LIB.T6G(SCH_1):PAGE359_I79@PURE_QUANTA.Q_RES(CHIPS)':
 'A': CDS_PINID='A';
NODE_NAME     R4214 1
 '@T6G_MB_LIB.T6G(SCH_1):PAGE359_I108@PURE_QUANTA.Q_RES(CHIPS)':
 'A': CDS_PINID='A';
NODE_NAME     R4213 1
 '@T6G_MB_LIB.T6G(SCH_1):PAGE359_I115@PURE_QUANTA.Q_RES(CHIPS)':
 'A': CDS_PINID='A';
NODE_NAME     R4212 1
 '@T6G_MB_LIB.T6G(SCH_1):PAGE359_I135@PURE_QUANTA.Q_RES(CHIPS)':
 'A': CDS_PINID='A';
NODE_NAME     R4211 2
 '@T6G_MB_LIB.T6G(SCH_1):PAGE359_I168@PURE_QUANTA.Q_RES(CHIPS)':
 'B': CDS_PINID='B';
NODE_NAME     R4209 2
 '@T6G_MB_LIB.T6G(SCH_1):PAGE359_I169@PURE_QUANTA.Q_RES(CHIPS)':
 'B': CDS_PINID='B';
NODE_NAME     R4210 2
 '@T6G_MB_LIB.T6G(SCH_1):PAGE359_I170@PURE_QUANTA.Q_RES(CHIPS)':
 'B': CDS_PINID='B';
NODE_NAME     R4208 2
 '@T6G_MB_LIB.T6G(SCH_1):PAGE359_I171@PURE_QUANTA.Q_RES(CHIPS)':
 'B': CDS_PINID='B';
NODE_NAME     R6074 1
 '@T6G_MB_LIB.T6G(SCH_1):PAGE84_I53@PURE_QUANTA.Q_RES(CHIPS)':
 'A': CDS_PINID='A';
NET_NAME
'FM_THERMAL_ALERT_R_N'
 '@T6G_MB_LIB.T6G(SCH_1):FM_THERMAL_ALERT_R_N':
 C_SIGNAL='@t6g_mb_lib.t6g(sch_1):fm_thermal_alert_r_n';
NODE_NAME     U18 L3
 '@T6G_MB_LIB.T6G(SCH_1):PAGE81_I143@PURE_QUANTA.LCMXO3LF9400C5BG484C(CHIPS)':
 'PL16C': CDS_PINID='PL16C';
NODE_NAME     R6074 2
 '@T6G_MB_LIB.T6G(SCH_1):PAGE84_I53@PURE_QUANTA.Q_RES(CHIPS)':
 'B': CDS_PINID='B';
NET_NAME
'FM_UARTSW_LSB_N'
 '@T6G_MB_LIB.T6G(SCH_1):FM_UARTSW_LSB_N':
 C_SIGNAL='@t6g_mb_lib.t6g(sch_1):fm_uartsw_lsb_n';
NODE_NAME     R3777 1
 '@T6G_MB_LIB.T6G(SCH_1):PAGE348_I25@PURE_QUANTA.Q_RES(CHIPS)':
 'A': CDS_PINID='A';
NODE_NAME     U18 G15
 '@T6G_MB_LIB.T6G(SCH_1):PAGE79_I94@PURE_QUANTA.LCMXO3LF9400C5BG484C(CHIPS)':
 'PT42D': CDS_PINID='PT42D';
NET_NAME
'FM_UARTSW_LSB_R'
 '@T6G_MB_LIB.T6G(SCH_1):FM_UARTSW_LSB_R':
 C_SIGNAL='@t6g_mb_lib.t6g(sch_1):fm_uartsw_lsb_r';
NODE_NAME     R3777 2
 '@T6G_MB_LIB.T6G(SCH_1):PAGE348_I25@PURE_QUANTA.Q_RES(CHIPS)':
 'B': CDS_PINID='B';
NODE_NAME     J41 A55
 '@T6G_MB_LIB.T6G(SCH_1):PAGE348_I176@PURE_QUANTA.SCONN168_ME1016810202011(CHIPS)':
 'GND_A55': CDS_PINID='GND_A55';
NET_NAME
'FM_UARTSW_MSB_N'
 '@T6G_MB_LIB.T6G(SCH_1):FM_UARTSW_MSB_N':
 C_SIGNAL='@t6g_mb_lib.t6g(sch_1):fm_uartsw_msb_n';
NODE_NAME     R3776 1
 '@T6G_MB_LIB.T6G(SCH_1):PAGE348_I27@PURE_QUANTA.Q_RES(CHIPS)':
 'A': CDS_PINID='A';
NODE_NAME     U18 F13
 '@T6G_MB_LIB.T6G(SCH_1):PAGE79_I94@PURE_QUANTA.LCMXO3LF9400C5BG484C(CHIPS)':
 'PT28D': CDS_PINID='PT28D';
NET_NAME
'FM_UARTSW_MSB_R'
 '@T6G_MB_LIB.T6G(SCH_1):FM_UARTSW_MSB_R':
 C_SIGNAL='@t6g_mb_lib.t6g(sch_1):fm_uartsw_msb_r';
NODE_NAME     R3776 2
 '@T6G_MB_LIB.T6G(SCH_1):PAGE348_I27@PURE_QUANTA.Q_RES(CHIPS)':
 'B': CDS_PINID='B';
NODE_NAME     J41 A52
 '@T6G_MB_LIB.T6G(SCH_1):PAGE348_I176@PURE_QUANTA.SCONN168_ME1016810202011(CHIPS)':
 'GND_A52': CDS_PINID='GND_A52';
NET_NAME
'FM_UART_EN'
 '@T6G_MB_LIB.T6G(SCH_1):FM_UART_EN':
 C_SIGNAL='@t6g_mb_lib.t6g(sch_1):fm_uart_en';
NODE_NAME     R3063 2
 '@T6G_MB_LIB.T6G(SCH_1):PAGE256_I171@PURE_QUANTA.Q_RES(CHIPS)':
 'B': CDS_PINID='B';
NODE_NAME     U204 1
 '@T6G_MB_LIB.T6G(SCH_1):PAGE256_I195@PURE_QUANTA.74LVC1G126SE7(CHIPS)':
 'OE': CDS_PINID='OE';
NET_NAME
'FM_UART_LS_EN'
 '@T6G_MB_LIB.T6G(SCH_1):FM_UART_LS_EN':
 C_SIGNAL='@t6g_mb_lib.t6g(sch_1):fm_uart_ls_en';
NODE_NAME     R1563 2
 '@T6G_MB_LIB.T6G(SCH_1):PAGE80_I63@PURE_QUANTA.Q_RES(CHIPS)':
 'B': CDS_PINID='B';
NODE_NAME     U18 U7
 '@T6G_MB_LIB.T6G(SCH_1):PAGE80_I216@PURE_QUANTA.LCMXO3LF9400C5BG484C(CHIPS)':
 'PB8C': CDS_PINID='PB8C';
NET_NAME
'FM_UV_ADR_TRIGGER_N'
 '@T6G_MB_LIB.T6G(SCH_1):FM_UV_ADR_TRIGGER_N':
 C_SIGNAL='@t6g_mb_lib.t6g(sch_1):fm_uv_adr_trigger_n';
NODE_NAME     R6096 2
 '@T6G_MB_LIB.T6G(SCH_1):PAGE79_I115@PURE_QUANTA.Q_RES(CHIPS)':
 'B': CDS_PINID='B';
NODE_NAME     R2233 2
 '@T6G_MB_LIB.T6G(SCH_1):PAGE372_I45@PURE_QUANTA.Q_RES(CHIPS)':
 'B': CDS_PINID='B';
NODE_NAME     U206 1
 '@T6G_MB_LIB.T6G(SCH_1):PAGE372_I49@PURE_QUANTA.LT6700CS61TRPBF(CHIPS)':
 'OUTA': CDS_PINID='OUTA';
NODE_NAME     R8118 2
 '@T6G_MB_LIB.T6G(SCH_1):PAGE372_I67@PURE_QUANTA.Q_RES(CHIPS)':
 'B': CDS_PINID='B';
NODE_NAME     R8119 2
 '@T6G_MB_LIB.T6G(SCH_1):PAGE372_I69@PURE_QUANTA.Q_RES(CHIPS)':
 'B': CDS_PINID='B';
NET_NAME
'FM_UV_ADR_TRIGGER_N_R2'
 '@T6G_MB_LIB.T6G(SCH_1):FM_UV_ADR_TRIGGER_N_R2':
 C_SIGNAL='@t6g_mb_lib.t6g(sch_1):fm_uv_adr_trigger_n_r2';
NODE_NAME     R8117 2
 '@T6G_MB_LIB.T6G(SCH_1):PAGE372_I63@PURE_QUANTA.Q_RES(CHIPS)':
 'B': CDS_PINID='B';
NODE_NAME     R8118 1
 '@T6G_MB_LIB.T6G(SCH_1):PAGE372_I67@PURE_QUANTA.Q_RES(CHIPS)':
 'A': CDS_PINID='A';
NODE_NAME     U8008 4
 '@T6G_MB_LIB.T6G(SCH_1):PAGE372_I71@PURE_QUANTA.AP331AWG7(CHIPS)':
 'OUTPUT': CDS_PINID='OUTPUT';
NET_NAME
'FM_UV_ADR_TRIGGER_R_N'
 '@T6G_MB_LIB.T6G(SCH_1):FM_UV_ADR_TRIGGER_R_N':
 C_SIGNAL='@t6g_mb_lib.t6g(sch_1):fm_uv_adr_trigger_r_n';
NODE_NAME     U18 A7
 '@T6G_MB_LIB.T6G(SCH_1):PAGE79_I94@PURE_QUANTA.LCMXO3LF9400C5BG484C(CHIPS)':
 'PT14B': CDS_PINID='PT14B';
NODE_NAME     R6096 1
 '@T6G_MB_LIB.T6G(SCH_1):PAGE79_I115@PURE_QUANTA.Q_RES(CHIPS)':
 'A': CDS_PINID='A';
NET_NAME
'FPGA_DEBUG_LED_CTRL'
 '@T6G_MB_LIB.T6G(SCH_1):FPGA_DEBUG_LED_CTRL':
 C_SIGNAL='@t6g_mb_lib.t6g(sch_1):fpga_debug_led_ctrl';
NODE_NAME     R371 1
 '@T6G_MB_LIB.T6G(SCH_1):PAGE80_I107@PURE_QUANTA.Q_RES(CHIPS)':
 'A': CDS_PINID='A';
NODE_NAME     R6041 2
 '@T6G_MB_LIB.T6G(SCH_1):PAGE144_I69@PURE_QUANTA.Q_RES(CHIPS)':
 'B': CDS_PINID='B';
NODE_NAME     SW1 20
 '@T6G_MB_LIB.T6G(SCH_1):PAGE144_I90@PURE_QUANTA.SW20S_DHNF10FQTR(CHIPS)':
 '20': CDS_PINID='\20\';
NET_NAME
'FPGA_DEBUG_SW_SPARE'
 '@T6G_MB_LIB.T6G(SCH_1):FPGA_DEBUG_SW_SPARE':
 C_SIGNAL='@t6g_mb_lib.t6g(sch_1):fpga_debug_sw_spare';
NODE_NAME     R5099 1
 '@T6G_MB_LIB.T6G(SCH_1):PAGE80_I35@PURE_QUANTA.Q_RES(CHIPS)':
 'A': CDS_PINID='A';
NODE_NAME     R6043 2
 '@T6G_MB_LIB.T6G(SCH_1):PAGE144_I61@PURE_QUANTA.Q_RES(CHIPS)':
 'B': CDS_PINID='B';
NODE_NAME     SW1 15
 '@T6G_MB_LIB.T6G(SCH_1):PAGE144_I90@PURE_QUANTA.SW20S_DHNF10FQTR(CHIPS)':
 '15': CDS_PINID='\15\';
NET_NAME
'FPGA_IO3V3_RSVD_1'
 '@T6G_MB_LIB.T6G(SCH_1):FPGA_IO3V3_RSVD_1':
 C_SIGNAL='@t6g_mb_lib.t6g(sch_1):fpga_io3v3_rsvd_1';
NODE_NAME     J41 OB13
 '@T6G_MB_LIB.T6G(SCH_1):PAGE348_I176@PURE_QUANTA.SCONN168_ME1016810202011(CHIPS)':
 'GND_OB13': CDS_PINID='GND_OB13';
NODE_NAME     U18 D16
 '@T6G_MB_LIB.T6G(SCH_1):PAGE79_I94@PURE_QUANTA.LCMXO3LF9400C5BG484C(CHIPS)':
 'PT39D': CDS_PINID='PT39D';
NET_NAME
'FW_RECOVERY'
 '@T6G_MB_LIB.T6G(SCH_1):FW_RECOVERY':
 C_SIGNAL='@t6g_mb_lib.t6g(sch_1):fw_recovery';
NODE_NAME     R4087 2
 '@T6G_MB_LIB.T6G(SCH_1):PAGE348_I31@PURE_QUANTA.Q_RES(CHIPS)':
 'B': CDS_PINID='B';
NODE_NAME     J41 A43
 '@T6G_MB_LIB.T6G(SCH_1):PAGE348_I176@PURE_QUANTA.SCONN168_ME1016810202011(CHIPS)':
 'GND_A43': CDS_PINID='GND_A43';
NET_NAME
'FW_RECOVERY_R'
 '@T6G_MB_LIB.T6G(SCH_1):FW_RECOVERY_R':
 C_SIGNAL='@t6g_mb_lib.t6g(sch_1):fw_recovery_r';
NODE_NAME     U99 2
 '@T6G_MB_LIB.T6G(SCH_1):PAGE148_I340@PURE_QUANTA.SN74LVC1G07DBVR(CHIPS)':
 'A': CDS_PINID='A';
NODE_NAME     R1342 1
 '@T6G_MB_LIB.T6G(SCH_1):PAGE148_I369@PURE_QUANTA.Q_RES(CHIPS)':
 'A': CDS_PINID='A';
NODE_NAME     R4087 1
 '@T6G_MB_LIB.T6G(SCH_1):PAGE348_I31@PURE_QUANTA.Q_RES(CHIPS)':
 'A': CDS_PINID='A';
NET_NAME
'GMI_CPU0_G0_CPU1_G2_TX_DN<0>'
 '@T6G_MB_LIB.T6G(SCH_1):GMI_CPU0_G0_CPU1_G2_TX_DN'<0>:
 C_SIGNAL='@t6g_mb_lib.t6g(sch_1):gmi_cpu0_g0_cpu1_g2_tx_dn(0)';
NODE_NAME     U25 AF41
 '@T6G_MB_LIB.T6G(SCH_1):PAGE22_I207@PURE_QUANTA.GENOA_SP5(CHIPS)':
 'G0_TXN0': CDS_PINID='G0_TXN0';
NODE_NAME     U26 AF35
 '@T6G_MB_LIB.T6G(SCH_1):PAGE50_I143@PURE_QUANTA.GENOA_SP5(CHIPS)':
 'G2_RXN15': CDS_PINID='G2_RXN15';
NET_NAME
'GMI_CPU0_G0_CPU1_G2_TX_DN<10>'
 '@T6G_MB_LIB.T6G(SCH_1):GMI_CPU0_G0_CPU1_G2_TX_DN'<10>:
 C_SIGNAL='@t6g_mb_lib.t6g(sch_1):gmi_cpu0_g0_cpu1_g2_tx_dn(10)';
NODE_NAME     U25 AG50
 '@T6G_MB_LIB.T6G(SCH_1):PAGE22_I207@PURE_QUANTA.GENOA_SP5(CHIPS)':
 'G0_TXN10': CDS_PINID='G0_TXN10';
NODE_NAME     U26 AG26
 '@T6G_MB_LIB.T6G(SCH_1):PAGE50_I143@PURE_QUANTA.GENOA_SP5(CHIPS)':
 'G2_RXN5': CDS_PINID='G2_RXN5';
NET_NAME
'GMI_CPU0_G0_CPU1_G2_TX_DN<11>'
 '@T6G_MB_LIB.T6G(SCH_1):GMI_CPU0_G0_CPU1_G2_TX_DN'<11>:
 C_SIGNAL='@t6g_mb_lib.t6g(sch_1):gmi_cpu0_g0_cpu1_g2_tx_dn(11)';
NODE_NAME     U25 AC50
 '@T6G_MB_LIB.T6G(SCH_1):PAGE22_I207@PURE_QUANTA.GENOA_SP5(CHIPS)':
 'G0_TXN11': CDS_PINID='G0_TXN11';
NODE_NAME     U26 AC26
 '@T6G_MB_LIB.T6G(SCH_1):PAGE50_I143@PURE_QUANTA.GENOA_SP5(CHIPS)':
 'G2_RXN4': CDS_PINID='G2_RXN4';
NET_NAME
'GMI_CPU0_G0_CPU1_G2_TX_DN<12>'
 '@T6G_MB_LIB.T6G(SCH_1):GMI_CPU0_G0_CPU1_G2_TX_DN'<12>:
 C_SIGNAL='@t6g_mb_lib.t6g(sch_1):gmi_cpu0_g0_cpu1_g2_tx_dn(12)';
NODE_NAME     U25 AE50
 '@T6G_MB_LIB.T6G(SCH_1):PAGE22_I207@PURE_QUANTA.GENOA_SP5(CHIPS)':
 'G0_TXN12': CDS_PINID='G0_TXN12';
NODE_NAME     U26 AE26
 '@T6G_MB_LIB.T6G(SCH_1):PAGE50_I143@PURE_QUANTA.GENOA_SP5(CHIPS)':
 'G2_RXN3': CDS_PINID='G2_RXN3';
NET_NAME
'GMI_CPU0_G0_CPU1_G2_TX_DN<13>'
 '@T6G_MB_LIB.T6G(SCH_1):GMI_CPU0_G0_CPU1_G2_TX_DN'<13>:
 C_SIGNAL='@t6g_mb_lib.t6g(sch_1):gmi_cpu0_g0_cpu1_g2_tx_dn(13)';
NODE_NAME     U25 AG53
 '@T6G_MB_LIB.T6G(SCH_1):PAGE22_I207@PURE_QUANTA.GENOA_SP5(CHIPS)':
 'G0_TXN13': CDS_PINID='G0_TXN13';
NODE_NAME     U26 AG23
 '@T6G_MB_LIB.T6G(SCH_1):PAGE50_I143@PURE_QUANTA.GENOA_SP5(CHIPS)':
 'G2_RXN2': CDS_PINID='G2_RXN2';
NET_NAME
'GMI_CPU0_G0_CPU1_G2_TX_DN<14>'
 '@T6G_MB_LIB.T6G(SCH_1):GMI_CPU0_G0_CPU1_G2_TX_DN'<14>:
 C_SIGNAL='@t6g_mb_lib.t6g(sch_1):gmi_cpu0_g0_cpu1_g2_tx_dn(14)';
NODE_NAME     U25 AC53
 '@T6G_MB_LIB.T6G(SCH_1):PAGE22_I207@PURE_QUANTA.GENOA_SP5(CHIPS)':
 'G0_TXN14': CDS_PINID='G0_TXN14';
NODE_NAME     U26 AC23
 '@T6G_MB_LIB.T6G(SCH_1):PAGE50_I143@PURE_QUANTA.GENOA_SP5(CHIPS)':
 'G2_RXN1': CDS_PINID='G2_RXN1';
NET_NAME
'GMI_CPU0_G0_CPU1_G2_TX_DN<15>'
 '@T6G_MB_LIB.T6G(SCH_1):GMI_CPU0_G0_CPU1_G2_TX_DN'<15>:
 C_SIGNAL='@t6g_mb_lib.t6g(sch_1):gmi_cpu0_g0_cpu1_g2_tx_dn(15)';
NODE_NAME     U25 AE53
 '@T6G_MB_LIB.T6G(SCH_1):PAGE22_I207@PURE_QUANTA.GENOA_SP5(CHIPS)':
 'G0_TXN15': CDS_PINID='G0_TXN15';
NODE_NAME     U26 AE23
 '@T6G_MB_LIB.T6G(SCH_1):PAGE50_I143@PURE_QUANTA.GENOA_SP5(CHIPS)':
 'G2_RXN0': CDS_PINID='G2_RXN0';
NET_NAME
'GMI_CPU0_G0_CPU1_G2_TX_DN<1>'
 '@T6G_MB_LIB.T6G(SCH_1):GMI_CPU0_G0_CPU1_G2_TX_DN'<1>:
 C_SIGNAL='@t6g_mb_lib.t6g(sch_1):gmi_cpu0_g0_cpu1_g2_tx_dn(1)';
NODE_NAME     U25 AD41
 '@T6G_MB_LIB.T6G(SCH_1):PAGE22_I207@PURE_QUANTA.GENOA_SP5(CHIPS)':
 'G0_TXN1': CDS_PINID='G0_TXN1';
NODE_NAME     U26 AD35
 '@T6G_MB_LIB.T6G(SCH_1):PAGE50_I143@PURE_QUANTA.GENOA_SP5(CHIPS)':
 'G2_RXN14': CDS_PINID='G2_RXN14';
NET_NAME
'GMI_CPU0_G0_CPU1_G2_TX_DN<2>'
 '@T6G_MB_LIB.T6G(SCH_1):GMI_CPU0_G0_CPU1_G2_TX_DN'<2>:
 C_SIGNAL='@t6g_mb_lib.t6g(sch_1):gmi_cpu0_g0_cpu1_g2_tx_dn(2)';
NODE_NAME     U25 AB41
 '@T6G_MB_LIB.T6G(SCH_1):PAGE22_I207@PURE_QUANTA.GENOA_SP5(CHIPS)':
 'G0_TXN2': CDS_PINID='G0_TXN2';
NODE_NAME     U26 AB35
 '@T6G_MB_LIB.T6G(SCH_1):PAGE50_I143@PURE_QUANTA.GENOA_SP5(CHIPS)':
 'G2_RXN13': CDS_PINID='G2_RXN13';
NET_NAME
'GMI_CPU0_G0_CPU1_G2_TX_DN<3>'
 '@T6G_MB_LIB.T6G(SCH_1):GMI_CPU0_G0_CPU1_G2_TX_DN'<3>:
 C_SIGNAL='@t6g_mb_lib.t6g(sch_1):gmi_cpu0_g0_cpu1_g2_tx_dn(3)';
NODE_NAME     U25 AG44
 '@T6G_MB_LIB.T6G(SCH_1):PAGE22_I207@PURE_QUANTA.GENOA_SP5(CHIPS)':
 'G0_TXN3': CDS_PINID='G0_TXN3';
NODE_NAME     U26 AG32
 '@T6G_MB_LIB.T6G(SCH_1):PAGE50_I143@PURE_QUANTA.GENOA_SP5(CHIPS)':
 'G2_RXN12': CDS_PINID='G2_RXN12';
NET_NAME
'GMI_CPU0_G0_CPU1_G2_TX_DN<4>'
 '@T6G_MB_LIB.T6G(SCH_1):GMI_CPU0_G0_CPU1_G2_TX_DN'<4>:
 C_SIGNAL='@t6g_mb_lib.t6g(sch_1):gmi_cpu0_g0_cpu1_g2_tx_dn(4)';
NODE_NAME     U25 AA44
 '@T6G_MB_LIB.T6G(SCH_1):PAGE22_I207@PURE_QUANTA.GENOA_SP5(CHIPS)':
 'G0_TXN4': CDS_PINID='G0_TXN4';
NODE_NAME     U26 AA32
 '@T6G_MB_LIB.T6G(SCH_1):PAGE50_I143@PURE_QUANTA.GENOA_SP5(CHIPS)':
 'G2_RXN11': CDS_PINID='G2_RXN11';
NET_NAME
'GMI_CPU0_G0_CPU1_G2_TX_DN<5>'
 '@T6G_MB_LIB.T6G(SCH_1):GMI_CPU0_G0_CPU1_G2_TX_DN'<5>:
 C_SIGNAL='@t6g_mb_lib.t6g(sch_1):gmi_cpu0_g0_cpu1_g2_tx_dn(5)';
NODE_NAME     U25 AC44
 '@T6G_MB_LIB.T6G(SCH_1):PAGE22_I207@PURE_QUANTA.GENOA_SP5(CHIPS)':
 'G0_TXN5': CDS_PINID='G0_TXN5';
NODE_NAME     U26 AC32
 '@T6G_MB_LIB.T6G(SCH_1):PAGE50_I143@PURE_QUANTA.GENOA_SP5(CHIPS)':
 'G2_RXN10': CDS_PINID='G2_RXN10';
NET_NAME
'GMI_CPU0_G0_CPU1_G2_TX_DN<6>'
 '@T6G_MB_LIB.T6G(SCH_1):GMI_CPU0_G0_CPU1_G2_TX_DN'<6>:
 C_SIGNAL='@t6g_mb_lib.t6g(sch_1):gmi_cpu0_g0_cpu1_g2_tx_dn(6)';
NODE_NAME     U25 AE44
 '@T6G_MB_LIB.T6G(SCH_1):PAGE22_I207@PURE_QUANTA.GENOA_SP5(CHIPS)':
 'G0_TXN6': CDS_PINID='G0_TXN6';
NODE_NAME     U26 AE32
 '@T6G_MB_LIB.T6G(SCH_1):PAGE50_I143@PURE_QUANTA.GENOA_SP5(CHIPS)':
 'G2_RXN9': CDS_PINID='G2_RXN9';
NET_NAME
'GMI_CPU0_G0_CPU1_G2_TX_DN<7>'
 '@T6G_MB_LIB.T6G(SCH_1):GMI_CPU0_G0_CPU1_G2_TX_DN'<7>:
 C_SIGNAL='@t6g_mb_lib.t6g(sch_1):gmi_cpu0_g0_cpu1_g2_tx_dn(7)';
NODE_NAME     U25 AG47
 '@T6G_MB_LIB.T6G(SCH_1):PAGE22_I207@PURE_QUANTA.GENOA_SP5(CHIPS)':
 'G0_TXN7': CDS_PINID='G0_TXN7';
NODE_NAME     U26 AG29
 '@T6G_MB_LIB.T6G(SCH_1):PAGE50_I143@PURE_QUANTA.GENOA_SP5(CHIPS)':
 'G2_RXN8': CDS_PINID='G2_RXN8';
NET_NAME
'GMI_CPU0_G0_CPU1_G2_TX_DN<8>'
 '@T6G_MB_LIB.T6G(SCH_1):GMI_CPU0_G0_CPU1_G2_TX_DN'<8>:
 C_SIGNAL='@t6g_mb_lib.t6g(sch_1):gmi_cpu0_g0_cpu1_g2_tx_dn(8)';
NODE_NAME     U25 AC47
 '@T6G_MB_LIB.T6G(SCH_1):PAGE22_I207@PURE_QUANTA.GENOA_SP5(CHIPS)':
 'G0_TXN8': CDS_PINID='G0_TXN8';
NODE_NAME     U26 AC29
 '@T6G_MB_LIB.T6G(SCH_1):PAGE50_I143@PURE_QUANTA.GENOA_SP5(CHIPS)':
 'G2_RXN7': CDS_PINID='G2_RXN7';
NET_NAME
'GMI_CPU0_G0_CPU1_G2_TX_DN<9>'
 '@T6G_MB_LIB.T6G(SCH_1):GMI_CPU0_G0_CPU1_G2_TX_DN'<9>:
 C_SIGNAL='@t6g_mb_lib.t6g(sch_1):gmi_cpu0_g0_cpu1_g2_tx_dn(9)';
NODE_NAME     U25 AE47
 '@T6G_MB_LIB.T6G(SCH_1):PAGE22_I207@PURE_QUANTA.GENOA_SP5(CHIPS)':
 'G0_TXN9': CDS_PINID='G0_TXN9';
NODE_NAME     U26 AE29
 '@T6G_MB_LIB.T6G(SCH_1):PAGE50_I143@PURE_QUANTA.GENOA_SP5(CHIPS)':
 'G2_RXN6': CDS_PINID='G2_RXN6';
NET_NAME
'GMI_CPU0_G0_CPU1_G2_TX_DP<0>'
 '@T6G_MB_LIB.T6G(SCH_1):GMI_CPU0_G0_CPU1_G2_TX_DP'<0>:
 C_SIGNAL='@t6g_mb_lib.t6g(sch_1):gmi_cpu0_g0_cpu1_g2_tx_dp(0)';
NODE_NAME     U25 AF40
 '@T6G_MB_LIB.T6G(SCH_1):PAGE22_I207@PURE_QUANTA.GENOA_SP5(CHIPS)':
 'G0_TXP0': CDS_PINID='G0_TXP0';
NODE_NAME     U26 AF36
 '@T6G_MB_LIB.T6G(SCH_1):PAGE50_I143@PURE_QUANTA.GENOA_SP5(CHIPS)':
 'G2_RXP15': CDS_PINID='G2_RXP15';
NET_NAME
'GMI_CPU0_G0_CPU1_G2_TX_DP<10>'
 '@T6G_MB_LIB.T6G(SCH_1):GMI_CPU0_G0_CPU1_G2_TX_DP'<10>:
 C_SIGNAL='@t6g_mb_lib.t6g(sch_1):gmi_cpu0_g0_cpu1_g2_tx_dp(10)';
NODE_NAME     U25 AG49
 '@T6G_MB_LIB.T6G(SCH_1):PAGE22_I207@PURE_QUANTA.GENOA_SP5(CHIPS)':
 'G0_TXP10': CDS_PINID='G0_TXP10';
NODE_NAME     U26 AG27
 '@T6G_MB_LIB.T6G(SCH_1):PAGE50_I143@PURE_QUANTA.GENOA_SP5(CHIPS)':
 'G2_RXP5': CDS_PINID='G2_RXP5';
NET_NAME
'GMI_CPU0_G0_CPU1_G2_TX_DP<11>'
 '@T6G_MB_LIB.T6G(SCH_1):GMI_CPU0_G0_CPU1_G2_TX_DP'<11>:
 C_SIGNAL='@t6g_mb_lib.t6g(sch_1):gmi_cpu0_g0_cpu1_g2_tx_dp(11)';
NODE_NAME     U25 AC49
 '@T6G_MB_LIB.T6G(SCH_1):PAGE22_I207@PURE_QUANTA.GENOA_SP5(CHIPS)':
 'G0_TXP11': CDS_PINID='G0_TXP11';
NODE_NAME     U26 AC27
 '@T6G_MB_LIB.T6G(SCH_1):PAGE50_I143@PURE_QUANTA.GENOA_SP5(CHIPS)':
 'G2_RXP4': CDS_PINID='G2_RXP4';
NET_NAME
'GMI_CPU0_G0_CPU1_G2_TX_DP<12>'
 '@T6G_MB_LIB.T6G(SCH_1):GMI_CPU0_G0_CPU1_G2_TX_DP'<12>:
 C_SIGNAL='@t6g_mb_lib.t6g(sch_1):gmi_cpu0_g0_cpu1_g2_tx_dp(12)';
NODE_NAME     U25 AE49
 '@T6G_MB_LIB.T6G(SCH_1):PAGE22_I207@PURE_QUANTA.GENOA_SP5(CHIPS)':
 'G0_TXP12': CDS_PINID='G0_TXP12';
NODE_NAME     U26 AE27
 '@T6G_MB_LIB.T6G(SCH_1):PAGE50_I143@PURE_QUANTA.GENOA_SP5(CHIPS)':
 'G2_RXP3': CDS_PINID='G2_RXP3';
NET_NAME
'GMI_CPU0_G0_CPU1_G2_TX_DP<13>'
 '@T6G_MB_LIB.T6G(SCH_1):GMI_CPU0_G0_CPU1_G2_TX_DP'<13>:
 C_SIGNAL='@t6g_mb_lib.t6g(sch_1):gmi_cpu0_g0_cpu1_g2_tx_dp(13)';
NODE_NAME     U25 AG52
 '@T6G_MB_LIB.T6G(SCH_1):PAGE22_I207@PURE_QUANTA.GENOA_SP5(CHIPS)':
 'G0_TXP13': CDS_PINID='G0_TXP13';
NODE_NAME     U26 AG24
 '@T6G_MB_LIB.T6G(SCH_1):PAGE50_I143@PURE_QUANTA.GENOA_SP5(CHIPS)':
 'G2_RXP2': CDS_PINID='G2_RXP2';
NET_NAME
'GMI_CPU0_G0_CPU1_G2_TX_DP<14>'
 '@T6G_MB_LIB.T6G(SCH_1):GMI_CPU0_G0_CPU1_G2_TX_DP'<14>:
 C_SIGNAL='@t6g_mb_lib.t6g(sch_1):gmi_cpu0_g0_cpu1_g2_tx_dp(14)';
NODE_NAME     U25 AC52
 '@T6G_MB_LIB.T6G(SCH_1):PAGE22_I207@PURE_QUANTA.GENOA_SP5(CHIPS)':
 'G0_TXP14': CDS_PINID='G0_TXP14';
NODE_NAME     U26 AC24
 '@T6G_MB_LIB.T6G(SCH_1):PAGE50_I143@PURE_QUANTA.GENOA_SP5(CHIPS)':
 'G2_RXP1': CDS_PINID='G2_RXP1';
NET_NAME
'GMI_CPU0_G0_CPU1_G2_TX_DP<15>'
 '@T6G_MB_LIB.T6G(SCH_1):GMI_CPU0_G0_CPU1_G2_TX_DP'<15>:
 C_SIGNAL='@t6g_mb_lib.t6g(sch_1):gmi_cpu0_g0_cpu1_g2_tx_dp(15)';
NODE_NAME     U25 AE52
 '@T6G_MB_LIB.T6G(SCH_1):PAGE22_I207@PURE_QUANTA.GENOA_SP5(CHIPS)':
 'G0_TXP15': CDS_PINID='G0_TXP15';
NODE_NAME     U26 AE24
 '@T6G_MB_LIB.T6G(SCH_1):PAGE50_I143@PURE_QUANTA.GENOA_SP5(CHIPS)':
 'G2_RXP0': CDS_PINID='G2_RXP0';
NET_NAME
'GMI_CPU0_G0_CPU1_G2_TX_DP<1>'
 '@T6G_MB_LIB.T6G(SCH_1):GMI_CPU0_G0_CPU1_G2_TX_DP'<1>:
 C_SIGNAL='@t6g_mb_lib.t6g(sch_1):gmi_cpu0_g0_cpu1_g2_tx_dp(1)';
NODE_NAME     U25 AD40
 '@T6G_MB_LIB.T6G(SCH_1):PAGE22_I207@PURE_QUANTA.GENOA_SP5(CHIPS)':
 'G0_TXP1': CDS_PINID='G0_TXP1';
NODE_NAME     U26 AD36
 '@T6G_MB_LIB.T6G(SCH_1):PAGE50_I143@PURE_QUANTA.GENOA_SP5(CHIPS)':
 'G2_RXP14': CDS_PINID='G2_RXP14';
NET_NAME
'GMI_CPU0_G0_CPU1_G2_TX_DP<2>'
 '@T6G_MB_LIB.T6G(SCH_1):GMI_CPU0_G0_CPU1_G2_TX_DP'<2>:
 C_SIGNAL='@t6g_mb_lib.t6g(sch_1):gmi_cpu0_g0_cpu1_g2_tx_dp(2)';
NODE_NAME     U25 AB40
 '@T6G_MB_LIB.T6G(SCH_1):PAGE22_I207@PURE_QUANTA.GENOA_SP5(CHIPS)':
 'G0_TXP2': CDS_PINID='G0_TXP2';
NODE_NAME     U26 AB36
 '@T6G_MB_LIB.T6G(SCH_1):PAGE50_I143@PURE_QUANTA.GENOA_SP5(CHIPS)':
 'G2_RXP13': CDS_PINID='G2_RXP13';
NET_NAME
'GMI_CPU0_G0_CPU1_G2_TX_DP<3>'
 '@T6G_MB_LIB.T6G(SCH_1):GMI_CPU0_G0_CPU1_G2_TX_DP'<3>:
 C_SIGNAL='@t6g_mb_lib.t6g(sch_1):gmi_cpu0_g0_cpu1_g2_tx_dp(3)';
NODE_NAME     U25 AG43
 '@T6G_MB_LIB.T6G(SCH_1):PAGE22_I207@PURE_QUANTA.GENOA_SP5(CHIPS)':
 'G0_TXP3': CDS_PINID='G0_TXP3';
NODE_NAME     U26 AG33
 '@T6G_MB_LIB.T6G(SCH_1):PAGE50_I143@PURE_QUANTA.GENOA_SP5(CHIPS)':
 'G2_RXP12': CDS_PINID='G2_RXP12';
NET_NAME
'GMI_CPU0_G0_CPU1_G2_TX_DP<4>'
 '@T6G_MB_LIB.T6G(SCH_1):GMI_CPU0_G0_CPU1_G2_TX_DP'<4>:
 C_SIGNAL='@t6g_mb_lib.t6g(sch_1):gmi_cpu0_g0_cpu1_g2_tx_dp(4)';
NODE_NAME     U25 AA43
 '@T6G_MB_LIB.T6G(SCH_1):PAGE22_I207@PURE_QUANTA.GENOA_SP5(CHIPS)':
 'G0_TXP4': CDS_PINID='G0_TXP4';
NODE_NAME     U26 AA33
 '@T6G_MB_LIB.T6G(SCH_1):PAGE50_I143@PURE_QUANTA.GENOA_SP5(CHIPS)':
 'G2_RXP11': CDS_PINID='G2_RXP11';
NET_NAME
'GMI_CPU0_G0_CPU1_G2_TX_DP<5>'
 '@T6G_MB_LIB.T6G(SCH_1):GMI_CPU0_G0_CPU1_G2_TX_DP'<5>:
 C_SIGNAL='@t6g_mb_lib.t6g(sch_1):gmi_cpu0_g0_cpu1_g2_tx_dp(5)';
NODE_NAME     U25 AC43
 '@T6G_MB_LIB.T6G(SCH_1):PAGE22_I207@PURE_QUANTA.GENOA_SP5(CHIPS)':
 'G0_TXP5': CDS_PINID='G0_TXP5';
NODE_NAME     U26 AC33
 '@T6G_MB_LIB.T6G(SCH_1):PAGE50_I143@PURE_QUANTA.GENOA_SP5(CHIPS)':
 'G2_RXP10': CDS_PINID='G2_RXP10';
NET_NAME
'GMI_CPU0_G0_CPU1_G2_TX_DP<6>'
 '@T6G_MB_LIB.T6G(SCH_1):GMI_CPU0_G0_CPU1_G2_TX_DP'<6>:
 C_SIGNAL='@t6g_mb_lib.t6g(sch_1):gmi_cpu0_g0_cpu1_g2_tx_dp(6)';
NODE_NAME     U25 AE43
 '@T6G_MB_LIB.T6G(SCH_1):PAGE22_I207@PURE_QUANTA.GENOA_SP5(CHIPS)':
 'G0_TXP6': CDS_PINID='G0_TXP6';
NODE_NAME     U26 AE33
 '@T6G_MB_LIB.T6G(SCH_1):PAGE50_I143@PURE_QUANTA.GENOA_SP5(CHIPS)':
 'G2_RXP9': CDS_PINID='G2_RXP9';
NET_NAME
'GMI_CPU0_G0_CPU1_G2_TX_DP<7>'
 '@T6G_MB_LIB.T6G(SCH_1):GMI_CPU0_G0_CPU1_G2_TX_DP'<7>:
 C_SIGNAL='@t6g_mb_lib.t6g(sch_1):gmi_cpu0_g0_cpu1_g2_tx_dp(7)';
NODE_NAME     U25 AG46
 '@T6G_MB_LIB.T6G(SCH_1):PAGE22_I207@PURE_QUANTA.GENOA_SP5(CHIPS)':
 'G0_TXP7': CDS_PINID='G0_TXP7';
NODE_NAME     U26 AG30
 '@T6G_MB_LIB.T6G(SCH_1):PAGE50_I143@PURE_QUANTA.GENOA_SP5(CHIPS)':
 'G2_RXP8': CDS_PINID='G2_RXP8';
NET_NAME
'GMI_CPU0_G0_CPU1_G2_TX_DP<8>'
 '@T6G_MB_LIB.T6G(SCH_1):GMI_CPU0_G0_CPU1_G2_TX_DP'<8>:
 C_SIGNAL='@t6g_mb_lib.t6g(sch_1):gmi_cpu0_g0_cpu1_g2_tx_dp(8)';
NODE_NAME     U25 AC46
 '@T6G_MB_LIB.T6G(SCH_1):PAGE22_I207@PURE_QUANTA.GENOA_SP5(CHIPS)':
 'G0_TXP8': CDS_PINID='G0_TXP8';
NODE_NAME     U26 AC30
 '@T6G_MB_LIB.T6G(SCH_1):PAGE50_I143@PURE_QUANTA.GENOA_SP5(CHIPS)':
 'G2_RXP7': CDS_PINID='G2_RXP7';
NET_NAME
'GMI_CPU0_G0_CPU1_G2_TX_DP<9>'
 '@T6G_MB_LIB.T6G(SCH_1):GMI_CPU0_G0_CPU1_G2_TX_DP'<9>:
 C_SIGNAL='@t6g_mb_lib.t6g(sch_1):gmi_cpu0_g0_cpu1_g2_tx_dp(9)';
NODE_NAME     U25 AE46
 '@T6G_MB_LIB.T6G(SCH_1):PAGE22_I207@PURE_QUANTA.GENOA_SP5(CHIPS)':
 'G0_TXP9': CDS_PINID='G0_TXP9';
NODE_NAME     U26 AE30
 '@T6G_MB_LIB.T6G(SCH_1):PAGE50_I143@PURE_QUANTA.GENOA_SP5(CHIPS)':
 'G2_RXP6': CDS_PINID='G2_RXP6';
NET_NAME
'GMI_CPU0_G1_CPU1_G3_TX_DN<0>'
 '@T6G_MB_LIB.T6G(SCH_1):GMI_CPU0_G1_CPU1_G3_TX_DN'<0>:
 C_SIGNAL='@t6g_mb_lib.t6g(sch_1):gmi_cpu0_g1_cpu1_g3_tx_dn(0)';
NODE_NAME     U25 AP41
 '@T6G_MB_LIB.T6G(SCH_1):PAGE22_I208@PURE_QUANTA.GENOA_SP5(CHIPS)':
 'G1_TXN0': CDS_PINID='G1_TXN0';
NODE_NAME     U26 AP35
 '@T6G_MB_LIB.T6G(SCH_1):PAGE50_I144@PURE_QUANTA.GENOA_SP5(CHIPS)':
 'G3_RXN15||SATA37_RXN': CDS_PINID='\g3_rxn15||sata37_rxn\';
NET_NAME
'GMI_CPU0_G1_CPU1_G3_TX_DN<10>'
 '@T6G_MB_LIB.T6G(SCH_1):GMI_CPU0_G1_CPU1_G3_TX_DN'<10>:
 C_SIGNAL='@t6g_mb_lib.t6g(sch_1):gmi_cpu0_g1_cpu1_g3_tx_dn(10)';
NODE_NAME     U25 AN50
 '@T6G_MB_LIB.T6G(SCH_1):PAGE22_I208@PURE_QUANTA.GENOA_SP5(CHIPS)':
 'G1_TXN10': CDS_PINID='G1_TXN10';
NODE_NAME     U26 AN26
 '@T6G_MB_LIB.T6G(SCH_1):PAGE50_I144@PURE_QUANTA.GENOA_SP5(CHIPS)':
 'G3_RXN5||SATA25_RXN': CDS_PINID='\g3_rxn5||sata25_rxn\';
NET_NAME
'GMI_CPU0_G1_CPU1_G3_TX_DN<11>'
 '@T6G_MB_LIB.T6G(SCH_1):GMI_CPU0_G1_CPU1_G3_TX_DN'<11>:
 C_SIGNAL='@t6g_mb_lib.t6g(sch_1):gmi_cpu0_g1_cpu1_g3_tx_dn(11)';
NODE_NAME     U25 AJ50
 '@T6G_MB_LIB.T6G(SCH_1):PAGE22_I208@PURE_QUANTA.GENOA_SP5(CHIPS)':
 'G1_TXN11': CDS_PINID='G1_TXN11';
NODE_NAME     U26 AJ26
 '@T6G_MB_LIB.T6G(SCH_1):PAGE50_I144@PURE_QUANTA.GENOA_SP5(CHIPS)':
 'G3_RXN4||SATA24_RXN': CDS_PINID='\g3_rxn4||sata24_rxn\';
NET_NAME
'GMI_CPU0_G1_CPU1_G3_TX_DN<12>'
 '@T6G_MB_LIB.T6G(SCH_1):GMI_CPU0_G1_CPU1_G3_TX_DN'<12>:
 C_SIGNAL='@t6g_mb_lib.t6g(sch_1):gmi_cpu0_g1_cpu1_g3_tx_dn(12)';
NODE_NAME     U25 AL50
 '@T6G_MB_LIB.T6G(SCH_1):PAGE22_I208@PURE_QUANTA.GENOA_SP5(CHIPS)':
 'G1_TXN12': CDS_PINID='G1_TXN12';
NODE_NAME     U26 AL26
 '@T6G_MB_LIB.T6G(SCH_1):PAGE50_I144@PURE_QUANTA.GENOA_SP5(CHIPS)':
 'G3_RXN3||SATA23_RXN': CDS_PINID='\g3_rxn3||sata23_rxn\';
NET_NAME
'GMI_CPU0_G1_CPU1_G3_TX_DN<13>'
 '@T6G_MB_LIB.T6G(SCH_1):GMI_CPU0_G1_CPU1_G3_TX_DN'<13>:
 C_SIGNAL='@t6g_mb_lib.t6g(sch_1):gmi_cpu0_g1_cpu1_g3_tx_dn(13)';
NODE_NAME     U25 AN53
 '@T6G_MB_LIB.T6G(SCH_1):PAGE22_I208@PURE_QUANTA.GENOA_SP5(CHIPS)':
 'G1_TXN13': CDS_PINID='G1_TXN13';
NODE_NAME     U26 AN23
 '@T6G_MB_LIB.T6G(SCH_1):PAGE50_I144@PURE_QUANTA.GENOA_SP5(CHIPS)':
 'G3_RXN2||SATA22_RXN': CDS_PINID='\g3_rxn2||sata22_rxn\';
NET_NAME
'GMI_CPU0_G1_CPU1_G3_TX_DN<14>'
 '@T6G_MB_LIB.T6G(SCH_1):GMI_CPU0_G1_CPU1_G3_TX_DN'<14>:
 C_SIGNAL='@t6g_mb_lib.t6g(sch_1):gmi_cpu0_g1_cpu1_g3_tx_dn(14)';
NODE_NAME     U25 AJ53
 '@T6G_MB_LIB.T6G(SCH_1):PAGE22_I208@PURE_QUANTA.GENOA_SP5(CHIPS)':
 'G1_TXN14': CDS_PINID='G1_TXN14';
NODE_NAME     U26 AJ23
 '@T6G_MB_LIB.T6G(SCH_1):PAGE50_I144@PURE_QUANTA.GENOA_SP5(CHIPS)':
 'G3_RXN1||SATA21_RXN': CDS_PINID='\g3_rxn1||sata21_rxn\';
NET_NAME
'GMI_CPU0_G1_CPU1_G3_TX_DN<15>'
 '@T6G_MB_LIB.T6G(SCH_1):GMI_CPU0_G1_CPU1_G3_TX_DN'<15>:
 C_SIGNAL='@t6g_mb_lib.t6g(sch_1):gmi_cpu0_g1_cpu1_g3_tx_dn(15)';
NODE_NAME     U25 AL53
 '@T6G_MB_LIB.T6G(SCH_1):PAGE22_I208@PURE_QUANTA.GENOA_SP5(CHIPS)':
 'G1_TXN15': CDS_PINID='G1_TXN15';
NODE_NAME     U26 AL23
 '@T6G_MB_LIB.T6G(SCH_1):PAGE50_I144@PURE_QUANTA.GENOA_SP5(CHIPS)':
 'G3_RXN0||SATA20_RXN': CDS_PINID='\g3_rxn0||sata20_rxn\';
NET_NAME
'GMI_CPU0_G1_CPU1_G3_TX_DN<1>'
 '@T6G_MB_LIB.T6G(SCH_1):GMI_CPU0_G1_CPU1_G3_TX_DN'<1>:
 C_SIGNAL='@t6g_mb_lib.t6g(sch_1):gmi_cpu0_g1_cpu1_g3_tx_dn(1)';
NODE_NAME     U25 AM41
 '@T6G_MB_LIB.T6G(SCH_1):PAGE22_I208@PURE_QUANTA.GENOA_SP5(CHIPS)':
 'G1_TXN1': CDS_PINID='G1_TXN1';
NODE_NAME     U26 AM35
 '@T6G_MB_LIB.T6G(SCH_1):PAGE50_I144@PURE_QUANTA.GENOA_SP5(CHIPS)':
 'G3_RXN14||SATA36_RXN': CDS_PINID='\g3_rxn14||sata36_rxn\';
NET_NAME
'GMI_CPU0_G1_CPU1_G3_TX_DN<2>'
 '@T6G_MB_LIB.T6G(SCH_1):GMI_CPU0_G1_CPU1_G3_TX_DN'<2>:
 C_SIGNAL='@t6g_mb_lib.t6g(sch_1):gmi_cpu0_g1_cpu1_g3_tx_dn(2)';
NODE_NAME     U25 AH41
 '@T6G_MB_LIB.T6G(SCH_1):PAGE22_I208@PURE_QUANTA.GENOA_SP5(CHIPS)':
 'G1_TXN2': CDS_PINID='G1_TXN2';
NODE_NAME     U26 AH35
 '@T6G_MB_LIB.T6G(SCH_1):PAGE50_I144@PURE_QUANTA.GENOA_SP5(CHIPS)':
 'G3_RXN13||SATA35_RXN': CDS_PINID='\g3_rxn13||sata35_rxn\';
NET_NAME
'GMI_CPU0_G1_CPU1_G3_TX_DN<3>'
 '@T6G_MB_LIB.T6G(SCH_1):GMI_CPU0_G1_CPU1_G3_TX_DN'<3>:
 C_SIGNAL='@t6g_mb_lib.t6g(sch_1):gmi_cpu0_g1_cpu1_g3_tx_dn(3)';
NODE_NAME     U25 AK41
 '@T6G_MB_LIB.T6G(SCH_1):PAGE22_I208@PURE_QUANTA.GENOA_SP5(CHIPS)':
 'G1_TXN3': CDS_PINID='G1_TXN3';
NODE_NAME     U26 AK35
 '@T6G_MB_LIB.T6G(SCH_1):PAGE50_I144@PURE_QUANTA.GENOA_SP5(CHIPS)':
 'G3_RXN12||SATA34_RXN': CDS_PINID='\g3_rxn12||sata34_rxn\';
NET_NAME
'GMI_CPU0_G1_CPU1_G3_TX_DN<4>'
 '@T6G_MB_LIB.T6G(SCH_1):GMI_CPU0_G1_CPU1_G3_TX_DN'<4>:
 C_SIGNAL='@t6g_mb_lib.t6g(sch_1):gmi_cpu0_g1_cpu1_g3_tx_dn(4)';
NODE_NAME     U25 AN44
 '@T6G_MB_LIB.T6G(SCH_1):PAGE22_I208@PURE_QUANTA.GENOA_SP5(CHIPS)':
 'G1_TXN4': CDS_PINID='G1_TXN4';
NODE_NAME     U26 AN32
 '@T6G_MB_LIB.T6G(SCH_1):PAGE50_I144@PURE_QUANTA.GENOA_SP5(CHIPS)':
 'G3_RXN11||SATA33_RXN': CDS_PINID='\g3_rxn11||sata33_rxn\';
NET_NAME
'GMI_CPU0_G1_CPU1_G3_TX_DN<5>'
 '@T6G_MB_LIB.T6G(SCH_1):GMI_CPU0_G1_CPU1_G3_TX_DN'<5>:
 C_SIGNAL='@t6g_mb_lib.t6g(sch_1):gmi_cpu0_g1_cpu1_g3_tx_dn(5)';
NODE_NAME     U25 AJ44
 '@T6G_MB_LIB.T6G(SCH_1):PAGE22_I208@PURE_QUANTA.GENOA_SP5(CHIPS)':
 'G1_TXN5': CDS_PINID='G1_TXN5';
NODE_NAME     U26 AJ32
 '@T6G_MB_LIB.T6G(SCH_1):PAGE50_I144@PURE_QUANTA.GENOA_SP5(CHIPS)':
 'G3_RXN10||SATA32_RXN': CDS_PINID='\g3_rxn10||sata32_rxn\';
NET_NAME
'GMI_CPU0_G1_CPU1_G3_TX_DN<6>'
 '@T6G_MB_LIB.T6G(SCH_1):GMI_CPU0_G1_CPU1_G3_TX_DN'<6>:
 C_SIGNAL='@t6g_mb_lib.t6g(sch_1):gmi_cpu0_g1_cpu1_g3_tx_dn(6)';
NODE_NAME     U25 AL44
 '@T6G_MB_LIB.T6G(SCH_1):PAGE22_I208@PURE_QUANTA.GENOA_SP5(CHIPS)':
 'G1_TXN6': CDS_PINID='G1_TXN6';
NODE_NAME     U26 AL32
 '@T6G_MB_LIB.T6G(SCH_1):PAGE50_I144@PURE_QUANTA.GENOA_SP5(CHIPS)':
 'G3_RXN9||SATA31_RXN': CDS_PINID='\g3_rxn9||sata31_rxn\';
NET_NAME
'GMI_CPU0_G1_CPU1_G3_TX_DN<7>'
 '@T6G_MB_LIB.T6G(SCH_1):GMI_CPU0_G1_CPU1_G3_TX_DN'<7>:
 C_SIGNAL='@t6g_mb_lib.t6g(sch_1):gmi_cpu0_g1_cpu1_g3_tx_dn(7)';
NODE_NAME     U25 AN47
 '@T6G_MB_LIB.T6G(SCH_1):PAGE22_I208@PURE_QUANTA.GENOA_SP5(CHIPS)':
 'G1_TXN7': CDS_PINID='G1_TXN7';
NODE_NAME     U26 AN29
 '@T6G_MB_LIB.T6G(SCH_1):PAGE50_I144@PURE_QUANTA.GENOA_SP5(CHIPS)':
 'G3_RXN8||SATA30_RXN': CDS_PINID='\g3_rxn8||sata30_rxn\';
NET_NAME
'GMI_CPU0_G1_CPU1_G3_TX_DN<8>'
 '@T6G_MB_LIB.T6G(SCH_1):GMI_CPU0_G1_CPU1_G3_TX_DN'<8>:
 C_SIGNAL='@t6g_mb_lib.t6g(sch_1):gmi_cpu0_g1_cpu1_g3_tx_dn(8)';
NODE_NAME     U25 AJ47
 '@T6G_MB_LIB.T6G(SCH_1):PAGE22_I208@PURE_QUANTA.GENOA_SP5(CHIPS)':
 'G1_TXN8': CDS_PINID='G1_TXN8';
NODE_NAME     U26 AJ29
 '@T6G_MB_LIB.T6G(SCH_1):PAGE50_I144@PURE_QUANTA.GENOA_SP5(CHIPS)':
 'G3_RXN7||SATA27_RXN': CDS_PINID='\g3_rxn7||sata27_rxn\';
NET_NAME
'GMI_CPU0_G1_CPU1_G3_TX_DN<9>'
 '@T6G_MB_LIB.T6G(SCH_1):GMI_CPU0_G1_CPU1_G3_TX_DN'<9>:
 C_SIGNAL='@t6g_mb_lib.t6g(sch_1):gmi_cpu0_g1_cpu1_g3_tx_dn(9)';
NODE_NAME     U25 AL47
 '@T6G_MB_LIB.T6G(SCH_1):PAGE22_I208@PURE_QUANTA.GENOA_SP5(CHIPS)':
 'G1_TXN9': CDS_PINID='G1_TXN9';
NODE_NAME     U26 AL29
 '@T6G_MB_LIB.T6G(SCH_1):PAGE50_I144@PURE_QUANTA.GENOA_SP5(CHIPS)':
 'G3_RXN6||SATA26_RXN': CDS_PINID='\g3_rxn6||sata26_rxn\';
NET_NAME
'GMI_CPU0_G1_CPU1_G3_TX_DP<0>'
 '@T6G_MB_LIB.T6G(SCH_1):GMI_CPU0_G1_CPU1_G3_TX_DP'<0>:
 C_SIGNAL='@t6g_mb_lib.t6g(sch_1):gmi_cpu0_g1_cpu1_g3_tx_dp(0)';
NODE_NAME     U25 AP40
 '@T6G_MB_LIB.T6G(SCH_1):PAGE22_I208@PURE_QUANTA.GENOA_SP5(CHIPS)':
 'G1_TXP0': CDS_PINID='G1_TXP0';
NODE_NAME     U26 AP36
 '@T6G_MB_LIB.T6G(SCH_1):PAGE50_I144@PURE_QUANTA.GENOA_SP5(CHIPS)':
 'G3_RXP15||SATA37_RXP': CDS_PINID='\g3_rxp15||sata37_rxp\';
NET_NAME
'GMI_CPU0_G1_CPU1_G3_TX_DP<10>'
 '@T6G_MB_LIB.T6G(SCH_1):GMI_CPU0_G1_CPU1_G3_TX_DP'<10>:
 C_SIGNAL='@t6g_mb_lib.t6g(sch_1):gmi_cpu0_g1_cpu1_g3_tx_dp(10)';
NODE_NAME     U25 AN49
 '@T6G_MB_LIB.T6G(SCH_1):PAGE22_I208@PURE_QUANTA.GENOA_SP5(CHIPS)':
 'G1_TXP10': CDS_PINID='G1_TXP10';
NODE_NAME     U26 AN27
 '@T6G_MB_LIB.T6G(SCH_1):PAGE50_I144@PURE_QUANTA.GENOA_SP5(CHIPS)':
 'G3_RXP5||SATA25_RXP': CDS_PINID='\g3_rxp5||sata25_rxp\';
NET_NAME
'GMI_CPU0_G1_CPU1_G3_TX_DP<11>'
 '@T6G_MB_LIB.T6G(SCH_1):GMI_CPU0_G1_CPU1_G3_TX_DP'<11>:
 C_SIGNAL='@t6g_mb_lib.t6g(sch_1):gmi_cpu0_g1_cpu1_g3_tx_dp(11)';
NODE_NAME     U25 AJ49
 '@T6G_MB_LIB.T6G(SCH_1):PAGE22_I208@PURE_QUANTA.GENOA_SP5(CHIPS)':
 'G1_TXP11': CDS_PINID='G1_TXP11';
NODE_NAME     U26 AJ27
 '@T6G_MB_LIB.T6G(SCH_1):PAGE50_I144@PURE_QUANTA.GENOA_SP5(CHIPS)':
 'G3_RXP4||SATA24_RXP': CDS_PINID='\g3_rxp4||sata24_rxp\';
NET_NAME
'GMI_CPU0_G1_CPU1_G3_TX_DP<12>'
 '@T6G_MB_LIB.T6G(SCH_1):GMI_CPU0_G1_CPU1_G3_TX_DP'<12>:
 C_SIGNAL='@t6g_mb_lib.t6g(sch_1):gmi_cpu0_g1_cpu1_g3_tx_dp(12)';
NODE_NAME     U25 AL49
 '@T6G_MB_LIB.T6G(SCH_1):PAGE22_I208@PURE_QUANTA.GENOA_SP5(CHIPS)':
 'G1_TXP12': CDS_PINID='G1_TXP12';
NODE_NAME     U26 AL27
 '@T6G_MB_LIB.T6G(SCH_1):PAGE50_I144@PURE_QUANTA.GENOA_SP5(CHIPS)':
 'G3_RXP3||SATA23_RXP': CDS_PINID='\g3_rxp3||sata23_rxp\';
NET_NAME
'GMI_CPU0_G1_CPU1_G3_TX_DP<13>'
 '@T6G_MB_LIB.T6G(SCH_1):GMI_CPU0_G1_CPU1_G3_TX_DP'<13>:
 C_SIGNAL='@t6g_mb_lib.t6g(sch_1):gmi_cpu0_g1_cpu1_g3_tx_dp(13)';
NODE_NAME     U25 AN52
 '@T6G_MB_LIB.T6G(SCH_1):PAGE22_I208@PURE_QUANTA.GENOA_SP5(CHIPS)':
 'G1_TXP13': CDS_PINID='G1_TXP13';
NODE_NAME     U26 AN24
 '@T6G_MB_LIB.T6G(SCH_1):PAGE50_I144@PURE_QUANTA.GENOA_SP5(CHIPS)':
 'G3_RXP2||SATA22_RXP': CDS_PINID='\g3_rxp2||sata22_rxp\';
NET_NAME
'GMI_CPU0_G1_CPU1_G3_TX_DP<14>'
 '@T6G_MB_LIB.T6G(SCH_1):GMI_CPU0_G1_CPU1_G3_TX_DP'<14>:
 C_SIGNAL='@t6g_mb_lib.t6g(sch_1):gmi_cpu0_g1_cpu1_g3_tx_dp(14)';
NODE_NAME     U25 AJ52
 '@T6G_MB_LIB.T6G(SCH_1):PAGE22_I208@PURE_QUANTA.GENOA_SP5(CHIPS)':
 'G1_TXP14': CDS_PINID='G1_TXP14';
NODE_NAME     U26 AJ24
 '@T6G_MB_LIB.T6G(SCH_1):PAGE50_I144@PURE_QUANTA.GENOA_SP5(CHIPS)':
 'G3_RXP1||SATA21_RXP': CDS_PINID='\g3_rxp1||sata21_rxp\';
NET_NAME
'GMI_CPU0_G1_CPU1_G3_TX_DP<15>'
 '@T6G_MB_LIB.T6G(SCH_1):GMI_CPU0_G1_CPU1_G3_TX_DP'<15>:
 C_SIGNAL='@t6g_mb_lib.t6g(sch_1):gmi_cpu0_g1_cpu1_g3_tx_dp(15)';
NODE_NAME     U25 AL52
 '@T6G_MB_LIB.T6G(SCH_1):PAGE22_I208@PURE_QUANTA.GENOA_SP5(CHIPS)':
 'G1_TXP15': CDS_PINID='G1_TXP15';
NODE_NAME     U26 AL24
 '@T6G_MB_LIB.T6G(SCH_1):PAGE50_I144@PURE_QUANTA.GENOA_SP5(CHIPS)':
 'G3_RXP0||SATA20_RXP': CDS_PINID='\g3_rxp0||sata20_rxp\';
NET_NAME
'GMI_CPU0_G1_CPU1_G3_TX_DP<1>'
 '@T6G_MB_LIB.T6G(SCH_1):GMI_CPU0_G1_CPU1_G3_TX_DP'<1>:
 C_SIGNAL='@t6g_mb_lib.t6g(sch_1):gmi_cpu0_g1_cpu1_g3_tx_dp(1)';
NODE_NAME     U25 AM40
 '@T6G_MB_LIB.T6G(SCH_1):PAGE22_I208@PURE_QUANTA.GENOA_SP5(CHIPS)':
 'G1_TXP1': CDS_PINID='G1_TXP1';
NODE_NAME     U26 AM36
 '@T6G_MB_LIB.T6G(SCH_1):PAGE50_I144@PURE_QUANTA.GENOA_SP5(CHIPS)':
 'G3_RXP14||SATA36_RXP': CDS_PINID='\g3_rxp14||sata36_rxp\';
NET_NAME
'GMI_CPU0_G1_CPU1_G3_TX_DP<2>'
 '@T6G_MB_LIB.T6G(SCH_1):GMI_CPU0_G1_CPU1_G3_TX_DP'<2>:
 C_SIGNAL='@t6g_mb_lib.t6g(sch_1):gmi_cpu0_g1_cpu1_g3_tx_dp(2)';
NODE_NAME     U25 AH40
 '@T6G_MB_LIB.T6G(SCH_1):PAGE22_I208@PURE_QUANTA.GENOA_SP5(CHIPS)':
 'G1_TXP2': CDS_PINID='G1_TXP2';
NODE_NAME     U26 AH36
 '@T6G_MB_LIB.T6G(SCH_1):PAGE50_I144@PURE_QUANTA.GENOA_SP5(CHIPS)':
 'G3_RXP13||SATA35_RXP': CDS_PINID='\g3_rxp13||sata35_rxp\';
NET_NAME
'GMI_CPU0_G1_CPU1_G3_TX_DP<3>'
 '@T6G_MB_LIB.T6G(SCH_1):GMI_CPU0_G1_CPU1_G3_TX_DP'<3>:
 C_SIGNAL='@t6g_mb_lib.t6g(sch_1):gmi_cpu0_g1_cpu1_g3_tx_dp(3)';
NODE_NAME     U25 AK40
 '@T6G_MB_LIB.T6G(SCH_1):PAGE22_I208@PURE_QUANTA.GENOA_SP5(CHIPS)':
 'G1_TXP3': CDS_PINID='G1_TXP3';
NODE_NAME     U26 AK36
 '@T6G_MB_LIB.T6G(SCH_1):PAGE50_I144@PURE_QUANTA.GENOA_SP5(CHIPS)':
 'G3_RXP12||SATA34_RXP': CDS_PINID='\g3_rxp12||sata34_rxp\';
NET_NAME
'GMI_CPU0_G1_CPU1_G3_TX_DP<4>'
 '@T6G_MB_LIB.T6G(SCH_1):GMI_CPU0_G1_CPU1_G3_TX_DP'<4>:
 C_SIGNAL='@t6g_mb_lib.t6g(sch_1):gmi_cpu0_g1_cpu1_g3_tx_dp(4)';
NODE_NAME     U25 AN43
 '@T6G_MB_LIB.T6G(SCH_1):PAGE22_I208@PURE_QUANTA.GENOA_SP5(CHIPS)':
 'G1_TXP4': CDS_PINID='G1_TXP4';
NODE_NAME     U26 AN33
 '@T6G_MB_LIB.T6G(SCH_1):PAGE50_I144@PURE_QUANTA.GENOA_SP5(CHIPS)':
 'G3_RXP11||SATA33_RXP': CDS_PINID='\g3_rxp11||sata33_rxp\';
NET_NAME
'GMI_CPU0_G1_CPU1_G3_TX_DP<5>'
 '@T6G_MB_LIB.T6G(SCH_1):GMI_CPU0_G1_CPU1_G3_TX_DP'<5>:
 C_SIGNAL='@t6g_mb_lib.t6g(sch_1):gmi_cpu0_g1_cpu1_g3_tx_dp(5)';
NODE_NAME     U25 AJ43
 '@T6G_MB_LIB.T6G(SCH_1):PAGE22_I208@PURE_QUANTA.GENOA_SP5(CHIPS)':
 'G1_TXP5': CDS_PINID='G1_TXP5';
NODE_NAME     U26 AJ33
 '@T6G_MB_LIB.T6G(SCH_1):PAGE50_I144@PURE_QUANTA.GENOA_SP5(CHIPS)':
 'G3_RXP10||SATA32_RXP': CDS_PINID='\g3_rxp10||sata32_rxp\';
NET_NAME
'GMI_CPU0_G1_CPU1_G3_TX_DP<6>'
 '@T6G_MB_LIB.T6G(SCH_1):GMI_CPU0_G1_CPU1_G3_TX_DP'<6>:
 C_SIGNAL='@t6g_mb_lib.t6g(sch_1):gmi_cpu0_g1_cpu1_g3_tx_dp(6)';
NODE_NAME     U25 AL43
 '@T6G_MB_LIB.T6G(SCH_1):PAGE22_I208@PURE_QUANTA.GENOA_SP5(CHIPS)':
 'G1_TXP6': CDS_PINID='G1_TXP6';
NODE_NAME     U26 AL33
 '@T6G_MB_LIB.T6G(SCH_1):PAGE50_I144@PURE_QUANTA.GENOA_SP5(CHIPS)':
 'G3_RXP9||SATA31_RXP': CDS_PINID='\g3_rxp9||sata31_rxp\';
NET_NAME
'GMI_CPU0_G1_CPU1_G3_TX_DP<7>'
 '@T6G_MB_LIB.T6G(SCH_1):GMI_CPU0_G1_CPU1_G3_TX_DP'<7>:
 C_SIGNAL='@t6g_mb_lib.t6g(sch_1):gmi_cpu0_g1_cpu1_g3_tx_dp(7)';
NODE_NAME     U25 AN46
 '@T6G_MB_LIB.T6G(SCH_1):PAGE22_I208@PURE_QUANTA.GENOA_SP5(CHIPS)':
 'G1_TXP7': CDS_PINID='G1_TXP7';
NODE_NAME     U26 AN30
 '@T6G_MB_LIB.T6G(SCH_1):PAGE50_I144@PURE_QUANTA.GENOA_SP5(CHIPS)':
 'G3_RXP8||SATA30_RXP': CDS_PINID='\g3_rxp8||sata30_rxp\';
NET_NAME
'GMI_CPU0_G1_CPU1_G3_TX_DP<8>'
 '@T6G_MB_LIB.T6G(SCH_1):GMI_CPU0_G1_CPU1_G3_TX_DP'<8>:
 C_SIGNAL='@t6g_mb_lib.t6g(sch_1):gmi_cpu0_g1_cpu1_g3_tx_dp(8)';
NODE_NAME     U25 AJ46
 '@T6G_MB_LIB.T6G(SCH_1):PAGE22_I208@PURE_QUANTA.GENOA_SP5(CHIPS)':
 'G1_TXP8': CDS_PINID='G1_TXP8';
NODE_NAME     U26 AJ30
 '@T6G_MB_LIB.T6G(SCH_1):PAGE50_I144@PURE_QUANTA.GENOA_SP5(CHIPS)':
 'G3_RXP7||SATA27_RXP': CDS_PINID='\g3_rxp7||sata27_rxp\';
NET_NAME
'GMI_CPU0_G1_CPU1_G3_TX_DP<9>'
 '@T6G_MB_LIB.T6G(SCH_1):GMI_CPU0_G1_CPU1_G3_TX_DP'<9>:
 C_SIGNAL='@t6g_mb_lib.t6g(sch_1):gmi_cpu0_g1_cpu1_g3_tx_dp(9)';
NODE_NAME     U25 AL46
 '@T6G_MB_LIB.T6G(SCH_1):PAGE22_I208@PURE_QUANTA.GENOA_SP5(CHIPS)':
 'G1_TXP9': CDS_PINID='G1_TXP9';
NODE_NAME     U26 AL30
 '@T6G_MB_LIB.T6G(SCH_1):PAGE50_I144@PURE_QUANTA.GENOA_SP5(CHIPS)':
 'G3_RXP6||SATA26_RXP': CDS_PINID='\g3_rxp6||sata26_rxp\';
NET_NAME
'GMI_CPU0_G2_CPU1_G0_TX_DN<0>'
 '@T6G_MB_LIB.T6G(SCH_1):GMI_CPU0_G2_CPU1_G0_TX_DN'<0>:
 C_SIGNAL='@t6g_mb_lib.t6g(sch_1):gmi_cpu0_g2_cpu1_g0_tx_dn(0)';
NODE_NAME     U25 N24
 '@T6G_MB_LIB.T6G(SCH_1):PAGE23_I215@PURE_QUANTA.GENOA_SP5(CHIPS)':
 'G2_TXN0': CDS_PINID='G2_TXN0';
NODE_NAME     U26 N52
 '@T6G_MB_LIB.T6G(SCH_1):PAGE49_I213@PURE_QUANTA.GENOA_SP5(CHIPS)':
 'G0_RXN15': CDS_PINID='G0_RXN15';
NET_NAME
'GMI_CPU0_G2_CPU1_G0_TX_DN<10>'
 '@T6G_MB_LIB.T6G(SCH_1):GMI_CPU0_G2_CPU1_G0_TX_DN'<10>:
 C_SIGNAL='@t6g_mb_lib.t6g(sch_1):gmi_cpu0_g2_cpu1_g0_tx_dn(10)';
NODE_NAME     U25 J33
 '@T6G_MB_LIB.T6G(SCH_1):PAGE23_I215@PURE_QUANTA.GENOA_SP5(CHIPS)':
 'G2_TXN10': CDS_PINID='G2_TXN10';
NODE_NAME     U26 J43
 '@T6G_MB_LIB.T6G(SCH_1):PAGE49_I213@PURE_QUANTA.GENOA_SP5(CHIPS)':
 'G0_RXN5': CDS_PINID='G0_RXN5';
NET_NAME
'GMI_CPU0_G2_CPU1_G0_TX_DN<11>'
 '@T6G_MB_LIB.T6G(SCH_1):GMI_CPU0_G2_CPU1_G0_TX_DN'<11>:
 C_SIGNAL='@t6g_mb_lib.t6g(sch_1):gmi_cpu0_g2_cpu1_g0_tx_dn(11)';
NODE_NAME     U25 G33
 '@T6G_MB_LIB.T6G(SCH_1):PAGE23_I215@PURE_QUANTA.GENOA_SP5(CHIPS)':
 'G2_TXN11': CDS_PINID='G2_TXN11';
NODE_NAME     U26 G43
 '@T6G_MB_LIB.T6G(SCH_1):PAGE49_I213@PURE_QUANTA.GENOA_SP5(CHIPS)':
 'G0_RXN4': CDS_PINID='G0_RXN4';
NET_NAME
'GMI_CPU0_G2_CPU1_G0_TX_DN<12>'
 '@T6G_MB_LIB.T6G(SCH_1):GMI_CPU0_G2_CPU1_G0_TX_DN'<12>:
 C_SIGNAL='@t6g_mb_lib.t6g(sch_1):gmi_cpu0_g2_cpu1_g0_tx_dn(12)';
NODE_NAME     U25 L33
 '@T6G_MB_LIB.T6G(SCH_1):PAGE23_I215@PURE_QUANTA.GENOA_SP5(CHIPS)':
 'G2_TXN12': CDS_PINID='G2_TXN12';
NODE_NAME     U26 L43
 '@T6G_MB_LIB.T6G(SCH_1):PAGE49_I213@PURE_QUANTA.GENOA_SP5(CHIPS)':
 'G0_RXN3': CDS_PINID='G0_RXN3';
NET_NAME
'GMI_CPU0_G2_CPU1_G0_TX_DN<13>'
 '@T6G_MB_LIB.T6G(SCH_1):GMI_CPU0_G2_CPU1_G0_TX_DN'<13>:
 C_SIGNAL='@t6g_mb_lib.t6g(sch_1):gmi_cpu0_g2_cpu1_g0_tx_dn(13)';
NODE_NAME     U25 H36
 '@T6G_MB_LIB.T6G(SCH_1):PAGE23_I215@PURE_QUANTA.GENOA_SP5(CHIPS)':
 'G2_TXN13': CDS_PINID='G2_TXN13';
NODE_NAME     U26 H40
 '@T6G_MB_LIB.T6G(SCH_1):PAGE49_I213@PURE_QUANTA.GENOA_SP5(CHIPS)':
 'G0_RXN2': CDS_PINID='G0_RXN2';
NET_NAME
'GMI_CPU0_G2_CPU1_G0_TX_DN<14>'
 '@T6G_MB_LIB.T6G(SCH_1):GMI_CPU0_G2_CPU1_G0_TX_DN'<14>:
 C_SIGNAL='@t6g_mb_lib.t6g(sch_1):gmi_cpu0_g2_cpu1_g0_tx_dn(14)';
NODE_NAME     U25 K36
 '@T6G_MB_LIB.T6G(SCH_1):PAGE23_I215@PURE_QUANTA.GENOA_SP5(CHIPS)':
 'G2_TXN14': CDS_PINID='G2_TXN14';
NODE_NAME     U26 K40
 '@T6G_MB_LIB.T6G(SCH_1):PAGE49_I213@PURE_QUANTA.GENOA_SP5(CHIPS)':
 'G0_RXN1': CDS_PINID='G0_RXN1';
NET_NAME
'GMI_CPU0_G2_CPU1_G0_TX_DN<15>'
 '@T6G_MB_LIB.T6G(SCH_1):GMI_CPU0_G2_CPU1_G0_TX_DN'<15>:
 C_SIGNAL='@t6g_mb_lib.t6g(sch_1):gmi_cpu0_g2_cpu1_g0_tx_dn(15)';
NODE_NAME     U25 M36
 '@T6G_MB_LIB.T6G(SCH_1):PAGE23_I215@PURE_QUANTA.GENOA_SP5(CHIPS)':
 'G2_TXN15': CDS_PINID='G2_TXN15';
NODE_NAME     U26 M40
 '@T6G_MB_LIB.T6G(SCH_1):PAGE49_I213@PURE_QUANTA.GENOA_SP5(CHIPS)':
 'G0_RXN0': CDS_PINID='G0_RXN0';
NET_NAME
'GMI_CPU0_G2_CPU1_G0_TX_DN<1>'
 '@T6G_MB_LIB.T6G(SCH_1):GMI_CPU0_G2_CPU1_G0_TX_DN'<1>:
 C_SIGNAL='@t6g_mb_lib.t6g(sch_1):gmi_cpu0_g2_cpu1_g0_tx_dn(1)';
NODE_NAME     U25 J24
 '@T6G_MB_LIB.T6G(SCH_1):PAGE23_I215@PURE_QUANTA.GENOA_SP5(CHIPS)':
 'G2_TXN1': CDS_PINID='G2_TXN1';
NODE_NAME     U26 J52
 '@T6G_MB_LIB.T6G(SCH_1):PAGE49_I213@PURE_QUANTA.GENOA_SP5(CHIPS)':
 'G0_RXN14': CDS_PINID='G0_RXN14';
NET_NAME
'GMI_CPU0_G2_CPU1_G0_TX_DN<2>'
 '@T6G_MB_LIB.T6G(SCH_1):GMI_CPU0_G2_CPU1_G0_TX_DN'<2>:
 C_SIGNAL='@t6g_mb_lib.t6g(sch_1):gmi_cpu0_g2_cpu1_g0_tx_dn(2)';
NODE_NAME     U25 G24
 '@T6G_MB_LIB.T6G(SCH_1):PAGE23_I215@PURE_QUANTA.GENOA_SP5(CHIPS)':
 'G2_TXN2': CDS_PINID='G2_TXN2';
NODE_NAME     U26 G52
 '@T6G_MB_LIB.T6G(SCH_1):PAGE49_I213@PURE_QUANTA.GENOA_SP5(CHIPS)':
 'G0_RXN13': CDS_PINID='G0_RXN13';
NET_NAME
'GMI_CPU0_G2_CPU1_G0_TX_DN<3>'
 '@T6G_MB_LIB.T6G(SCH_1):GMI_CPU0_G2_CPU1_G0_TX_DN'<3>:
 C_SIGNAL='@t6g_mb_lib.t6g(sch_1):gmi_cpu0_g2_cpu1_g0_tx_dn(3)';
NODE_NAME     U25 L24
 '@T6G_MB_LIB.T6G(SCH_1):PAGE23_I215@PURE_QUANTA.GENOA_SP5(CHIPS)':
 'G2_TXN3': CDS_PINID='G2_TXN3';
NODE_NAME     U26 L52
 '@T6G_MB_LIB.T6G(SCH_1):PAGE49_I213@PURE_QUANTA.GENOA_SP5(CHIPS)':
 'G0_RXN12': CDS_PINID='G0_RXN12';
NET_NAME
'GMI_CPU0_G2_CPU1_G0_TX_DN<4>'
 '@T6G_MB_LIB.T6G(SCH_1):GMI_CPU0_G2_CPU1_G0_TX_DN'<4>:
 C_SIGNAL='@t6g_mb_lib.t6g(sch_1):gmi_cpu0_g2_cpu1_g0_tx_dn(4)';
NODE_NAME     U25 J27
 '@T6G_MB_LIB.T6G(SCH_1):PAGE23_I215@PURE_QUANTA.GENOA_SP5(CHIPS)':
 'G2_TXN4': CDS_PINID='G2_TXN4';
NODE_NAME     U26 J49
 '@T6G_MB_LIB.T6G(SCH_1):PAGE49_I213@PURE_QUANTA.GENOA_SP5(CHIPS)':
 'G0_RXN11': CDS_PINID='G0_RXN11';
NET_NAME
'GMI_CPU0_G2_CPU1_G0_TX_DN<5>'
 '@T6G_MB_LIB.T6G(SCH_1):GMI_CPU0_G2_CPU1_G0_TX_DN'<5>:
 C_SIGNAL='@t6g_mb_lib.t6g(sch_1):gmi_cpu0_g2_cpu1_g0_tx_dn(5)';
NODE_NAME     U25 G27
 '@T6G_MB_LIB.T6G(SCH_1):PAGE23_I215@PURE_QUANTA.GENOA_SP5(CHIPS)':
 'G2_TXN5': CDS_PINID='G2_TXN5';
NODE_NAME     U26 G49
 '@T6G_MB_LIB.T6G(SCH_1):PAGE49_I213@PURE_QUANTA.GENOA_SP5(CHIPS)':
 'G0_RXN10': CDS_PINID='G0_RXN10';
NET_NAME
'GMI_CPU0_G2_CPU1_G0_TX_DN<6>'
 '@T6G_MB_LIB.T6G(SCH_1):GMI_CPU0_G2_CPU1_G0_TX_DN'<6>:
 C_SIGNAL='@t6g_mb_lib.t6g(sch_1):gmi_cpu0_g2_cpu1_g0_tx_dn(6)';
NODE_NAME     U25 L27
 '@T6G_MB_LIB.T6G(SCH_1):PAGE23_I215@PURE_QUANTA.GENOA_SP5(CHIPS)':
 'G2_TXN6': CDS_PINID='G2_TXN6';
NODE_NAME     U26 L49
 '@T6G_MB_LIB.T6G(SCH_1):PAGE49_I213@PURE_QUANTA.GENOA_SP5(CHIPS)':
 'G0_RXN9': CDS_PINID='G0_RXN9';
NET_NAME
'GMI_CPU0_G2_CPU1_G0_TX_DN<7>'
 '@T6G_MB_LIB.T6G(SCH_1):GMI_CPU0_G2_CPU1_G0_TX_DN'<7>:
 C_SIGNAL='@t6g_mb_lib.t6g(sch_1):gmi_cpu0_g2_cpu1_g0_tx_dn(7)';
NODE_NAME     U25 J30
 '@T6G_MB_LIB.T6G(SCH_1):PAGE23_I215@PURE_QUANTA.GENOA_SP5(CHIPS)':
 'G2_TXN7': CDS_PINID='G2_TXN7';
NODE_NAME     U26 J46
 '@T6G_MB_LIB.T6G(SCH_1):PAGE49_I213@PURE_QUANTA.GENOA_SP5(CHIPS)':
 'G0_RXN8': CDS_PINID='G0_RXN8';
NET_NAME
'GMI_CPU0_G2_CPU1_G0_TX_DN<8>'
 '@T6G_MB_LIB.T6G(SCH_1):GMI_CPU0_G2_CPU1_G0_TX_DN'<8>:
 C_SIGNAL='@t6g_mb_lib.t6g(sch_1):gmi_cpu0_g2_cpu1_g0_tx_dn(8)';
NODE_NAME     U25 G30
 '@T6G_MB_LIB.T6G(SCH_1):PAGE23_I215@PURE_QUANTA.GENOA_SP5(CHIPS)':
 'G2_TXN8': CDS_PINID='G2_TXN8';
NODE_NAME     U26 G46
 '@T6G_MB_LIB.T6G(SCH_1):PAGE49_I213@PURE_QUANTA.GENOA_SP5(CHIPS)':
 'G0_RXN7': CDS_PINID='G0_RXN7';
NET_NAME
'GMI_CPU0_G2_CPU1_G0_TX_DN<9>'
 '@T6G_MB_LIB.T6G(SCH_1):GMI_CPU0_G2_CPU1_G0_TX_DN'<9>:
 C_SIGNAL='@t6g_mb_lib.t6g(sch_1):gmi_cpu0_g2_cpu1_g0_tx_dn(9)';
NODE_NAME     U25 L30
 '@T6G_MB_LIB.T6G(SCH_1):PAGE23_I215@PURE_QUANTA.GENOA_SP5(CHIPS)':
 'G2_TXN9': CDS_PINID='G2_TXN9';
NODE_NAME     U26 L46
 '@T6G_MB_LIB.T6G(SCH_1):PAGE49_I213@PURE_QUANTA.GENOA_SP5(CHIPS)':
 'G0_RXN6': CDS_PINID='G0_RXN6';
NET_NAME
'GMI_CPU0_G2_CPU1_G0_TX_DP<0>'
 '@T6G_MB_LIB.T6G(SCH_1):GMI_CPU0_G2_CPU1_G0_TX_DP'<0>:
 C_SIGNAL='@t6g_mb_lib.t6g(sch_1):gmi_cpu0_g2_cpu1_g0_tx_dp(0)';
NODE_NAME     U25 N23
 '@T6G_MB_LIB.T6G(SCH_1):PAGE23_I215@PURE_QUANTA.GENOA_SP5(CHIPS)':
 'G2_TXP0': CDS_PINID='G2_TXP0';
NODE_NAME     U26 N53
 '@T6G_MB_LIB.T6G(SCH_1):PAGE49_I213@PURE_QUANTA.GENOA_SP5(CHIPS)':
 'G0_RXP15': CDS_PINID='G0_RXP15';
NET_NAME
'GMI_CPU0_G2_CPU1_G0_TX_DP<10>'
 '@T6G_MB_LIB.T6G(SCH_1):GMI_CPU0_G2_CPU1_G0_TX_DP'<10>:
 C_SIGNAL='@t6g_mb_lib.t6g(sch_1):gmi_cpu0_g2_cpu1_g0_tx_dp(10)';
NODE_NAME     U25 J32
 '@T6G_MB_LIB.T6G(SCH_1):PAGE23_I215@PURE_QUANTA.GENOA_SP5(CHIPS)':
 'G2_TXP10': CDS_PINID='G2_TXP10';
NODE_NAME     U26 J44
 '@T6G_MB_LIB.T6G(SCH_1):PAGE49_I213@PURE_QUANTA.GENOA_SP5(CHIPS)':
 'G0_RXP5': CDS_PINID='G0_RXP5';
NET_NAME
'GMI_CPU0_G2_CPU1_G0_TX_DP<11>'
 '@T6G_MB_LIB.T6G(SCH_1):GMI_CPU0_G2_CPU1_G0_TX_DP'<11>:
 C_SIGNAL='@t6g_mb_lib.t6g(sch_1):gmi_cpu0_g2_cpu1_g0_tx_dp(11)';
NODE_NAME     U25 G32
 '@T6G_MB_LIB.T6G(SCH_1):PAGE23_I215@PURE_QUANTA.GENOA_SP5(CHIPS)':
 'G2_TXP11': CDS_PINID='G2_TXP11';
NODE_NAME     U26 G44
 '@T6G_MB_LIB.T6G(SCH_1):PAGE49_I213@PURE_QUANTA.GENOA_SP5(CHIPS)':
 'G0_RXP4': CDS_PINID='G0_RXP4';
NET_NAME
'GMI_CPU0_G2_CPU1_G0_TX_DP<12>'
 '@T6G_MB_LIB.T6G(SCH_1):GMI_CPU0_G2_CPU1_G0_TX_DP'<12>:
 C_SIGNAL='@t6g_mb_lib.t6g(sch_1):gmi_cpu0_g2_cpu1_g0_tx_dp(12)';
NODE_NAME     U25 L32
 '@T6G_MB_LIB.T6G(SCH_1):PAGE23_I215@PURE_QUANTA.GENOA_SP5(CHIPS)':
 'G2_TXP12': CDS_PINID='G2_TXP12';
NODE_NAME     U26 L44
 '@T6G_MB_LIB.T6G(SCH_1):PAGE49_I213@PURE_QUANTA.GENOA_SP5(CHIPS)':
 'G0_RXP3': CDS_PINID='G0_RXP3';
NET_NAME
'GMI_CPU0_G2_CPU1_G0_TX_DP<13>'
 '@T6G_MB_LIB.T6G(SCH_1):GMI_CPU0_G2_CPU1_G0_TX_DP'<13>:
 C_SIGNAL='@t6g_mb_lib.t6g(sch_1):gmi_cpu0_g2_cpu1_g0_tx_dp(13)';
NODE_NAME     U25 H35
 '@T6G_MB_LIB.T6G(SCH_1):PAGE23_I215@PURE_QUANTA.GENOA_SP5(CHIPS)':
 'G2_TXP13': CDS_PINID='G2_TXP13';
NODE_NAME     U26 H41
 '@T6G_MB_LIB.T6G(SCH_1):PAGE49_I213@PURE_QUANTA.GENOA_SP5(CHIPS)':
 'G0_RXP2': CDS_PINID='G0_RXP2';
NET_NAME
'GMI_CPU0_G2_CPU1_G0_TX_DP<14>'
 '@T6G_MB_LIB.T6G(SCH_1):GMI_CPU0_G2_CPU1_G0_TX_DP'<14>:
 C_SIGNAL='@t6g_mb_lib.t6g(sch_1):gmi_cpu0_g2_cpu1_g0_tx_dp(14)';
NODE_NAME     U25 K35
 '@T6G_MB_LIB.T6G(SCH_1):PAGE23_I215@PURE_QUANTA.GENOA_SP5(CHIPS)':
 'G2_TXP14': CDS_PINID='G2_TXP14';
NODE_NAME     U26 K41
 '@T6G_MB_LIB.T6G(SCH_1):PAGE49_I213@PURE_QUANTA.GENOA_SP5(CHIPS)':
 'G0_RXP1': CDS_PINID='G0_RXP1';
NET_NAME
'GMI_CPU0_G2_CPU1_G0_TX_DP<15>'
 '@T6G_MB_LIB.T6G(SCH_1):GMI_CPU0_G2_CPU1_G0_TX_DP'<15>:
 C_SIGNAL='@t6g_mb_lib.t6g(sch_1):gmi_cpu0_g2_cpu1_g0_tx_dp(15)';
NODE_NAME     U25 M35
 '@T6G_MB_LIB.T6G(SCH_1):PAGE23_I215@PURE_QUANTA.GENOA_SP5(CHIPS)':
 'G2_TXP15': CDS_PINID='G2_TXP15';
NODE_NAME     U26 M41
 '@T6G_MB_LIB.T6G(SCH_1):PAGE49_I213@PURE_QUANTA.GENOA_SP5(CHIPS)':
 'G0_RXP0': CDS_PINID='G0_RXP0';
NET_NAME
'GMI_CPU0_G2_CPU1_G0_TX_DP<1>'
 '@T6G_MB_LIB.T6G(SCH_1):GMI_CPU0_G2_CPU1_G0_TX_DP'<1>:
 C_SIGNAL='@t6g_mb_lib.t6g(sch_1):gmi_cpu0_g2_cpu1_g0_tx_dp(1)';
NODE_NAME     U25 J23
 '@T6G_MB_LIB.T6G(SCH_1):PAGE23_I215@PURE_QUANTA.GENOA_SP5(CHIPS)':
 'G2_TXP1': CDS_PINID='G2_TXP1';
NODE_NAME     U26 J53
 '@T6G_MB_LIB.T6G(SCH_1):PAGE49_I213@PURE_QUANTA.GENOA_SP5(CHIPS)':
 'G0_RXP14': CDS_PINID='G0_RXP14';
NET_NAME
'GMI_CPU0_G2_CPU1_G0_TX_DP<2>'
 '@T6G_MB_LIB.T6G(SCH_1):GMI_CPU0_G2_CPU1_G0_TX_DP'<2>:
 C_SIGNAL='@t6g_mb_lib.t6g(sch_1):gmi_cpu0_g2_cpu1_g0_tx_dp(2)';
NODE_NAME     U25 G23
 '@T6G_MB_LIB.T6G(SCH_1):PAGE23_I215@PURE_QUANTA.GENOA_SP5(CHIPS)':
 'G2_TXP2': CDS_PINID='G2_TXP2';
NODE_NAME     U26 G53
 '@T6G_MB_LIB.T6G(SCH_1):PAGE49_I213@PURE_QUANTA.GENOA_SP5(CHIPS)':
 'G0_RXP13': CDS_PINID='G0_RXP13';
NET_NAME
'GMI_CPU0_G2_CPU1_G0_TX_DP<3>'
 '@T6G_MB_LIB.T6G(SCH_1):GMI_CPU0_G2_CPU1_G0_TX_DP'<3>:
 C_SIGNAL='@t6g_mb_lib.t6g(sch_1):gmi_cpu0_g2_cpu1_g0_tx_dp(3)';
NODE_NAME     U25 L23
 '@T6G_MB_LIB.T6G(SCH_1):PAGE23_I215@PURE_QUANTA.GENOA_SP5(CHIPS)':
 'G2_TXP3': CDS_PINID='G2_TXP3';
NODE_NAME     U26 L53
 '@T6G_MB_LIB.T6G(SCH_1):PAGE49_I213@PURE_QUANTA.GENOA_SP5(CHIPS)':
 'G0_RXP12': CDS_PINID='G0_RXP12';
NET_NAME
'GMI_CPU0_G2_CPU1_G0_TX_DP<4>'
 '@T6G_MB_LIB.T6G(SCH_1):GMI_CPU0_G2_CPU1_G0_TX_DP'<4>:
 C_SIGNAL='@t6g_mb_lib.t6g(sch_1):gmi_cpu0_g2_cpu1_g0_tx_dp(4)';
NODE_NAME     U25 J26
 '@T6G_MB_LIB.T6G(SCH_1):PAGE23_I215@PURE_QUANTA.GENOA_SP5(CHIPS)':
 'G2_TXP4': CDS_PINID='G2_TXP4';
NODE_NAME     U26 J50
 '@T6G_MB_LIB.T6G(SCH_1):PAGE49_I213@PURE_QUANTA.GENOA_SP5(CHIPS)':
 'G0_RXP11': CDS_PINID='G0_RXP11';
NET_NAME
'GMI_CPU0_G2_CPU1_G0_TX_DP<5>'
 '@T6G_MB_LIB.T6G(SCH_1):GMI_CPU0_G2_CPU1_G0_TX_DP'<5>:
 C_SIGNAL='@t6g_mb_lib.t6g(sch_1):gmi_cpu0_g2_cpu1_g0_tx_dp(5)';
NODE_NAME     U25 G26
 '@T6G_MB_LIB.T6G(SCH_1):PAGE23_I215@PURE_QUANTA.GENOA_SP5(CHIPS)':
 'G2_TXP5': CDS_PINID='G2_TXP5';
NODE_NAME     U26 G50
 '@T6G_MB_LIB.T6G(SCH_1):PAGE49_I213@PURE_QUANTA.GENOA_SP5(CHIPS)':
 'G0_RXP10': CDS_PINID='G0_RXP10';
NET_NAME
'GMI_CPU0_G2_CPU1_G0_TX_DP<6>'
 '@T6G_MB_LIB.T6G(SCH_1):GMI_CPU0_G2_CPU1_G0_TX_DP'<6>:
 C_SIGNAL='@t6g_mb_lib.t6g(sch_1):gmi_cpu0_g2_cpu1_g0_tx_dp(6)';
NODE_NAME     U25 L26
 '@T6G_MB_LIB.T6G(SCH_1):PAGE23_I215@PURE_QUANTA.GENOA_SP5(CHIPS)':
 'G2_TXP6': CDS_PINID='G2_TXP6';
NODE_NAME     U26 L50
 '@T6G_MB_LIB.T6G(SCH_1):PAGE49_I213@PURE_QUANTA.GENOA_SP5(CHIPS)':
 'G0_RXP9': CDS_PINID='G0_RXP9';
NET_NAME
'GMI_CPU0_G2_CPU1_G0_TX_DP<7>'
 '@T6G_MB_LIB.T6G(SCH_1):GMI_CPU0_G2_CPU1_G0_TX_DP'<7>:
 C_SIGNAL='@t6g_mb_lib.t6g(sch_1):gmi_cpu0_g2_cpu1_g0_tx_dp(7)';
NODE_NAME     U25 J29
 '@T6G_MB_LIB.T6G(SCH_1):PAGE23_I215@PURE_QUANTA.GENOA_SP5(CHIPS)':
 'G2_TXP7': CDS_PINID='G2_TXP7';
NODE_NAME     U26 J47
 '@T6G_MB_LIB.T6G(SCH_1):PAGE49_I213@PURE_QUANTA.GENOA_SP5(CHIPS)':
 'G0_RXP8': CDS_PINID='G0_RXP8';
NET_NAME
'GMI_CPU0_G2_CPU1_G0_TX_DP<8>'
 '@T6G_MB_LIB.T6G(SCH_1):GMI_CPU0_G2_CPU1_G0_TX_DP'<8>:
 C_SIGNAL='@t6g_mb_lib.t6g(sch_1):gmi_cpu0_g2_cpu1_g0_tx_dp(8)';
NODE_NAME     U25 G29
 '@T6G_MB_LIB.T6G(SCH_1):PAGE23_I215@PURE_QUANTA.GENOA_SP5(CHIPS)':
 'G2_TXP8': CDS_PINID='G2_TXP8';
NODE_NAME     U26 G47
 '@T6G_MB_LIB.T6G(SCH_1):PAGE49_I213@PURE_QUANTA.GENOA_SP5(CHIPS)':
 'G0_RXP7': CDS_PINID='G0_RXP7';
NET_NAME
'GMI_CPU0_G2_CPU1_G0_TX_DP<9>'
 '@T6G_MB_LIB.T6G(SCH_1):GMI_CPU0_G2_CPU1_G0_TX_DP'<9>:
 C_SIGNAL='@t6g_mb_lib.t6g(sch_1):gmi_cpu0_g2_cpu1_g0_tx_dp(9)';
NODE_NAME     U25 L29
 '@T6G_MB_LIB.T6G(SCH_1):PAGE23_I215@PURE_QUANTA.GENOA_SP5(CHIPS)':
 'G2_TXP9': CDS_PINID='G2_TXP9';
NODE_NAME     U26 L47
 '@T6G_MB_LIB.T6G(SCH_1):PAGE49_I213@PURE_QUANTA.GENOA_SP5(CHIPS)':
 'G0_RXP6': CDS_PINID='G0_RXP6';
NET_NAME
'GMI_CPU1_G0_CPU0_G2_TX_DN<0>'
 '@T6G_MB_LIB.T6G(SCH_1):GMI_CPU1_G0_CPU0_G2_TX_DN'<0>:
 C_SIGNAL='@t6g_mb_lib.t6g(sch_1):gmi_cpu1_g0_cpu0_g2_tx_dn(0)';
NODE_NAME     U25 AE23
 '@T6G_MB_LIB.T6G(SCH_1):PAGE23_I215@PURE_QUANTA.GENOA_SP5(CHIPS)':
 'G2_RXN0': CDS_PINID='G2_RXN0';
NODE_NAME     U26 AE53
 '@T6G_MB_LIB.T6G(SCH_1):PAGE49_I213@PURE_QUANTA.GENOA_SP5(CHIPS)':
 'G0_TXN15': CDS_PINID='G0_TXN15';
NET_NAME
'GMI_CPU1_G0_CPU0_G2_TX_DN<10>'
 '@T6G_MB_LIB.T6G(SCH_1):GMI_CPU1_G0_CPU0_G2_TX_DN'<10>:
 C_SIGNAL='@t6g_mb_lib.t6g(sch_1):gmi_cpu1_g0_cpu0_g2_tx_dn(10)';
NODE_NAME     U25 AC32
 '@T6G_MB_LIB.T6G(SCH_1):PAGE23_I215@PURE_QUANTA.GENOA_SP5(CHIPS)':
 'G2_RXN10': CDS_PINID='G2_RXN10';
NODE_NAME     U26 AC44
 '@T6G_MB_LIB.T6G(SCH_1):PAGE49_I213@PURE_QUANTA.GENOA_SP5(CHIPS)':
 'G0_TXN5': CDS_PINID='G0_TXN5';
NET_NAME
'GMI_CPU1_G0_CPU0_G2_TX_DN<11>'
 '@T6G_MB_LIB.T6G(SCH_1):GMI_CPU1_G0_CPU0_G2_TX_DN'<11>:
 C_SIGNAL='@t6g_mb_lib.t6g(sch_1):gmi_cpu1_g0_cpu0_g2_tx_dn(11)';
NODE_NAME     U25 AA32
 '@T6G_MB_LIB.T6G(SCH_1):PAGE23_I215@PURE_QUANTA.GENOA_SP5(CHIPS)':
 'G2_RXN11': CDS_PINID='G2_RXN11';
NODE_NAME     U26 AA44
 '@T6G_MB_LIB.T6G(SCH_1):PAGE49_I213@PURE_QUANTA.GENOA_SP5(CHIPS)':
 'G0_TXN4': CDS_PINID='G0_TXN4';
NET_NAME
'GMI_CPU1_G0_CPU0_G2_TX_DN<12>'
 '@T6G_MB_LIB.T6G(SCH_1):GMI_CPU1_G0_CPU0_G2_TX_DN'<12>:
 C_SIGNAL='@t6g_mb_lib.t6g(sch_1):gmi_cpu1_g0_cpu0_g2_tx_dn(12)';
NODE_NAME     U25 AG32
 '@T6G_MB_LIB.T6G(SCH_1):PAGE23_I215@PURE_QUANTA.GENOA_SP5(CHIPS)':
 'G2_RXN12': CDS_PINID='G2_RXN12';
NODE_NAME     U26 AG44
 '@T6G_MB_LIB.T6G(SCH_1):PAGE49_I213@PURE_QUANTA.GENOA_SP5(CHIPS)':
 'G0_TXN3': CDS_PINID='G0_TXN3';
NET_NAME
'GMI_CPU1_G0_CPU0_G2_TX_DN<13>'
 '@T6G_MB_LIB.T6G(SCH_1):GMI_CPU1_G0_CPU0_G2_TX_DN'<13>:
 C_SIGNAL='@t6g_mb_lib.t6g(sch_1):gmi_cpu1_g0_cpu0_g2_tx_dn(13)';
NODE_NAME     U25 AB35
 '@T6G_MB_LIB.T6G(SCH_1):PAGE23_I215@PURE_QUANTA.GENOA_SP5(CHIPS)':
 'G2_RXN13': CDS_PINID='G2_RXN13';
NODE_NAME     U26 AB41
 '@T6G_MB_LIB.T6G(SCH_1):PAGE49_I213@PURE_QUANTA.GENOA_SP5(CHIPS)':
 'G0_TXN2': CDS_PINID='G0_TXN2';
NET_NAME
'GMI_CPU1_G0_CPU0_G2_TX_DN<14>'
 '@T6G_MB_LIB.T6G(SCH_1):GMI_CPU1_G0_CPU0_G2_TX_DN'<14>:
 C_SIGNAL='@t6g_mb_lib.t6g(sch_1):gmi_cpu1_g0_cpu0_g2_tx_dn(14)';
NODE_NAME     U25 AD35
 '@T6G_MB_LIB.T6G(SCH_1):PAGE23_I215@PURE_QUANTA.GENOA_SP5(CHIPS)':
 'G2_RXN14': CDS_PINID='G2_RXN14';
NODE_NAME     U26 AD41
 '@T6G_MB_LIB.T6G(SCH_1):PAGE49_I213@PURE_QUANTA.GENOA_SP5(CHIPS)':
 'G0_TXN1': CDS_PINID='G0_TXN1';
NET_NAME
'GMI_CPU1_G0_CPU0_G2_TX_DN<15>'
 '@T6G_MB_LIB.T6G(SCH_1):GMI_CPU1_G0_CPU0_G2_TX_DN'<15>:
 C_SIGNAL='@t6g_mb_lib.t6g(sch_1):gmi_cpu1_g0_cpu0_g2_tx_dn(15)';
NODE_NAME     U25 AF35
 '@T6G_MB_LIB.T6G(SCH_1):PAGE23_I215@PURE_QUANTA.GENOA_SP5(CHIPS)':
 'G2_RXN15': CDS_PINID='G2_RXN15';
NODE_NAME     U26 AF41
 '@T6G_MB_LIB.T6G(SCH_1):PAGE49_I213@PURE_QUANTA.GENOA_SP5(CHIPS)':
 'G0_TXN0': CDS_PINID='G0_TXN0';
NET_NAME
'GMI_CPU1_G0_CPU0_G2_TX_DN<1>'
 '@T6G_MB_LIB.T6G(SCH_1):GMI_CPU1_G0_CPU0_G2_TX_DN'<1>:
 C_SIGNAL='@t6g_mb_lib.t6g(sch_1):gmi_cpu1_g0_cpu0_g2_tx_dn(1)';
NODE_NAME     U25 AC23
 '@T6G_MB_LIB.T6G(SCH_1):PAGE23_I215@PURE_QUANTA.GENOA_SP5(CHIPS)':
 'G2_RXN1': CDS_PINID='G2_RXN1';
NODE_NAME     U26 AC53
 '@T6G_MB_LIB.T6G(SCH_1):PAGE49_I213@PURE_QUANTA.GENOA_SP5(CHIPS)':
 'G0_TXN14': CDS_PINID='G0_TXN14';
NET_NAME
'GMI_CPU1_G0_CPU0_G2_TX_DN<2>'
 '@T6G_MB_LIB.T6G(SCH_1):GMI_CPU1_G0_CPU0_G2_TX_DN'<2>:
 C_SIGNAL='@t6g_mb_lib.t6g(sch_1):gmi_cpu1_g0_cpu0_g2_tx_dn(2)';
NODE_NAME     U25 AG23
 '@T6G_MB_LIB.T6G(SCH_1):PAGE23_I215@PURE_QUANTA.GENOA_SP5(CHIPS)':
 'G2_RXN2': CDS_PINID='G2_RXN2';
NODE_NAME     U26 AG53
 '@T6G_MB_LIB.T6G(SCH_1):PAGE49_I213@PURE_QUANTA.GENOA_SP5(CHIPS)':
 'G0_TXN13': CDS_PINID='G0_TXN13';
NET_NAME
'GMI_CPU1_G0_CPU0_G2_TX_DN<3>'
 '@T6G_MB_LIB.T6G(SCH_1):GMI_CPU1_G0_CPU0_G2_TX_DN'<3>:
 C_SIGNAL='@t6g_mb_lib.t6g(sch_1):gmi_cpu1_g0_cpu0_g2_tx_dn(3)';
NODE_NAME     U25 AE26
 '@T6G_MB_LIB.T6G(SCH_1):PAGE23_I215@PURE_QUANTA.GENOA_SP5(CHIPS)':
 'G2_RXN3': CDS_PINID='G2_RXN3';
NODE_NAME     U26 AE50
 '@T6G_MB_LIB.T6G(SCH_1):PAGE49_I213@PURE_QUANTA.GENOA_SP5(CHIPS)':
 'G0_TXN12': CDS_PINID='G0_TXN12';
NET_NAME
'GMI_CPU1_G0_CPU0_G2_TX_DN<4>'
 '@T6G_MB_LIB.T6G(SCH_1):GMI_CPU1_G0_CPU0_G2_TX_DN'<4>:
 C_SIGNAL='@t6g_mb_lib.t6g(sch_1):gmi_cpu1_g0_cpu0_g2_tx_dn(4)';
NODE_NAME     U25 AC26
 '@T6G_MB_LIB.T6G(SCH_1):PAGE23_I215@PURE_QUANTA.GENOA_SP5(CHIPS)':
 'G2_RXN4': CDS_PINID='G2_RXN4';
NODE_NAME     U26 AC50
 '@T6G_MB_LIB.T6G(SCH_1):PAGE49_I213@PURE_QUANTA.GENOA_SP5(CHIPS)':
 'G0_TXN11': CDS_PINID='G0_TXN11';
NET_NAME
'GMI_CPU1_G0_CPU0_G2_TX_DN<5>'
 '@T6G_MB_LIB.T6G(SCH_1):GMI_CPU1_G0_CPU0_G2_TX_DN'<5>:
 C_SIGNAL='@t6g_mb_lib.t6g(sch_1):gmi_cpu1_g0_cpu0_g2_tx_dn(5)';
NODE_NAME     U25 AG26
 '@T6G_MB_LIB.T6G(SCH_1):PAGE23_I215@PURE_QUANTA.GENOA_SP5(CHIPS)':
 'G2_RXN5': CDS_PINID='G2_RXN5';
NODE_NAME     U26 AG50
 '@T6G_MB_LIB.T6G(SCH_1):PAGE49_I213@PURE_QUANTA.GENOA_SP5(CHIPS)':
 'G0_TXN10': CDS_PINID='G0_TXN10';
NET_NAME
'GMI_CPU1_G0_CPU0_G2_TX_DN<6>'
 '@T6G_MB_LIB.T6G(SCH_1):GMI_CPU1_G0_CPU0_G2_TX_DN'<6>:
 C_SIGNAL='@t6g_mb_lib.t6g(sch_1):gmi_cpu1_g0_cpu0_g2_tx_dn(6)';
NODE_NAME     U25 AE29
 '@T6G_MB_LIB.T6G(SCH_1):PAGE23_I215@PURE_QUANTA.GENOA_SP5(CHIPS)':
 'G2_RXN6': CDS_PINID='G2_RXN6';
NODE_NAME     U26 AE47
 '@T6G_MB_LIB.T6G(SCH_1):PAGE49_I213@PURE_QUANTA.GENOA_SP5(CHIPS)':
 'G0_TXN9': CDS_PINID='G0_TXN9';
NET_NAME
'GMI_CPU1_G0_CPU0_G2_TX_DN<7>'
 '@T6G_MB_LIB.T6G(SCH_1):GMI_CPU1_G0_CPU0_G2_TX_DN'<7>:
 C_SIGNAL='@t6g_mb_lib.t6g(sch_1):gmi_cpu1_g0_cpu0_g2_tx_dn(7)';
NODE_NAME     U25 AC29
 '@T6G_MB_LIB.T6G(SCH_1):PAGE23_I215@PURE_QUANTA.GENOA_SP5(CHIPS)':
 'G2_RXN7': CDS_PINID='G2_RXN7';
NODE_NAME     U26 AC47
 '@T6G_MB_LIB.T6G(SCH_1):PAGE49_I213@PURE_QUANTA.GENOA_SP5(CHIPS)':
 'G0_TXN8': CDS_PINID='G0_TXN8';
NET_NAME
'GMI_CPU1_G0_CPU0_G2_TX_DN<8>'
 '@T6G_MB_LIB.T6G(SCH_1):GMI_CPU1_G0_CPU0_G2_TX_DN'<8>:
 C_SIGNAL='@t6g_mb_lib.t6g(sch_1):gmi_cpu1_g0_cpu0_g2_tx_dn(8)';
NODE_NAME     U25 AG29
 '@T6G_MB_LIB.T6G(SCH_1):PAGE23_I215@PURE_QUANTA.GENOA_SP5(CHIPS)':
 'G2_RXN8': CDS_PINID='G2_RXN8';
NODE_NAME     U26 AG47
 '@T6G_MB_LIB.T6G(SCH_1):PAGE49_I213@PURE_QUANTA.GENOA_SP5(CHIPS)':
 'G0_TXN7': CDS_PINID='G0_TXN7';
NET_NAME
'GMI_CPU1_G0_CPU0_G2_TX_DN<9>'
 '@T6G_MB_LIB.T6G(SCH_1):GMI_CPU1_G0_CPU0_G2_TX_DN'<9>:
 C_SIGNAL='@t6g_mb_lib.t6g(sch_1):gmi_cpu1_g0_cpu0_g2_tx_dn(9)';
NODE_NAME     U25 AE32
 '@T6G_MB_LIB.T6G(SCH_1):PAGE23_I215@PURE_QUANTA.GENOA_SP5(CHIPS)':
 'G2_RXN9': CDS_PINID='G2_RXN9';
NODE_NAME     U26 AE44
 '@T6G_MB_LIB.T6G(SCH_1):PAGE49_I213@PURE_QUANTA.GENOA_SP5(CHIPS)':
 'G0_TXN6': CDS_PINID='G0_TXN6';
NET_NAME
'GMI_CPU1_G0_CPU0_G2_TX_DP<0>'
 '@T6G_MB_LIB.T6G(SCH_1):GMI_CPU1_G0_CPU0_G2_TX_DP'<0>:
 C_SIGNAL='@t6g_mb_lib.t6g(sch_1):gmi_cpu1_g0_cpu0_g2_tx_dp(0)';
NODE_NAME     U25 AE24
 '@T6G_MB_LIB.T6G(SCH_1):PAGE23_I215@PURE_QUANTA.GENOA_SP5(CHIPS)':
 'G2_RXP0': CDS_PINID='G2_RXP0';
NODE_NAME     U26 AE52
 '@T6G_MB_LIB.T6G(SCH_1):PAGE49_I213@PURE_QUANTA.GENOA_SP5(CHIPS)':
 'G0_TXP15': CDS_PINID='G0_TXP15';
NET_NAME
'GMI_CPU1_G0_CPU0_G2_TX_DP<10>'
 '@T6G_MB_LIB.T6G(SCH_1):GMI_CPU1_G0_CPU0_G2_TX_DP'<10>:
 C_SIGNAL='@t6g_mb_lib.t6g(sch_1):gmi_cpu1_g0_cpu0_g2_tx_dp(10)';
NODE_NAME     U25 AC33
 '@T6G_MB_LIB.T6G(SCH_1):PAGE23_I215@PURE_QUANTA.GENOA_SP5(CHIPS)':
 'G2_RXP10': CDS_PINID='G2_RXP10';
NODE_NAME     U26 AC43
 '@T6G_MB_LIB.T6G(SCH_1):PAGE49_I213@PURE_QUANTA.GENOA_SP5(CHIPS)':
 'G0_TXP5': CDS_PINID='G0_TXP5';
NET_NAME
'GMI_CPU1_G0_CPU0_G2_TX_DP<11>'
 '@T6G_MB_LIB.T6G(SCH_1):GMI_CPU1_G0_CPU0_G2_TX_DP'<11>:
 C_SIGNAL='@t6g_mb_lib.t6g(sch_1):gmi_cpu1_g0_cpu0_g2_tx_dp(11)';
NODE_NAME     U25 AA33
 '@T6G_MB_LIB.T6G(SCH_1):PAGE23_I215@PURE_QUANTA.GENOA_SP5(CHIPS)':
 'G2_RXP11': CDS_PINID='G2_RXP11';
NODE_NAME     U26 AA43
 '@T6G_MB_LIB.T6G(SCH_1):PAGE49_I213@PURE_QUANTA.GENOA_SP5(CHIPS)':
 'G0_TXP4': CDS_PINID='G0_TXP4';
NET_NAME
'GMI_CPU1_G0_CPU0_G2_TX_DP<12>'
 '@T6G_MB_LIB.T6G(SCH_1):GMI_CPU1_G0_CPU0_G2_TX_DP'<12>:
 C_SIGNAL='@t6g_mb_lib.t6g(sch_1):gmi_cpu1_g0_cpu0_g2_tx_dp(12)';
NODE_NAME     U25 AG33
 '@T6G_MB_LIB.T6G(SCH_1):PAGE23_I215@PURE_QUANTA.GENOA_SP5(CHIPS)':
 'G2_RXP12': CDS_PINID='G2_RXP12';
NODE_NAME     U26 AG43
 '@T6G_MB_LIB.T6G(SCH_1):PAGE49_I213@PURE_QUANTA.GENOA_SP5(CHIPS)':
 'G0_TXP3': CDS_PINID='G0_TXP3';
NET_NAME
'GMI_CPU1_G0_CPU0_G2_TX_DP<13>'
 '@T6G_MB_LIB.T6G(SCH_1):GMI_CPU1_G0_CPU0_G2_TX_DP'<13>:
 C_SIGNAL='@t6g_mb_lib.t6g(sch_1):gmi_cpu1_g0_cpu0_g2_tx_dp(13)';
NODE_NAME     U25 AB36
 '@T6G_MB_LIB.T6G(SCH_1):PAGE23_I215@PURE_QUANTA.GENOA_SP5(CHIPS)':
 'G2_RXP13': CDS_PINID='G2_RXP13';
NODE_NAME     U26 AB40
 '@T6G_MB_LIB.T6G(SCH_1):PAGE49_I213@PURE_QUANTA.GENOA_SP5(CHIPS)':
 'G0_TXP2': CDS_PINID='G0_TXP2';
NET_NAME
'GMI_CPU1_G0_CPU0_G2_TX_DP<14>'
 '@T6G_MB_LIB.T6G(SCH_1):GMI_CPU1_G0_CPU0_G2_TX_DP'<14>:
 C_SIGNAL='@t6g_mb_lib.t6g(sch_1):gmi_cpu1_g0_cpu0_g2_tx_dp(14)';
NODE_NAME     U25 AD36
 '@T6G_MB_LIB.T6G(SCH_1):PAGE23_I215@PURE_QUANTA.GENOA_SP5(CHIPS)':
 'G2_RXP14': CDS_PINID='G2_RXP14';
NODE_NAME     U26 AD40
 '@T6G_MB_LIB.T6G(SCH_1):PAGE49_I213@PURE_QUANTA.GENOA_SP5(CHIPS)':
 'G0_TXP1': CDS_PINID='G0_TXP1';
NET_NAME
'GMI_CPU1_G0_CPU0_G2_TX_DP<15>'
 '@T6G_MB_LIB.T6G(SCH_1):GMI_CPU1_G0_CPU0_G2_TX_DP'<15>:
 C_SIGNAL='@t6g_mb_lib.t6g(sch_1):gmi_cpu1_g0_cpu0_g2_tx_dp(15)';
NODE_NAME     U25 AF36
 '@T6G_MB_LIB.T6G(SCH_1):PAGE23_I215@PURE_QUANTA.GENOA_SP5(CHIPS)':
 'G2_RXP15': CDS_PINID='G2_RXP15';
NODE_NAME     U26 AF40
 '@T6G_MB_LIB.T6G(SCH_1):PAGE49_I213@PURE_QUANTA.GENOA_SP5(CHIPS)':
 'G0_TXP0': CDS_PINID='G0_TXP0';
NET_NAME
'GMI_CPU1_G0_CPU0_G2_TX_DP<1>'
 '@T6G_MB_LIB.T6G(SCH_1):GMI_CPU1_G0_CPU0_G2_TX_DP'<1>:
 C_SIGNAL='@t6g_mb_lib.t6g(sch_1):gmi_cpu1_g0_cpu0_g2_tx_dp(1)';
NODE_NAME     U25 AC24
 '@T6G_MB_LIB.T6G(SCH_1):PAGE23_I215@PURE_QUANTA.GENOA_SP5(CHIPS)':
 'G2_RXP1': CDS_PINID='G2_RXP1';
NODE_NAME     U26 AC52
 '@T6G_MB_LIB.T6G(SCH_1):PAGE49_I213@PURE_QUANTA.GENOA_SP5(CHIPS)':
 'G0_TXP14': CDS_PINID='G0_TXP14';
NET_NAME
'GMI_CPU1_G0_CPU0_G2_TX_DP<2>'
 '@T6G_MB_LIB.T6G(SCH_1):GMI_CPU1_G0_CPU0_G2_TX_DP'<2>:
 C_SIGNAL='@t6g_mb_lib.t6g(sch_1):gmi_cpu1_g0_cpu0_g2_tx_dp(2)';
NODE_NAME     U25 AG24
 '@T6G_MB_LIB.T6G(SCH_1):PAGE23_I215@PURE_QUANTA.GENOA_SP5(CHIPS)':
 'G2_RXP2': CDS_PINID='G2_RXP2';
NODE_NAME     U26 AG52
 '@T6G_MB_LIB.T6G(SCH_1):PAGE49_I213@PURE_QUANTA.GENOA_SP5(CHIPS)':
 'G0_TXP13': CDS_PINID='G0_TXP13';
NET_NAME
'GMI_CPU1_G0_CPU0_G2_TX_DP<3>'
 '@T6G_MB_LIB.T6G(SCH_1):GMI_CPU1_G0_CPU0_G2_TX_DP'<3>:
 C_SIGNAL='@t6g_mb_lib.t6g(sch_1):gmi_cpu1_g0_cpu0_g2_tx_dp(3)';
NODE_NAME     U25 AE27
 '@T6G_MB_LIB.T6G(SCH_1):PAGE23_I215@PURE_QUANTA.GENOA_SP5(CHIPS)':
 'G2_RXP3': CDS_PINID='G2_RXP3';
NODE_NAME     U26 AE49
 '@T6G_MB_LIB.T6G(SCH_1):PAGE49_I213@PURE_QUANTA.GENOA_SP5(CHIPS)':
 'G0_TXP12': CDS_PINID='G0_TXP12';
NET_NAME
'GMI_CPU1_G0_CPU0_G2_TX_DP<4>'
 '@T6G_MB_LIB.T6G(SCH_1):GMI_CPU1_G0_CPU0_G2_TX_DP'<4>:
 C_SIGNAL='@t6g_mb_lib.t6g(sch_1):gmi_cpu1_g0_cpu0_g2_tx_dp(4)';
NODE_NAME     U25 AC27
 '@T6G_MB_LIB.T6G(SCH_1):PAGE23_I215@PURE_QUANTA.GENOA_SP5(CHIPS)':
 'G2_RXP4': CDS_PINID='G2_RXP4';
NODE_NAME     U26 AC49
 '@T6G_MB_LIB.T6G(SCH_1):PAGE49_I213@PURE_QUANTA.GENOA_SP5(CHIPS)':
 'G0_TXP11': CDS_PINID='G0_TXP11';
NET_NAME
'GMI_CPU1_G0_CPU0_G2_TX_DP<5>'
 '@T6G_MB_LIB.T6G(SCH_1):GMI_CPU1_G0_CPU0_G2_TX_DP'<5>:
 C_SIGNAL='@t6g_mb_lib.t6g(sch_1):gmi_cpu1_g0_cpu0_g2_tx_dp(5)';
NODE_NAME     U25 AG27
 '@T6G_MB_LIB.T6G(SCH_1):PAGE23_I215@PURE_QUANTA.GENOA_SP5(CHIPS)':
 'G2_RXP5': CDS_PINID='G2_RXP5';
NODE_NAME     U26 AG49
 '@T6G_MB_LIB.T6G(SCH_1):PAGE49_I213@PURE_QUANTA.GENOA_SP5(CHIPS)':
 'G0_TXP10': CDS_PINID='G0_TXP10';
NET_NAME
'GMI_CPU1_G0_CPU0_G2_TX_DP<6>'
 '@T6G_MB_LIB.T6G(SCH_1):GMI_CPU1_G0_CPU0_G2_TX_DP'<6>:
 C_SIGNAL='@t6g_mb_lib.t6g(sch_1):gmi_cpu1_g0_cpu0_g2_tx_dp(6)';
NODE_NAME     U25 AE30
 '@T6G_MB_LIB.T6G(SCH_1):PAGE23_I215@PURE_QUANTA.GENOA_SP5(CHIPS)':
 'G2_RXP6': CDS_PINID='G2_RXP6';
NODE_NAME     U26 AE46
 '@T6G_MB_LIB.T6G(SCH_1):PAGE49_I213@PURE_QUANTA.GENOA_SP5(CHIPS)':
 'G0_TXP9': CDS_PINID='G0_TXP9';
NET_NAME
'GMI_CPU1_G0_CPU0_G2_TX_DP<7>'
 '@T6G_MB_LIB.T6G(SCH_1):GMI_CPU1_G0_CPU0_G2_TX_DP'<7>:
 C_SIGNAL='@t6g_mb_lib.t6g(sch_1):gmi_cpu1_g0_cpu0_g2_tx_dp(7)';
NODE_NAME     U25 AC30
 '@T6G_MB_LIB.T6G(SCH_1):PAGE23_I215@PURE_QUANTA.GENOA_SP5(CHIPS)':
 'G2_RXP7': CDS_PINID='G2_RXP7';
NODE_NAME     U26 AC46
 '@T6G_MB_LIB.T6G(SCH_1):PAGE49_I213@PURE_QUANTA.GENOA_SP5(CHIPS)':
 'G0_TXP8': CDS_PINID='G0_TXP8';
NET_NAME
'GMI_CPU1_G0_CPU0_G2_TX_DP<8>'
 '@T6G_MB_LIB.T6G(SCH_1):GMI_CPU1_G0_CPU0_G2_TX_DP'<8>:
 C_SIGNAL='@t6g_mb_lib.t6g(sch_1):gmi_cpu1_g0_cpu0_g2_tx_dp(8)';
NODE_NAME     U25 AG30
 '@T6G_MB_LIB.T6G(SCH_1):PAGE23_I215@PURE_QUANTA.GENOA_SP5(CHIPS)':
 'G2_RXP8': CDS_PINID='G2_RXP8';
NODE_NAME     U26 AG46
 '@T6G_MB_LIB.T6G(SCH_1):PAGE49_I213@PURE_QUANTA.GENOA_SP5(CHIPS)':
 'G0_TXP7': CDS_PINID='G0_TXP7';
NET_NAME
'GMI_CPU1_G0_CPU0_G2_TX_DP<9>'
 '@T6G_MB_LIB.T6G(SCH_1):GMI_CPU1_G0_CPU0_G2_TX_DP'<9>:
 C_SIGNAL='@t6g_mb_lib.t6g(sch_1):gmi_cpu1_g0_cpu0_g2_tx_dp(9)';
NODE_NAME     U25 AE33
 '@T6G_MB_LIB.T6G(SCH_1):PAGE23_I215@PURE_QUANTA.GENOA_SP5(CHIPS)':
 'G2_RXP9': CDS_PINID='G2_RXP9';
NODE_NAME     U26 AE43
 '@T6G_MB_LIB.T6G(SCH_1):PAGE49_I213@PURE_QUANTA.GENOA_SP5(CHIPS)':
 'G0_TXP6': CDS_PINID='G0_TXP6';
NET_NAME
'GMI_CPU1_G2_CPU0_G0_TX_DN<0>'
 '@T6G_MB_LIB.T6G(SCH_1):GMI_CPU1_G2_CPU0_G0_TX_DN'<0>:
 C_SIGNAL='@t6g_mb_lib.t6g(sch_1):gmi_cpu1_g2_cpu0_g0_tx_dn(0)';
NODE_NAME     U25 M40
 '@T6G_MB_LIB.T6G(SCH_1):PAGE22_I207@PURE_QUANTA.GENOA_SP5(CHIPS)':
 'G0_RXN0': CDS_PINID='G0_RXN0';
NODE_NAME     U26 M36
 '@T6G_MB_LIB.T6G(SCH_1):PAGE50_I143@PURE_QUANTA.GENOA_SP5(CHIPS)':
 'G2_TXN15': CDS_PINID='G2_TXN15';
NET_NAME
'GMI_CPU1_G2_CPU0_G0_TX_DN<10>'
 '@T6G_MB_LIB.T6G(SCH_1):GMI_CPU1_G2_CPU0_G0_TX_DN'<10>:
 C_SIGNAL='@t6g_mb_lib.t6g(sch_1):gmi_cpu1_g2_cpu0_g0_tx_dn(10)';
NODE_NAME     U25 G49
 '@T6G_MB_LIB.T6G(SCH_1):PAGE22_I207@PURE_QUANTA.GENOA_SP5(CHIPS)':
 'G0_RXN10': CDS_PINID='G0_RXN10';
NODE_NAME     U26 G27
 '@T6G_MB_LIB.T6G(SCH_1):PAGE50_I143@PURE_QUANTA.GENOA_SP5(CHIPS)':
 'G2_TXN5': CDS_PINID='G2_TXN5';
NET_NAME
'GMI_CPU1_G2_CPU0_G0_TX_DN<11>'
 '@T6G_MB_LIB.T6G(SCH_1):GMI_CPU1_G2_CPU0_G0_TX_DN'<11>:
 C_SIGNAL='@t6g_mb_lib.t6g(sch_1):gmi_cpu1_g2_cpu0_g0_tx_dn(11)';
NODE_NAME     U25 J49
 '@T6G_MB_LIB.T6G(SCH_1):PAGE22_I207@PURE_QUANTA.GENOA_SP5(CHIPS)':
 'G0_RXN11': CDS_PINID='G0_RXN11';
NODE_NAME     U26 J27
 '@T6G_MB_LIB.T6G(SCH_1):PAGE50_I143@PURE_QUANTA.GENOA_SP5(CHIPS)':
 'G2_TXN4': CDS_PINID='G2_TXN4';
NET_NAME
'GMI_CPU1_G2_CPU0_G0_TX_DN<12>'
 '@T6G_MB_LIB.T6G(SCH_1):GMI_CPU1_G2_CPU0_G0_TX_DN'<12>:
 C_SIGNAL='@t6g_mb_lib.t6g(sch_1):gmi_cpu1_g2_cpu0_g0_tx_dn(12)';
NODE_NAME     U25 L52
 '@T6G_MB_LIB.T6G(SCH_1):PAGE22_I207@PURE_QUANTA.GENOA_SP5(CHIPS)':
 'G0_RXN12': CDS_PINID='G0_RXN12';
NODE_NAME     U26 L24
 '@T6G_MB_LIB.T6G(SCH_1):PAGE50_I143@PURE_QUANTA.GENOA_SP5(CHIPS)':
 'G2_TXN3': CDS_PINID='G2_TXN3';
NET_NAME
'GMI_CPU1_G2_CPU0_G0_TX_DN<13>'
 '@T6G_MB_LIB.T6G(SCH_1):GMI_CPU1_G2_CPU0_G0_TX_DN'<13>:
 C_SIGNAL='@t6g_mb_lib.t6g(sch_1):gmi_cpu1_g2_cpu0_g0_tx_dn(13)';
NODE_NAME     U25 G52
 '@T6G_MB_LIB.T6G(SCH_1):PAGE22_I207@PURE_QUANTA.GENOA_SP5(CHIPS)':
 'G0_RXN13': CDS_PINID='G0_RXN13';
NODE_NAME     U26 G24
 '@T6G_MB_LIB.T6G(SCH_1):PAGE50_I143@PURE_QUANTA.GENOA_SP5(CHIPS)':
 'G2_TXN2': CDS_PINID='G2_TXN2';
NET_NAME
'GMI_CPU1_G2_CPU0_G0_TX_DN<14>'
 '@T6G_MB_LIB.T6G(SCH_1):GMI_CPU1_G2_CPU0_G0_TX_DN'<14>:
 C_SIGNAL='@t6g_mb_lib.t6g(sch_1):gmi_cpu1_g2_cpu0_g0_tx_dn(14)';
NODE_NAME     U25 J52
 '@T6G_MB_LIB.T6G(SCH_1):PAGE22_I207@PURE_QUANTA.GENOA_SP5(CHIPS)':
 'G0_RXN14': CDS_PINID='G0_RXN14';
NODE_NAME     U26 J24
 '@T6G_MB_LIB.T6G(SCH_1):PAGE50_I143@PURE_QUANTA.GENOA_SP5(CHIPS)':
 'G2_TXN1': CDS_PINID='G2_TXN1';
NET_NAME
'GMI_CPU1_G2_CPU0_G0_TX_DN<15>'
 '@T6G_MB_LIB.T6G(SCH_1):GMI_CPU1_G2_CPU0_G0_TX_DN'<15>:
 C_SIGNAL='@t6g_mb_lib.t6g(sch_1):gmi_cpu1_g2_cpu0_g0_tx_dn(15)';
NODE_NAME     U25 N52
 '@T6G_MB_LIB.T6G(SCH_1):PAGE22_I207@PURE_QUANTA.GENOA_SP5(CHIPS)':
 'G0_RXN15': CDS_PINID='G0_RXN15';
NODE_NAME     U26 N24
 '@T6G_MB_LIB.T6G(SCH_1):PAGE50_I143@PURE_QUANTA.GENOA_SP5(CHIPS)':
 'G2_TXN0': CDS_PINID='G2_TXN0';
NET_NAME
'GMI_CPU1_G2_CPU0_G0_TX_DN<1>'
 '@T6G_MB_LIB.T6G(SCH_1):GMI_CPU1_G2_CPU0_G0_TX_DN'<1>:
 C_SIGNAL='@t6g_mb_lib.t6g(sch_1):gmi_cpu1_g2_cpu0_g0_tx_dn(1)';
NODE_NAME     U25 K40
 '@T6G_MB_LIB.T6G(SCH_1):PAGE22_I207@PURE_QUANTA.GENOA_SP5(CHIPS)':
 'G0_RXN1': CDS_PINID='G0_RXN1';
NODE_NAME     U26 K36
 '@T6G_MB_LIB.T6G(SCH_1):PAGE50_I143@PURE_QUANTA.GENOA_SP5(CHIPS)':
 'G2_TXN14': CDS_PINID='G2_TXN14';
NET_NAME
'GMI_CPU1_G2_CPU0_G0_TX_DN<2>'
 '@T6G_MB_LIB.T6G(SCH_1):GMI_CPU1_G2_CPU0_G0_TX_DN'<2>:
 C_SIGNAL='@t6g_mb_lib.t6g(sch_1):gmi_cpu1_g2_cpu0_g0_tx_dn(2)';
NODE_NAME     U25 H40
 '@T6G_MB_LIB.T6G(SCH_1):PAGE22_I207@PURE_QUANTA.GENOA_SP5(CHIPS)':
 'G0_RXN2': CDS_PINID='G0_RXN2';
NODE_NAME     U26 H36
 '@T6G_MB_LIB.T6G(SCH_1):PAGE50_I143@PURE_QUANTA.GENOA_SP5(CHIPS)':
 'G2_TXN13': CDS_PINID='G2_TXN13';
NET_NAME
'GMI_CPU1_G2_CPU0_G0_TX_DN<3>'
 '@T6G_MB_LIB.T6G(SCH_1):GMI_CPU1_G2_CPU0_G0_TX_DN'<3>:
 C_SIGNAL='@t6g_mb_lib.t6g(sch_1):gmi_cpu1_g2_cpu0_g0_tx_dn(3)';
NODE_NAME     U25 L43
 '@T6G_MB_LIB.T6G(SCH_1):PAGE22_I207@PURE_QUANTA.GENOA_SP5(CHIPS)':
 'G0_RXN3': CDS_PINID='G0_RXN3';
NODE_NAME     U26 L33
 '@T6G_MB_LIB.T6G(SCH_1):PAGE50_I143@PURE_QUANTA.GENOA_SP5(CHIPS)':
 'G2_TXN12': CDS_PINID='G2_TXN12';
NET_NAME
'GMI_CPU1_G2_CPU0_G0_TX_DN<4>'
 '@T6G_MB_LIB.T6G(SCH_1):GMI_CPU1_G2_CPU0_G0_TX_DN'<4>:
 C_SIGNAL='@t6g_mb_lib.t6g(sch_1):gmi_cpu1_g2_cpu0_g0_tx_dn(4)';
NODE_NAME     U25 G43
 '@T6G_MB_LIB.T6G(SCH_1):PAGE22_I207@PURE_QUANTA.GENOA_SP5(CHIPS)':
 'G0_RXN4': CDS_PINID='G0_RXN4';
NODE_NAME     U26 G33
 '@T6G_MB_LIB.T6G(SCH_1):PAGE50_I143@PURE_QUANTA.GENOA_SP5(CHIPS)':
 'G2_TXN11': CDS_PINID='G2_TXN11';
NET_NAME
'GMI_CPU1_G2_CPU0_G0_TX_DN<5>'
 '@T6G_MB_LIB.T6G(SCH_1):GMI_CPU1_G2_CPU0_G0_TX_DN'<5>:
 C_SIGNAL='@t6g_mb_lib.t6g(sch_1):gmi_cpu1_g2_cpu0_g0_tx_dn(5)';
NODE_NAME     U25 J43
 '@T6G_MB_LIB.T6G(SCH_1):PAGE22_I207@PURE_QUANTA.GENOA_SP5(CHIPS)':
 'G0_RXN5': CDS_PINID='G0_RXN5';
NODE_NAME     U26 J33
 '@T6G_MB_LIB.T6G(SCH_1):PAGE50_I143@PURE_QUANTA.GENOA_SP5(CHIPS)':
 'G2_TXN10': CDS_PINID='G2_TXN10';
NET_NAME
'GMI_CPU1_G2_CPU0_G0_TX_DN<6>'
 '@T6G_MB_LIB.T6G(SCH_1):GMI_CPU1_G2_CPU0_G0_TX_DN'<6>:
 C_SIGNAL='@t6g_mb_lib.t6g(sch_1):gmi_cpu1_g2_cpu0_g0_tx_dn(6)';
NODE_NAME     U25 L46
 '@T6G_MB_LIB.T6G(SCH_1):PAGE22_I207@PURE_QUANTA.GENOA_SP5(CHIPS)':
 'G0_RXN6': CDS_PINID='G0_RXN6';
NODE_NAME     U26 L30
 '@T6G_MB_LIB.T6G(SCH_1):PAGE50_I143@PURE_QUANTA.GENOA_SP5(CHIPS)':
 'G2_TXN9': CDS_PINID='G2_TXN9';
NET_NAME
'GMI_CPU1_G2_CPU0_G0_TX_DN<7>'
 '@T6G_MB_LIB.T6G(SCH_1):GMI_CPU1_G2_CPU0_G0_TX_DN'<7>:
 C_SIGNAL='@t6g_mb_lib.t6g(sch_1):gmi_cpu1_g2_cpu0_g0_tx_dn(7)';
NODE_NAME     U25 G46
 '@T6G_MB_LIB.T6G(SCH_1):PAGE22_I207@PURE_QUANTA.GENOA_SP5(CHIPS)':
 'G0_RXN7': CDS_PINID='G0_RXN7';
NODE_NAME     U26 G30
 '@T6G_MB_LIB.T6G(SCH_1):PAGE50_I143@PURE_QUANTA.GENOA_SP5(CHIPS)':
 'G2_TXN8': CDS_PINID='G2_TXN8';
NET_NAME
'GMI_CPU1_G2_CPU0_G0_TX_DN<8>'
 '@T6G_MB_LIB.T6G(SCH_1):GMI_CPU1_G2_CPU0_G0_TX_DN'<8>:
 C_SIGNAL='@t6g_mb_lib.t6g(sch_1):gmi_cpu1_g2_cpu0_g0_tx_dn(8)';
NODE_NAME     U25 J46
 '@T6G_MB_LIB.T6G(SCH_1):PAGE22_I207@PURE_QUANTA.GENOA_SP5(CHIPS)':
 'G0_RXN8': CDS_PINID='G0_RXN8';
NODE_NAME     U26 J30
 '@T6G_MB_LIB.T6G(SCH_1):PAGE50_I143@PURE_QUANTA.GENOA_SP5(CHIPS)':
 'G2_TXN7': CDS_PINID='G2_TXN7';
NET_NAME
'GMI_CPU1_G2_CPU0_G0_TX_DN<9>'
 '@T6G_MB_LIB.T6G(SCH_1):GMI_CPU1_G2_CPU0_G0_TX_DN'<9>:
 C_SIGNAL='@t6g_mb_lib.t6g(sch_1):gmi_cpu1_g2_cpu0_g0_tx_dn(9)';
NODE_NAME     U25 L49
 '@T6G_MB_LIB.T6G(SCH_1):PAGE22_I207@PURE_QUANTA.GENOA_SP5(CHIPS)':
 'G0_RXN9': CDS_PINID='G0_RXN9';
NODE_NAME     U26 L27
 '@T6G_MB_LIB.T6G(SCH_1):PAGE50_I143@PURE_QUANTA.GENOA_SP5(CHIPS)':
 'G2_TXN6': CDS_PINID='G2_TXN6';
NET_NAME
'GMI_CPU1_G2_CPU0_G0_TX_DP<0>'
 '@T6G_MB_LIB.T6G(SCH_1):GMI_CPU1_G2_CPU0_G0_TX_DP'<0>:
 C_SIGNAL='@t6g_mb_lib.t6g(sch_1):gmi_cpu1_g2_cpu0_g0_tx_dp(0)';
NODE_NAME     U25 M41
 '@T6G_MB_LIB.T6G(SCH_1):PAGE22_I207@PURE_QUANTA.GENOA_SP5(CHIPS)':
 'G0_RXP0': CDS_PINID='G0_RXP0';
NODE_NAME     U26 M35
 '@T6G_MB_LIB.T6G(SCH_1):PAGE50_I143@PURE_QUANTA.GENOA_SP5(CHIPS)':
 'G2_TXP15': CDS_PINID='G2_TXP15';
NET_NAME
'GMI_CPU1_G2_CPU0_G0_TX_DP<10>'
 '@T6G_MB_LIB.T6G(SCH_1):GMI_CPU1_G2_CPU0_G0_TX_DP'<10>:
 C_SIGNAL='@t6g_mb_lib.t6g(sch_1):gmi_cpu1_g2_cpu0_g0_tx_dp(10)';
NODE_NAME     U25 G50
 '@T6G_MB_LIB.T6G(SCH_1):PAGE22_I207@PURE_QUANTA.GENOA_SP5(CHIPS)':
 'G0_RXP10': CDS_PINID='G0_RXP10';
NODE_NAME     U26 G26
 '@T6G_MB_LIB.T6G(SCH_1):PAGE50_I143@PURE_QUANTA.GENOA_SP5(CHIPS)':
 'G2_TXP5': CDS_PINID='G2_TXP5';
NET_NAME
'GMI_CPU1_G2_CPU0_G0_TX_DP<11>'
 '@T6G_MB_LIB.T6G(SCH_1):GMI_CPU1_G2_CPU0_G0_TX_DP'<11>:
 C_SIGNAL='@t6g_mb_lib.t6g(sch_1):gmi_cpu1_g2_cpu0_g0_tx_dp(11)';
NODE_NAME     U25 J50
 '@T6G_MB_LIB.T6G(SCH_1):PAGE22_I207@PURE_QUANTA.GENOA_SP5(CHIPS)':
 'G0_RXP11': CDS_PINID='G0_RXP11';
NODE_NAME     U26 J26
 '@T6G_MB_LIB.T6G(SCH_1):PAGE50_I143@PURE_QUANTA.GENOA_SP5(CHIPS)':
 'G2_TXP4': CDS_PINID='G2_TXP4';
NET_NAME
'GMI_CPU1_G2_CPU0_G0_TX_DP<12>'
 '@T6G_MB_LIB.T6G(SCH_1):GMI_CPU1_G2_CPU0_G0_TX_DP'<12>:
 C_SIGNAL='@t6g_mb_lib.t6g(sch_1):gmi_cpu1_g2_cpu0_g0_tx_dp(12)';
NODE_NAME     U25 L53
 '@T6G_MB_LIB.T6G(SCH_1):PAGE22_I207@PURE_QUANTA.GENOA_SP5(CHIPS)':
 'G0_RXP12': CDS_PINID='G0_RXP12';
NODE_NAME     U26 L23
 '@T6G_MB_LIB.T6G(SCH_1):PAGE50_I143@PURE_QUANTA.GENOA_SP5(CHIPS)':
 'G2_TXP3': CDS_PINID='G2_TXP3';
NET_NAME
'GMI_CPU1_G2_CPU0_G0_TX_DP<13>'
 '@T6G_MB_LIB.T6G(SCH_1):GMI_CPU1_G2_CPU0_G0_TX_DP'<13>:
 C_SIGNAL='@t6g_mb_lib.t6g(sch_1):gmi_cpu1_g2_cpu0_g0_tx_dp(13)';
NODE_NAME     U25 G53
 '@T6G_MB_LIB.T6G(SCH_1):PAGE22_I207@PURE_QUANTA.GENOA_SP5(CHIPS)':
 'G0_RXP13': CDS_PINID='G0_RXP13';
NODE_NAME     U26 G23
 '@T6G_MB_LIB.T6G(SCH_1):PAGE50_I143@PURE_QUANTA.GENOA_SP5(CHIPS)':
 'G2_TXP2': CDS_PINID='G2_TXP2';
NET_NAME
'GMI_CPU1_G2_CPU0_G0_TX_DP<14>'
 '@T6G_MB_LIB.T6G(SCH_1):GMI_CPU1_G2_CPU0_G0_TX_DP'<14>:
 C_SIGNAL='@t6g_mb_lib.t6g(sch_1):gmi_cpu1_g2_cpu0_g0_tx_dp(14)';
NODE_NAME     U25 J53
 '@T6G_MB_LIB.T6G(SCH_1):PAGE22_I207@PURE_QUANTA.GENOA_SP5(CHIPS)':
 'G0_RXP14': CDS_PINID='G0_RXP14';
NODE_NAME     U26 J23
 '@T6G_MB_LIB.T6G(SCH_1):PAGE50_I143@PURE_QUANTA.GENOA_SP5(CHIPS)':
 'G2_TXP1': CDS_PINID='G2_TXP1';
NET_NAME
'GMI_CPU1_G2_CPU0_G0_TX_DP<15>'
 '@T6G_MB_LIB.T6G(SCH_1):GMI_CPU1_G2_CPU0_G0_TX_DP'<15>:
 C_SIGNAL='@t6g_mb_lib.t6g(sch_1):gmi_cpu1_g2_cpu0_g0_tx_dp(15)';
NODE_NAME     U25 N53
 '@T6G_MB_LIB.T6G(SCH_1):PAGE22_I207@PURE_QUANTA.GENOA_SP5(CHIPS)':
 'G0_RXP15': CDS_PINID='G0_RXP15';
NODE_NAME     U26 N23
 '@T6G_MB_LIB.T6G(SCH_1):PAGE50_I143@PURE_QUANTA.GENOA_SP5(CHIPS)':
 'G2_TXP0': CDS_PINID='G2_TXP0';
NET_NAME
'GMI_CPU1_G2_CPU0_G0_TX_DP<1>'
 '@T6G_MB_LIB.T6G(SCH_1):GMI_CPU1_G2_CPU0_G0_TX_DP'<1>:
 C_SIGNAL='@t6g_mb_lib.t6g(sch_1):gmi_cpu1_g2_cpu0_g0_tx_dp(1)';
NODE_NAME     U25 K41
 '@T6G_MB_LIB.T6G(SCH_1):PAGE22_I207@PURE_QUANTA.GENOA_SP5(CHIPS)':
 'G0_RXP1': CDS_PINID='G0_RXP1';
NODE_NAME     U26 K35
 '@T6G_MB_LIB.T6G(SCH_1):PAGE50_I143@PURE_QUANTA.GENOA_SP5(CHIPS)':
 'G2_TXP14': CDS_PINID='G2_TXP14';
NET_NAME
'GMI_CPU1_G2_CPU0_G0_TX_DP<2>'
 '@T6G_MB_LIB.T6G(SCH_1):GMI_CPU1_G2_CPU0_G0_TX_DP'<2>:
 C_SIGNAL='@t6g_mb_lib.t6g(sch_1):gmi_cpu1_g2_cpu0_g0_tx_dp(2)';
NODE_NAME     U25 H41
 '@T6G_MB_LIB.T6G(SCH_1):PAGE22_I207@PURE_QUANTA.GENOA_SP5(CHIPS)':
 'G0_RXP2': CDS_PINID='G0_RXP2';
NODE_NAME     U26 H35
 '@T6G_MB_LIB.T6G(SCH_1):PAGE50_I143@PURE_QUANTA.GENOA_SP5(CHIPS)':
 'G2_TXP13': CDS_PINID='G2_TXP13';
NET_NAME
'GMI_CPU1_G2_CPU0_G0_TX_DP<3>'
 '@T6G_MB_LIB.T6G(SCH_1):GMI_CPU1_G2_CPU0_G0_TX_DP'<3>:
 C_SIGNAL='@t6g_mb_lib.t6g(sch_1):gmi_cpu1_g2_cpu0_g0_tx_dp(3)';
NODE_NAME     U25 L44
 '@T6G_MB_LIB.T6G(SCH_1):PAGE22_I207@PURE_QUANTA.GENOA_SP5(CHIPS)':
 'G0_RXP3': CDS_PINID='G0_RXP3';
NODE_NAME     U26 L32
 '@T6G_MB_LIB.T6G(SCH_1):PAGE50_I143@PURE_QUANTA.GENOA_SP5(CHIPS)':
 'G2_TXP12': CDS_PINID='G2_TXP12';
NET_NAME
'GMI_CPU1_G2_CPU0_G0_TX_DP<4>'
 '@T6G_MB_LIB.T6G(SCH_1):GMI_CPU1_G2_CPU0_G0_TX_DP'<4>:
 C_SIGNAL='@t6g_mb_lib.t6g(sch_1):gmi_cpu1_g2_cpu0_g0_tx_dp(4)';
NODE_NAME     U25 G44
 '@T6G_MB_LIB.T6G(SCH_1):PAGE22_I207@PURE_QUANTA.GENOA_SP5(CHIPS)':
 'G0_RXP4': CDS_PINID='G0_RXP4';
NODE_NAME     U26 G32
 '@T6G_MB_LIB.T6G(SCH_1):PAGE50_I143@PURE_QUANTA.GENOA_SP5(CHIPS)':
 'G2_TXP11': CDS_PINID='G2_TXP11';
NET_NAME
'GMI_CPU1_G2_CPU0_G0_TX_DP<5>'
 '@T6G_MB_LIB.T6G(SCH_1):GMI_CPU1_G2_CPU0_G0_TX_DP'<5>:
 C_SIGNAL='@t6g_mb_lib.t6g(sch_1):gmi_cpu1_g2_cpu0_g0_tx_dp(5)';
NODE_NAME     U25 J44
 '@T6G_MB_LIB.T6G(SCH_1):PAGE22_I207@PURE_QUANTA.GENOA_SP5(CHIPS)':
 'G0_RXP5': CDS_PINID='G0_RXP5';
NODE_NAME     U26 J32
 '@T6G_MB_LIB.T6G(SCH_1):PAGE50_I143@PURE_QUANTA.GENOA_SP5(CHIPS)':
 'G2_TXP10': CDS_PINID='G2_TXP10';
NET_NAME
'GMI_CPU1_G2_CPU0_G0_TX_DP<6>'
 '@T6G_MB_LIB.T6G(SCH_1):GMI_CPU1_G2_CPU0_G0_TX_DP'<6>:
 C_SIGNAL='@t6g_mb_lib.t6g(sch_1):gmi_cpu1_g2_cpu0_g0_tx_dp(6)';
NODE_NAME     U25 L47
 '@T6G_MB_LIB.T6G(SCH_1):PAGE22_I207@PURE_QUANTA.GENOA_SP5(CHIPS)':
 'G0_RXP6': CDS_PINID='G0_RXP6';
NODE_NAME     U26 L29
 '@T6G_MB_LIB.T6G(SCH_1):PAGE50_I143@PURE_QUANTA.GENOA_SP5(CHIPS)':
 'G2_TXP9': CDS_PINID='G2_TXP9';
NET_NAME
'GMI_CPU1_G2_CPU0_G0_TX_DP<7>'
 '@T6G_MB_LIB.T6G(SCH_1):GMI_CPU1_G2_CPU0_G0_TX_DP'<7>:
 C_SIGNAL='@t6g_mb_lib.t6g(sch_1):gmi_cpu1_g2_cpu0_g0_tx_dp(7)';
NODE_NAME     U25 G47
 '@T6G_MB_LIB.T6G(SCH_1):PAGE22_I207@PURE_QUANTA.GENOA_SP5(CHIPS)':
 'G0_RXP7': CDS_PINID='G0_RXP7';
NODE_NAME     U26 G29
 '@T6G_MB_LIB.T6G(SCH_1):PAGE50_I143@PURE_QUANTA.GENOA_SP5(CHIPS)':
 'G2_TXP8': CDS_PINID='G2_TXP8';
NET_NAME
'GMI_CPU1_G2_CPU0_G0_TX_DP<8>'
 '@T6G_MB_LIB.T6G(SCH_1):GMI_CPU1_G2_CPU0_G0_TX_DP'<8>:
 C_SIGNAL='@t6g_mb_lib.t6g(sch_1):gmi_cpu1_g2_cpu0_g0_tx_dp(8)';
NODE_NAME     U25 J47
 '@T6G_MB_LIB.T6G(SCH_1):PAGE22_I207@PURE_QUANTA.GENOA_SP5(CHIPS)':
 'G0_RXP8': CDS_PINID='G0_RXP8';
NODE_NAME     U26 J29
 '@T6G_MB_LIB.T6G(SCH_1):PAGE50_I143@PURE_QUANTA.GENOA_SP5(CHIPS)':
 'G2_TXP7': CDS_PINID='G2_TXP7';
NET_NAME
'GMI_CPU1_G2_CPU0_G0_TX_DP<9>'
 '@T6G_MB_LIB.T6G(SCH_1):GMI_CPU1_G2_CPU0_G0_TX_DP'<9>:
 C_SIGNAL='@t6g_mb_lib.t6g(sch_1):gmi_cpu1_g2_cpu0_g0_tx_dp(9)';
NODE_NAME     U25 L50
 '@T6G_MB_LIB.T6G(SCH_1):PAGE22_I207@PURE_QUANTA.GENOA_SP5(CHIPS)':
 'G0_RXP9': CDS_PINID='G0_RXP9';
NODE_NAME     U26 L26
 '@T6G_MB_LIB.T6G(SCH_1):PAGE50_I143@PURE_QUANTA.GENOA_SP5(CHIPS)':
 'G2_TXP6': CDS_PINID='G2_TXP6';
NET_NAME
'GMI_CPU1_G3_CPU0_G1_TX_DN<0>'
 '@T6G_MB_LIB.T6G(SCH_1):GMI_CPU1_G3_CPU0_G1_TX_DN'<0>:
 C_SIGNAL='@t6g_mb_lib.t6g(sch_1):gmi_cpu1_g3_cpu0_g1_tx_dn(0)';
NODE_NAME     U25 V40
 '@T6G_MB_LIB.T6G(SCH_1):PAGE22_I208@PURE_QUANTA.GENOA_SP5(CHIPS)':
 'G1_RXN0': CDS_PINID='G1_RXN0';
NODE_NAME     U26 V36
 '@T6G_MB_LIB.T6G(SCH_1):PAGE50_I144@PURE_QUANTA.GENOA_SP5(CHIPS)':
 'G3_TXN15||SATA37_TXN': CDS_PINID='\g3_txn15||sata37_txn\';
NET_NAME
'GMI_CPU1_G3_CPU0_G1_TX_DN<10>'
 '@T6G_MB_LIB.T6G(SCH_1):GMI_CPU1_G3_CPU0_G1_TX_DN'<10>:
 C_SIGNAL='@t6g_mb_lib.t6g(sch_1):gmi_cpu1_g3_cpu0_g1_tx_dn(10)';
NODE_NAME     U25 N49
 '@T6G_MB_LIB.T6G(SCH_1):PAGE22_I208@PURE_QUANTA.GENOA_SP5(CHIPS)':
 'G1_RXN10': CDS_PINID='G1_RXN10';
NODE_NAME     U26 N27
 '@T6G_MB_LIB.T6G(SCH_1):PAGE50_I144@PURE_QUANTA.GENOA_SP5(CHIPS)':
 'G3_TXN5||SATA25_TXN': CDS_PINID='\g3_txn5||sata25_txn\';
NET_NAME
'GMI_CPU1_G3_CPU0_G1_TX_DN<11>'
 '@T6G_MB_LIB.T6G(SCH_1):GMI_CPU1_G3_CPU0_G1_TX_DN'<11>:
 C_SIGNAL='@t6g_mb_lib.t6g(sch_1):gmi_cpu1_g3_cpu0_g1_tx_dn(11)';
NODE_NAME     U25 R49
 '@T6G_MB_LIB.T6G(SCH_1):PAGE22_I208@PURE_QUANTA.GENOA_SP5(CHIPS)':
 'G1_RXN11': CDS_PINID='G1_RXN11';
NODE_NAME     U26 R27
 '@T6G_MB_LIB.T6G(SCH_1):PAGE50_I144@PURE_QUANTA.GENOA_SP5(CHIPS)':
 'G3_TXN4||SATA24_TXN': CDS_PINID='\g3_txn4||sata24_txn\';
NET_NAME
'GMI_CPU1_G3_CPU0_G1_TX_DN<12>'
 '@T6G_MB_LIB.T6G(SCH_1):GMI_CPU1_G3_CPU0_G1_TX_DN'<12>:
 C_SIGNAL='@t6g_mb_lib.t6g(sch_1):gmi_cpu1_g3_cpu0_g1_tx_dn(12)';
NODE_NAME     U25 U49
 '@T6G_MB_LIB.T6G(SCH_1):PAGE22_I208@PURE_QUANTA.GENOA_SP5(CHIPS)':
 'G1_RXN12': CDS_PINID='G1_RXN12';
NODE_NAME     U26 U27
 '@T6G_MB_LIB.T6G(SCH_1):PAGE50_I144@PURE_QUANTA.GENOA_SP5(CHIPS)':
 'G3_TXN3||SATA23_TXN': CDS_PINID='\g3_txn3||sata23_txn\';
NET_NAME
'GMI_CPU1_G3_CPU0_G1_TX_DN<13>'
 '@T6G_MB_LIB.T6G(SCH_1):GMI_CPU1_G3_CPU0_G1_TX_DN'<13>:
 C_SIGNAL='@t6g_mb_lib.t6g(sch_1):gmi_cpu1_g3_cpu0_g1_tx_dn(13)';
NODE_NAME     U25 W52
 '@T6G_MB_LIB.T6G(SCH_1):PAGE22_I208@PURE_QUANTA.GENOA_SP5(CHIPS)':
 'G1_RXN13': CDS_PINID='G1_RXN13';
NODE_NAME     U26 W24
 '@T6G_MB_LIB.T6G(SCH_1):PAGE50_I144@PURE_QUANTA.GENOA_SP5(CHIPS)':
 'G3_TXN2||SATA22_TXN': CDS_PINID='\g3_txn2||sata22_txn\';
NET_NAME
'GMI_CPU1_G3_CPU0_G1_TX_DN<14>'
 '@T6G_MB_LIB.T6G(SCH_1):GMI_CPU1_G3_CPU0_G1_TX_DN'<14>:
 C_SIGNAL='@t6g_mb_lib.t6g(sch_1):gmi_cpu1_g3_cpu0_g1_tx_dn(14)';
NODE_NAME     U25 R52
 '@T6G_MB_LIB.T6G(SCH_1):PAGE22_I208@PURE_QUANTA.GENOA_SP5(CHIPS)':
 'G1_RXN14': CDS_PINID='G1_RXN14';
NODE_NAME     U26 R24
 '@T6G_MB_LIB.T6G(SCH_1):PAGE50_I144@PURE_QUANTA.GENOA_SP5(CHIPS)':
 'G3_TXN1||SATA21_TXN': CDS_PINID='\g3_txn1||sata21_txn\';
NET_NAME
'GMI_CPU1_G3_CPU0_G1_TX_DN<15>'
 '@T6G_MB_LIB.T6G(SCH_1):GMI_CPU1_G3_CPU0_G1_TX_DN'<15>:
 C_SIGNAL='@t6g_mb_lib.t6g(sch_1):gmi_cpu1_g3_cpu0_g1_tx_dn(15)';
NODE_NAME     U25 U52
 '@T6G_MB_LIB.T6G(SCH_1):PAGE22_I208@PURE_QUANTA.GENOA_SP5(CHIPS)':
 'G1_RXN15': CDS_PINID='G1_RXN15';
NODE_NAME     U26 U24
 '@T6G_MB_LIB.T6G(SCH_1):PAGE50_I144@PURE_QUANTA.GENOA_SP5(CHIPS)':
 'G3_TXN0||SATA20_TXN': CDS_PINID='\g3_txn0||sata20_txn\';
NET_NAME
'GMI_CPU1_G3_CPU0_G1_TX_DN<1>'
 '@T6G_MB_LIB.T6G(SCH_1):GMI_CPU1_G3_CPU0_G1_TX_DN'<1>:
 C_SIGNAL='@t6g_mb_lib.t6g(sch_1):gmi_cpu1_g3_cpu0_g1_tx_dn(1)';
NODE_NAME     U25 T40
 '@T6G_MB_LIB.T6G(SCH_1):PAGE22_I208@PURE_QUANTA.GENOA_SP5(CHIPS)':
 'G1_RXN1': CDS_PINID='G1_RXN1';
NODE_NAME     U26 T36
 '@T6G_MB_LIB.T6G(SCH_1):PAGE50_I144@PURE_QUANTA.GENOA_SP5(CHIPS)':
 'G3_TXN14||SATA36_TXN': CDS_PINID='\g3_txn14||sata36_txn\';
NET_NAME
'GMI_CPU1_G3_CPU0_G1_TX_DN<2>'
 '@T6G_MB_LIB.T6G(SCH_1):GMI_CPU1_G3_CPU0_G1_TX_DN'<2>:
 C_SIGNAL='@t6g_mb_lib.t6g(sch_1):gmi_cpu1_g3_cpu0_g1_tx_dn(2)';
NODE_NAME     U25 P40
 '@T6G_MB_LIB.T6G(SCH_1):PAGE22_I208@PURE_QUANTA.GENOA_SP5(CHIPS)':
 'G1_RXN2': CDS_PINID='G1_RXN2';
NODE_NAME     U26 P36
 '@T6G_MB_LIB.T6G(SCH_1):PAGE50_I144@PURE_QUANTA.GENOA_SP5(CHIPS)':
 'G3_TXN13||SATA35_TXN': CDS_PINID='\g3_txn13||sata35_txn\';
NET_NAME
'GMI_CPU1_G3_CPU0_G1_TX_DN<3>'
 '@T6G_MB_LIB.T6G(SCH_1):GMI_CPU1_G3_CPU0_G1_TX_DN'<3>:
 C_SIGNAL='@t6g_mb_lib.t6g(sch_1):gmi_cpu1_g3_cpu0_g1_tx_dn(3)';
NODE_NAME     U25 U43
 '@T6G_MB_LIB.T6G(SCH_1):PAGE22_I208@PURE_QUANTA.GENOA_SP5(CHIPS)':
 'G1_RXN3': CDS_PINID='G1_RXN3';
NODE_NAME     U26 U33
 '@T6G_MB_LIB.T6G(SCH_1):PAGE50_I144@PURE_QUANTA.GENOA_SP5(CHIPS)':
 'G3_TXN12||SATA34_TXN': CDS_PINID='\g3_txn12||sata34_txn\';
NET_NAME
'GMI_CPU1_G3_CPU0_G1_TX_DN<4>'
 '@T6G_MB_LIB.T6G(SCH_1):GMI_CPU1_G3_CPU0_G1_TX_DN'<4>:
 C_SIGNAL='@t6g_mb_lib.t6g(sch_1):gmi_cpu1_g3_cpu0_g1_tx_dn(4)';
NODE_NAME     U25 N43
 '@T6G_MB_LIB.T6G(SCH_1):PAGE22_I208@PURE_QUANTA.GENOA_SP5(CHIPS)':
 'G1_RXN4': CDS_PINID='G1_RXN4';
NODE_NAME     U26 N33
 '@T6G_MB_LIB.T6G(SCH_1):PAGE50_I144@PURE_QUANTA.GENOA_SP5(CHIPS)':
 'G3_TXN11||SATA33_TXN': CDS_PINID='\g3_txn11||sata33_txn\';
NET_NAME
'GMI_CPU1_G3_CPU0_G1_TX_DN<5>'
 '@T6G_MB_LIB.T6G(SCH_1):GMI_CPU1_G3_CPU0_G1_TX_DN'<5>:
 C_SIGNAL='@t6g_mb_lib.t6g(sch_1):gmi_cpu1_g3_cpu0_g1_tx_dn(5)';
NODE_NAME     U25 R43
 '@T6G_MB_LIB.T6G(SCH_1):PAGE22_I208@PURE_QUANTA.GENOA_SP5(CHIPS)':
 'G1_RXN5': CDS_PINID='G1_RXN5';
NODE_NAME     U26 R33
 '@T6G_MB_LIB.T6G(SCH_1):PAGE50_I144@PURE_QUANTA.GENOA_SP5(CHIPS)':
 'G3_TXN10||SATA32_TXN': CDS_PINID='\g3_txn10||sata32_txn\';
NET_NAME
'GMI_CPU1_G3_CPU0_G1_TX_DN<6>'
 '@T6G_MB_LIB.T6G(SCH_1):GMI_CPU1_G3_CPU0_G1_TX_DN'<6>:
 C_SIGNAL='@t6g_mb_lib.t6g(sch_1):gmi_cpu1_g3_cpu0_g1_tx_dn(6)';
NODE_NAME     U25 U46
 '@T6G_MB_LIB.T6G(SCH_1):PAGE22_I208@PURE_QUANTA.GENOA_SP5(CHIPS)':
 'G1_RXN6': CDS_PINID='G1_RXN6';
NODE_NAME     U26 U30
 '@T6G_MB_LIB.T6G(SCH_1):PAGE50_I144@PURE_QUANTA.GENOA_SP5(CHIPS)':
 'G3_TXN9||SATA31_TXN': CDS_PINID='\g3_txn9||sata31_txn\';
NET_NAME
'GMI_CPU1_G3_CPU0_G1_TX_DN<7>'
 '@T6G_MB_LIB.T6G(SCH_1):GMI_CPU1_G3_CPU0_G1_TX_DN'<7>:
 C_SIGNAL='@t6g_mb_lib.t6g(sch_1):gmi_cpu1_g3_cpu0_g1_tx_dn(7)';
NODE_NAME     U25 N46
 '@T6G_MB_LIB.T6G(SCH_1):PAGE22_I208@PURE_QUANTA.GENOA_SP5(CHIPS)':
 'G1_RXN7': CDS_PINID='G1_RXN7';
NODE_NAME     U26 N30
 '@T6G_MB_LIB.T6G(SCH_1):PAGE50_I144@PURE_QUANTA.GENOA_SP5(CHIPS)':
 'G3_TXN8||SATA30_TXN': CDS_PINID='\g3_txn8||sata30_txn\';
NET_NAME
'GMI_CPU1_G3_CPU0_G1_TX_DN<8>'
 '@T6G_MB_LIB.T6G(SCH_1):GMI_CPU1_G3_CPU0_G1_TX_DN'<8>:
 C_SIGNAL='@t6g_mb_lib.t6g(sch_1):gmi_cpu1_g3_cpu0_g1_tx_dn(8)';
NODE_NAME     U25 R46
 '@T6G_MB_LIB.T6G(SCH_1):PAGE22_I208@PURE_QUANTA.GENOA_SP5(CHIPS)':
 'G1_RXN8': CDS_PINID='G1_RXN8';
NODE_NAME     U26 R30
 '@T6G_MB_LIB.T6G(SCH_1):PAGE50_I144@PURE_QUANTA.GENOA_SP5(CHIPS)':
 'G3_TXN7||SATA27_TXN': CDS_PINID='\g3_txn7||sata27_txn\';
NET_NAME
'GMI_CPU1_G3_CPU0_G1_TX_DN<9>'
 '@T6G_MB_LIB.T6G(SCH_1):GMI_CPU1_G3_CPU0_G1_TX_DN'<9>:
 C_SIGNAL='@t6g_mb_lib.t6g(sch_1):gmi_cpu1_g3_cpu0_g1_tx_dn(9)';
NODE_NAME     U25 W49
 '@T6G_MB_LIB.T6G(SCH_1):PAGE22_I208@PURE_QUANTA.GENOA_SP5(CHIPS)':
 'G1_RXN9': CDS_PINID='G1_RXN9';
NODE_NAME     U26 W27
 '@T6G_MB_LIB.T6G(SCH_1):PAGE50_I144@PURE_QUANTA.GENOA_SP5(CHIPS)':
 'G3_TXN6||SATA26_TXN': CDS_PINID='\g3_txn6||sata26_txn\';
NET_NAME
'GMI_CPU1_G3_CPU0_G1_TX_DP<0>'
 '@T6G_MB_LIB.T6G(SCH_1):GMI_CPU1_G3_CPU0_G1_TX_DP'<0>:
 C_SIGNAL='@t6g_mb_lib.t6g(sch_1):gmi_cpu1_g3_cpu0_g1_tx_dp(0)';
NODE_NAME     U25 V41
 '@T6G_MB_LIB.T6G(SCH_1):PAGE22_I208@PURE_QUANTA.GENOA_SP5(CHIPS)':
 'G1_RXP0': CDS_PINID='G1_RXP0';
NODE_NAME     U26 V35
 '@T6G_MB_LIB.T6G(SCH_1):PAGE50_I144@PURE_QUANTA.GENOA_SP5(CHIPS)':
 'G3_TXP15||SATA37_TXP': CDS_PINID='\g3_txp15||sata37_txp\';
NET_NAME
'GMI_CPU1_G3_CPU0_G1_TX_DP<10>'
 '@T6G_MB_LIB.T6G(SCH_1):GMI_CPU1_G3_CPU0_G1_TX_DP'<10>:
 C_SIGNAL='@t6g_mb_lib.t6g(sch_1):gmi_cpu1_g3_cpu0_g1_tx_dp(10)';
NODE_NAME     U25 N50
 '@T6G_MB_LIB.T6G(SCH_1):PAGE22_I208@PURE_QUANTA.GENOA_SP5(CHIPS)':
 'G1_RXP10': CDS_PINID='G1_RXP10';
NODE_NAME     U26 N26
 '@T6G_MB_LIB.T6G(SCH_1):PAGE50_I144@PURE_QUANTA.GENOA_SP5(CHIPS)':
 'G3_TXP5||SATA25_TXP': CDS_PINID='\g3_txp5||sata25_txp\';
NET_NAME
'GMI_CPU1_G3_CPU0_G1_TX_DP<11>'
 '@T6G_MB_LIB.T6G(SCH_1):GMI_CPU1_G3_CPU0_G1_TX_DP'<11>:
 C_SIGNAL='@t6g_mb_lib.t6g(sch_1):gmi_cpu1_g3_cpu0_g1_tx_dp(11)';
NODE_NAME     U25 R50
 '@T6G_MB_LIB.T6G(SCH_1):PAGE22_I208@PURE_QUANTA.GENOA_SP5(CHIPS)':
 'G1_RXP11': CDS_PINID='G1_RXP11';
NODE_NAME     U26 R26
 '@T6G_MB_LIB.T6G(SCH_1):PAGE50_I144@PURE_QUANTA.GENOA_SP5(CHIPS)':
 'G3_TXP4||SATA24_TXP': CDS_PINID='\g3_txp4||sata24_txp\';
NET_NAME
'GMI_CPU1_G3_CPU0_G1_TX_DP<12>'
 '@T6G_MB_LIB.T6G(SCH_1):GMI_CPU1_G3_CPU0_G1_TX_DP'<12>:
 C_SIGNAL='@t6g_mb_lib.t6g(sch_1):gmi_cpu1_g3_cpu0_g1_tx_dp(12)';
NODE_NAME     U25 U50
 '@T6G_MB_LIB.T6G(SCH_1):PAGE22_I208@PURE_QUANTA.GENOA_SP5(CHIPS)':
 'G1_RXP12': CDS_PINID='G1_RXP12';
NODE_NAME     U26 U26
 '@T6G_MB_LIB.T6G(SCH_1):PAGE50_I144@PURE_QUANTA.GENOA_SP5(CHIPS)':
 'G3_TXP3||SATA23_TXP': CDS_PINID='\g3_txp3||sata23_txp\';
NET_NAME
'GMI_CPU1_G3_CPU0_G1_TX_DP<13>'
 '@T6G_MB_LIB.T6G(SCH_1):GMI_CPU1_G3_CPU0_G1_TX_DP'<13>:
 C_SIGNAL='@t6g_mb_lib.t6g(sch_1):gmi_cpu1_g3_cpu0_g1_tx_dp(13)';
NODE_NAME     U25 W53
 '@T6G_MB_LIB.T6G(SCH_1):PAGE22_I208@PURE_QUANTA.GENOA_SP5(CHIPS)':
 'G1_RXP13': CDS_PINID='G1_RXP13';
NODE_NAME     U26 W23
 '@T6G_MB_LIB.T6G(SCH_1):PAGE50_I144@PURE_QUANTA.GENOA_SP5(CHIPS)':
 'G3_TXP2||SATA22_TXP': CDS_PINID='\g3_txp2||sata22_txp\';
NET_NAME
'GMI_CPU1_G3_CPU0_G1_TX_DP<14>'
 '@T6G_MB_LIB.T6G(SCH_1):GMI_CPU1_G3_CPU0_G1_TX_DP'<14>:
 C_SIGNAL='@t6g_mb_lib.t6g(sch_1):gmi_cpu1_g3_cpu0_g1_tx_dp(14)';
NODE_NAME     U25 R53
 '@T6G_MB_LIB.T6G(SCH_1):PAGE22_I208@PURE_QUANTA.GENOA_SP5(CHIPS)':
 'G1_RXP14': CDS_PINID='G1_RXP14';
NODE_NAME     U26 R23
 '@T6G_MB_LIB.T6G(SCH_1):PAGE50_I144@PURE_QUANTA.GENOA_SP5(CHIPS)':
 'G3_TXP1||SATA21_TXP': CDS_PINID='\g3_txp1||sata21_txp\';
NET_NAME
'GMI_CPU1_G3_CPU0_G1_TX_DP<15>'
 '@T6G_MB_LIB.T6G(SCH_1):GMI_CPU1_G3_CPU0_G1_TX_DP'<15>:
 C_SIGNAL='@t6g_mb_lib.t6g(sch_1):gmi_cpu1_g3_cpu0_g1_tx_dp(15)';
NODE_NAME     U25 U53
 '@T6G_MB_LIB.T6G(SCH_1):PAGE22_I208@PURE_QUANTA.GENOA_SP5(CHIPS)':
 'G1_RXP15': CDS_PINID='G1_RXP15';
NODE_NAME     U26 U23
 '@T6G_MB_LIB.T6G(SCH_1):PAGE50_I144@PURE_QUANTA.GENOA_SP5(CHIPS)':
 'G3_TXP0||SATA20_TXP': CDS_PINID='\g3_txp0||sata20_txp\';
NET_NAME
'GMI_CPU1_G3_CPU0_G1_TX_DP<1>'
 '@T6G_MB_LIB.T6G(SCH_1):GMI_CPU1_G3_CPU0_G1_TX_DP'<1>:
 C_SIGNAL='@t6g_mb_lib.t6g(sch_1):gmi_cpu1_g3_cpu0_g1_tx_dp(1)';
NODE_NAME     U25 T41
 '@T6G_MB_LIB.T6G(SCH_1):PAGE22_I208@PURE_QUANTA.GENOA_SP5(CHIPS)':
 'G1_RXP1': CDS_PINID='G1_RXP1';
NODE_NAME     U26 T35
 '@T6G_MB_LIB.T6G(SCH_1):PAGE50_I144@PURE_QUANTA.GENOA_SP5(CHIPS)':
 'G3_TXP14||SATA36_TXP': CDS_PINID='\g3_txp14||sata36_txp\';
NET_NAME
'GMI_CPU1_G3_CPU0_G1_TX_DP<2>'
 '@T6G_MB_LIB.T6G(SCH_1):GMI_CPU1_G3_CPU0_G1_TX_DP'<2>:
 C_SIGNAL='@t6g_mb_lib.t6g(sch_1):gmi_cpu1_g3_cpu0_g1_tx_dp(2)';
NODE_NAME     U25 P41
 '@T6G_MB_LIB.T6G(SCH_1):PAGE22_I208@PURE_QUANTA.GENOA_SP5(CHIPS)':
 'G1_RXP2': CDS_PINID='G1_RXP2';
NODE_NAME     U26 P35
 '@T6G_MB_LIB.T6G(SCH_1):PAGE50_I144@PURE_QUANTA.GENOA_SP5(CHIPS)':
 'G3_TXP13||SATA35_TXP': CDS_PINID='\g3_txp13||sata35_txp\';
NET_NAME
'GMI_CPU1_G3_CPU0_G1_TX_DP<3>'
 '@T6G_MB_LIB.T6G(SCH_1):GMI_CPU1_G3_CPU0_G1_TX_DP'<3>:
 C_SIGNAL='@t6g_mb_lib.t6g(sch_1):gmi_cpu1_g3_cpu0_g1_tx_dp(3)';
NODE_NAME     U25 U44
 '@T6G_MB_LIB.T6G(SCH_1):PAGE22_I208@PURE_QUANTA.GENOA_SP5(CHIPS)':
 'G1_RXP3': CDS_PINID='G1_RXP3';
NODE_NAME     U26 U32
 '@T6G_MB_LIB.T6G(SCH_1):PAGE50_I144@PURE_QUANTA.GENOA_SP5(CHIPS)':
 'G3_TXP12||SATA34_TXP': CDS_PINID='\g3_txp12||sata34_txp\';
NET_NAME
'GMI_CPU1_G3_CPU0_G1_TX_DP<4>'
 '@T6G_MB_LIB.T6G(SCH_1):GMI_CPU1_G3_CPU0_G1_TX_DP'<4>:
 C_SIGNAL='@t6g_mb_lib.t6g(sch_1):gmi_cpu1_g3_cpu0_g1_tx_dp(4)';
NODE_NAME     U25 N44
 '@T6G_MB_LIB.T6G(SCH_1):PAGE22_I208@PURE_QUANTA.GENOA_SP5(CHIPS)':
 'G1_RXP4': CDS_PINID='G1_RXP4';
NODE_NAME     U26 N32
 '@T6G_MB_LIB.T6G(SCH_1):PAGE50_I144@PURE_QUANTA.GENOA_SP5(CHIPS)':
 'G3_TXP11||SATA33_TXP': CDS_PINID='\g3_txp11||sata33_txp\';
NET_NAME
'GMI_CPU1_G3_CPU0_G1_TX_DP<5>'
 '@T6G_MB_LIB.T6G(SCH_1):GMI_CPU1_G3_CPU0_G1_TX_DP'<5>:
 C_SIGNAL='@t6g_mb_lib.t6g(sch_1):gmi_cpu1_g3_cpu0_g1_tx_dp(5)';
NODE_NAME     U25 R44
 '@T6G_MB_LIB.T6G(SCH_1):PAGE22_I208@PURE_QUANTA.GENOA_SP5(CHIPS)':
 'G1_RXP5': CDS_PINID='G1_RXP5';
NODE_NAME     U26 R32
 '@T6G_MB_LIB.T6G(SCH_1):PAGE50_I144@PURE_QUANTA.GENOA_SP5(CHIPS)':
 'G3_TXP10||SATA32_TXP': CDS_PINID='\g3_txp10||sata32_txp\';
NET_NAME
'GMI_CPU1_G3_CPU0_G1_TX_DP<6>'
 '@T6G_MB_LIB.T6G(SCH_1):GMI_CPU1_G3_CPU0_G1_TX_DP'<6>:
 C_SIGNAL='@t6g_mb_lib.t6g(sch_1):gmi_cpu1_g3_cpu0_g1_tx_dp(6)';
NODE_NAME     U25 U47
 '@T6G_MB_LIB.T6G(SCH_1):PAGE22_I208@PURE_QUANTA.GENOA_SP5(CHIPS)':
 'G1_RXP6': CDS_PINID='G1_RXP6';
NODE_NAME     U26 U29
 '@T6G_MB_LIB.T6G(SCH_1):PAGE50_I144@PURE_QUANTA.GENOA_SP5(CHIPS)':
 'G3_TXP9||SATA31_TXP': CDS_PINID='\g3_txp9||sata31_txp\';
NET_NAME
'GMI_CPU1_G3_CPU0_G1_TX_DP<7>'
 '@T6G_MB_LIB.T6G(SCH_1):GMI_CPU1_G3_CPU0_G1_TX_DP'<7>:
 C_SIGNAL='@t6g_mb_lib.t6g(sch_1):gmi_cpu1_g3_cpu0_g1_tx_dp(7)';
NODE_NAME     U25 N47
 '@T6G_MB_LIB.T6G(SCH_1):PAGE22_I208@PURE_QUANTA.GENOA_SP5(CHIPS)':
 'G1_RXP7': CDS_PINID='G1_RXP7';
NODE_NAME     U26 N29
 '@T6G_MB_LIB.T6G(SCH_1):PAGE50_I144@PURE_QUANTA.GENOA_SP5(CHIPS)':
 'G3_TXP8||SATA30_TXP': CDS_PINID='\g3_txp8||sata30_txp\';
NET_NAME
'GMI_CPU1_G3_CPU0_G1_TX_DP<8>'
 '@T6G_MB_LIB.T6G(SCH_1):GMI_CPU1_G3_CPU0_G1_TX_DP'<8>:
 C_SIGNAL='@t6g_mb_lib.t6g(sch_1):gmi_cpu1_g3_cpu0_g1_tx_dp(8)';
NODE_NAME     U25 R47
 '@T6G_MB_LIB.T6G(SCH_1):PAGE22_I208@PURE_QUANTA.GENOA_SP5(CHIPS)':
 'G1_RXP8': CDS_PINID='G1_RXP8';
NODE_NAME     U26 R29
 '@T6G_MB_LIB.T6G(SCH_1):PAGE50_I144@PURE_QUANTA.GENOA_SP5(CHIPS)':
 'G3_TXP7||SATA27_TXP': CDS_PINID='\g3_txp7||sata27_txp\';
NET_NAME
'GMI_CPU1_G3_CPU0_G1_TX_DP<9>'
 '@T6G_MB_LIB.T6G(SCH_1):GMI_CPU1_G3_CPU0_G1_TX_DP'<9>:
 C_SIGNAL='@t6g_mb_lib.t6g(sch_1):gmi_cpu1_g3_cpu0_g1_tx_dp(9)';
NODE_NAME     U25 W50
 '@T6G_MB_LIB.T6G(SCH_1):PAGE22_I208@PURE_QUANTA.GENOA_SP5(CHIPS)':
 'G1_RXP9': CDS_PINID='G1_RXP9';
NODE_NAME     U26 W26
 '@T6G_MB_LIB.T6G(SCH_1):PAGE50_I144@PURE_QUANTA.GENOA_SP5(CHIPS)':
 'G3_TXP6||SATA26_TXP': CDS_PINID='\g3_txp6||sata26_txp\';
NET_NAME
'GND'
 '@T6G_MB_LIB.T6G(SCH_1):GND':
 C_SIGNAL='@t6g_mb_lib.t6g(sch_1):gnd',
 CDS_GLOBAL_NET='TRUE';
NODE_NAME     C212 2
 '@T6G_MB_LIB.T6G(SCH_1):PAGE27_I295@PURE_QUANTA.Q_CAP(CHIPS)':
 'B': CDS_PINID='B';
NODE_NAME     C211 2
 '@T6G_MB_LIB.T6G(SCH_1):PAGE27_I297@PURE_QUANTA.Q_CAP(CHIPS)':
 'B': CDS_PINID='B';
NODE_NAME     C210 2
 '@T6G_MB_LIB.T6G(SCH_1):PAGE27_I302@PURE_QUANTA.Q_CAP(CHIPS)':
 'B': CDS_PINID='B';
NODE_NAME     C209 2
 '@T6G_MB_LIB.T6G(SCH_1):PAGE27_I303@PURE_QUANTA.Q_CAP(CHIPS)':
 'B': CDS_PINID='B';
NODE_NAME     C208 2
 '@T6G_MB_LIB.T6G(SCH_1):PAGE27_I306@PURE_QUANTA.Q_CAP(CHIPS)':
 'B': CDS_PINID='B';
NODE_NAME     C207 2
 '@T6G_MB_LIB.T6G(SCH_1):PAGE27_I307@PURE_QUANTA.Q_CAP(CHIPS)':
 'B': CDS_PINID='B';
NODE_NAME     R393 2
 '@T6G_MB_LIB.T6G(SCH_1):PAGE27_I396@PURE_QUANTA.Q_RES(CHIPS)':
 'B': CDS_PINID='B';
NODE_NAME     R394 2
 '@T6G_MB_LIB.T6G(SCH_1):PAGE27_I397@PURE_QUANTA.Q_RES(CHIPS)':
 'B': CDS_PINID='B';
NODE_NAME     U3 3
 '@T6G_MB_LIB.T6G(SCH_1):PAGE29_I373@PURE_QUANTA.SN74LVC1G07DBVR(CHIPS)':
 'GND': CDS_PINID='GND';
NODE_NAME     C30 2
 '@T6G_MB_LIB.T6G(SCH_1):PAGE29_I379@PURE_QUANTA.Q_CAP(CHIPS)':
 'B': CDS_PINID='B';
NODE_NAME     U25 A3
 '@T6G_MB_LIB.T6G(SCH_1):PAGE31_I19@PURE_QUANTA.GENOA_SP5(CHIPS)':
 'VSS_A3': CDS_PINID='VSS_A3';
NODE_NAME     U25 A9
 '@T6G_MB_LIB.T6G(SCH_1):PAGE31_I19@PURE_QUANTA.GENOA_SP5(CHIPS)':
 'VSS_A9': CDS_PINID='VSS_A9';
NODE_NAME     U25 A15
 '@T6G_MB_LIB.T6G(SCH_1):PAGE31_I19@PURE_QUANTA.GENOA_SP5(CHIPS)':
 'VSS_A15': CDS_PINID='VSS_A15';
NODE_NAME     U25 A21
 '@T6G_MB_LIB.T6G(SCH_1):PAGE31_I19@PURE_QUANTA.GENOA_SP5(CHIPS)':
 'VSS_A21': CDS_PINID='VSS_A21';
NODE_NAME     U25 A27
 '@T6G_MB_LIB.T6G(SCH_1):PAGE31_I19@PURE_QUANTA.GENOA_SP5(CHIPS)':
 'VSS_A27': CDS_PINID='VSS_A27';
NODE_NAME     U25 A43
 '@T6G_MB_LIB.T6G(SCH_1):PAGE31_I19@PURE_QUANTA.GENOA_SP5(CHIPS)':
 'VSS_A43': CDS_PINID='VSS_A43';
NODE_NAME     U25 A44
 '@T6G_MB_LIB.T6G(SCH_1):PAGE31_I19@PURE_QUANTA.GENOA_SP5(CHIPS)':
 'VSS_A44': CDS_PINID='VSS_A44';
NODE_NAME     U25 A47
 '@T6G_MB_LIB.T6G(SCH_1):PAGE31_I19@PURE_QUANTA.GENOA_SP5(CHIPS)':
 'VSS_A47': CDS_PINID='VSS_A47';
NODE_NAME     U25 A49
 '@T6G_MB_LIB.T6G(SCH_1):PAGE31_I19@PURE_QUANTA.GENOA_SP5(CHIPS)':
 'VSS_A49': CDS_PINID='VSS_A49';
NODE_NAME     U25 A53
 '@T6G_MB_LIB.T6G(SCH_1):PAGE31_I19@PURE_QUANTA.GENOA_SP5(CHIPS)':
 'VSS_A53': CDS_PINID='VSS_A53';
NODE_NAME     U25 A61
 '@T6G_MB_LIB.T6G(SCH_1):PAGE31_I19@PURE_QUANTA.GENOA_SP5(CHIPS)':
 'VSS_A61': CDS_PINID='VSS_A61';
NODE_NAME     U25 A67
 '@T6G_MB_LIB.T6G(SCH_1):PAGE31_I19@PURE_QUANTA.GENOA_SP5(CHIPS)':
 'VSS_A67': CDS_PINID='VSS_A67';
NODE_NAME     U25 A72
 '@T6G_MB_LIB.T6G(SCH_1):PAGE31_I19@PURE_QUANTA.GENOA_SP5(CHIPS)':
 'VSS_A72': CDS_PINID='VSS_A72';
NODE_NAME     U25 A73
 '@T6G_MB_LIB.T6G(SCH_1):PAGE31_I19@PURE_QUANTA.GENOA_SP5(CHIPS)':
 'VSS_A73': CDS_PINID='VSS_A73';
NODE_NAME     U25 B7
 '@T6G_MB_LIB.T6G(SCH_1):PAGE31_I19@PURE_QUANTA.GENOA_SP5(CHIPS)':
 'VSS_B7': CDS_PINID='VSS_B7';
NODE_NAME     U25 B8
 '@T6G_MB_LIB.T6G(SCH_1):PAGE31_I19@PURE_QUANTA.GENOA_SP5(CHIPS)':
 'VSS_B8': CDS_PINID='VSS_B8';
NODE_NAME     U25 B10
 '@T6G_MB_LIB.T6G(SCH_1):PAGE31_I19@PURE_QUANTA.GENOA_SP5(CHIPS)':
 'VSS_B10': CDS_PINID='VSS_B10';
NODE_NAME     U25 B11
 '@T6G_MB_LIB.T6G(SCH_1):PAGE31_I19@PURE_QUANTA.GENOA_SP5(CHIPS)':
 'VSS_B11': CDS_PINID='VSS_B11';
NODE_NAME     U25 B13
 '@T6G_MB_LIB.T6G(SCH_1):PAGE31_I19@PURE_QUANTA.GENOA_SP5(CHIPS)':
 'VSS_B13': CDS_PINID='VSS_B13';
NODE_NAME     U25 B18
 '@T6G_MB_LIB.T6G(SCH_1):PAGE31_I19@PURE_QUANTA.GENOA_SP5(CHIPS)':
 'VSS_B18': CDS_PINID='VSS_B18';
NODE_NAME     U25 B24
 '@T6G_MB_LIB.T6G(SCH_1):PAGE31_I19@PURE_QUANTA.GENOA_SP5(CHIPS)':
 'VSS_B24': CDS_PINID='VSS_B24';
NODE_NAME     U25 B27
 '@T6G_MB_LIB.T6G(SCH_1):PAGE31_I19@PURE_QUANTA.GENOA_SP5(CHIPS)':
 'VSS_B27': CDS_PINID='VSS_B27';
NODE_NAME     U25 B30
 '@T6G_MB_LIB.T6G(SCH_1):PAGE31_I19@PURE_QUANTA.GENOA_SP5(CHIPS)':
 'VSS_B30': CDS_PINID='VSS_B30';
NODE_NAME     U25 B33
 '@T6G_MB_LIB.T6G(SCH_1):PAGE31_I19@PURE_QUANTA.GENOA_SP5(CHIPS)':
 'VSS_B33': CDS_PINID='VSS_B33';
NODE_NAME     U25 B37
 '@T6G_MB_LIB.T6G(SCH_1):PAGE31_I19@PURE_QUANTA.GENOA_SP5(CHIPS)':
 'VSS_B37': CDS_PINID='VSS_B37';
NODE_NAME     U25 B39
 '@T6G_MB_LIB.T6G(SCH_1):PAGE31_I19@PURE_QUANTA.GENOA_SP5(CHIPS)':
 'VSS_B39': CDS_PINID='VSS_B39';
NODE_NAME     U25 B43
 '@T6G_MB_LIB.T6G(SCH_1):PAGE31_I19@PURE_QUANTA.GENOA_SP5(CHIPS)':
 'VSS_B43': CDS_PINID='VSS_B43';
NODE_NAME     U25 B46
 '@T6G_MB_LIB.T6G(SCH_1):PAGE31_I19@PURE_QUANTA.GENOA_SP5(CHIPS)':
 'VSS_B46': CDS_PINID='VSS_B46';
NODE_NAME     U25 B49
 '@T6G_MB_LIB.T6G(SCH_1):PAGE31_I19@PURE_QUANTA.GENOA_SP5(CHIPS)':
 'VSS_B49': CDS_PINID='VSS_B49';
NODE_NAME     U25 B52
 '@T6G_MB_LIB.T6G(SCH_1):PAGE31_I19@PURE_QUANTA.GENOA_SP5(CHIPS)':
 'VSS_B52': CDS_PINID='VSS_B52';
NODE_NAME     U25 B55
 '@T6G_MB_LIB.T6G(SCH_1):PAGE31_I19@PURE_QUANTA.GENOA_SP5(CHIPS)':
 'VSS_B55': CDS_PINID='VSS_B55';
NODE_NAME     U25 B59
 '@T6G_MB_LIB.T6G(SCH_1):PAGE31_I19@PURE_QUANTA.GENOA_SP5(CHIPS)':
 'VSS_B59': CDS_PINID='VSS_B59';
NODE_NAME     U25 B62
 '@T6G_MB_LIB.T6G(SCH_1):PAGE31_I19@PURE_QUANTA.GENOA_SP5(CHIPS)':
 'VSS_B62': CDS_PINID='VSS_B62';
NODE_NAME     U25 B65
 '@T6G_MB_LIB.T6G(SCH_1):PAGE31_I19@PURE_QUANTA.GENOA_SP5(CHIPS)':
 'VSS_B65': CDS_PINID='VSS_B65';
NODE_NAME     U25 B68
 '@T6G_MB_LIB.T6G(SCH_1):PAGE31_I19@PURE_QUANTA.GENOA_SP5(CHIPS)':
 'VSS_B68': CDS_PINID='VSS_B68';
NODE_NAME     U25 B70
 '@T6G_MB_LIB.T6G(SCH_1):PAGE31_I19@PURE_QUANTA.GENOA_SP5(CHIPS)':
 'VSS_B70': CDS_PINID='VSS_B70';
NODE_NAME     U25 C1
 '@T6G_MB_LIB.T6G(SCH_1):PAGE31_I19@PURE_QUANTA.GENOA_SP5(CHIPS)':
 'VSS_C1': CDS_PINID='VSS_C1';
NODE_NAME     U25 C5
 '@T6G_MB_LIB.T6G(SCH_1):PAGE31_I19@PURE_QUANTA.GENOA_SP5(CHIPS)':
 'VSS_C5': CDS_PINID='VSS_C5';
NODE_NAME     U25 C8
 '@T6G_MB_LIB.T6G(SCH_1):PAGE31_I19@PURE_QUANTA.GENOA_SP5(CHIPS)':
 'VSS_C8': CDS_PINID='VSS_C8';
NODE_NAME     U25 C10
 '@T6G_MB_LIB.T6G(SCH_1):PAGE31_I19@PURE_QUANTA.GENOA_SP5(CHIPS)':
 'VSS_C10': CDS_PINID='VSS_C10';
NODE_NAME     U25 C11
 '@T6G_MB_LIB.T6G(SCH_1):PAGE31_I19@PURE_QUANTA.GENOA_SP5(CHIPS)':
 'VSS_C11': CDS_PINID='VSS_C11';
NODE_NAME     U25 C13
 '@T6G_MB_LIB.T6G(SCH_1):PAGE31_I19@PURE_QUANTA.GENOA_SP5(CHIPS)':
 'VSS_C13': CDS_PINID='VSS_C13';
NODE_NAME     U25 C15
 '@T6G_MB_LIB.T6G(SCH_1):PAGE31_I19@PURE_QUANTA.GENOA_SP5(CHIPS)':
 'VSS_C15': CDS_PINID='VSS_C15';
NODE_NAME     U25 C21
 '@T6G_MB_LIB.T6G(SCH_1):PAGE31_I19@PURE_QUANTA.GENOA_SP5(CHIPS)':
 'VSS_C21': CDS_PINID='VSS_C21';
NODE_NAME     U25 C24
 '@T6G_MB_LIB.T6G(SCH_1):PAGE31_I19@PURE_QUANTA.GENOA_SP5(CHIPS)':
 'VSS_C24': CDS_PINID='VSS_C24';
NODE_NAME     U25 C27
 '@T6G_MB_LIB.T6G(SCH_1):PAGE31_I19@PURE_QUANTA.GENOA_SP5(CHIPS)':
 'VSS_C27': CDS_PINID='VSS_C27';
NODE_NAME     U25 C30
 '@T6G_MB_LIB.T6G(SCH_1):PAGE31_I19@PURE_QUANTA.GENOA_SP5(CHIPS)':
 'VSS_C30': CDS_PINID='VSS_C30';
NODE_NAME     U25 C36
 '@T6G_MB_LIB.T6G(SCH_1):PAGE31_I19@PURE_QUANTA.GENOA_SP5(CHIPS)':
 'VSS_C36': CDS_PINID='VSS_C36';
NODE_NAME     U25 C40
 '@T6G_MB_LIB.T6G(SCH_1):PAGE31_I19@PURE_QUANTA.GENOA_SP5(CHIPS)':
 'VSS_C40': CDS_PINID='VSS_C40';
NODE_NAME     U25 C43
 '@T6G_MB_LIB.T6G(SCH_1):PAGE31_I19@PURE_QUANTA.GENOA_SP5(CHIPS)':
 'VSS_C43': CDS_PINID='VSS_C43';
NODE_NAME     U25 C46
 '@T6G_MB_LIB.T6G(SCH_1):PAGE31_I19@PURE_QUANTA.GENOA_SP5(CHIPS)':
 'VSS_C46': CDS_PINID='VSS_C46';
NODE_NAME     U25 C49
 '@T6G_MB_LIB.T6G(SCH_1):PAGE31_I19@PURE_QUANTA.GENOA_SP5(CHIPS)':
 'VSS_C49': CDS_PINID='VSS_C49';
NODE_NAME     U25 C52
 '@T6G_MB_LIB.T6G(SCH_1):PAGE31_I19@PURE_QUANTA.GENOA_SP5(CHIPS)':
 'VSS_C52': CDS_PINID='VSS_C52';
NODE_NAME     U25 C55
 '@T6G_MB_LIB.T6G(SCH_1):PAGE31_I19@PURE_QUANTA.GENOA_SP5(CHIPS)':
 'VSS_C55': CDS_PINID='VSS_C55';
NODE_NAME     U25 C56
 '@T6G_MB_LIB.T6G(SCH_1):PAGE31_I19@PURE_QUANTA.GENOA_SP5(CHIPS)':
 'VSS_C56': CDS_PINID='VSS_C56';
NODE_NAME     U25 C57
 '@T6G_MB_LIB.T6G(SCH_1):PAGE31_I19@PURE_QUANTA.GENOA_SP5(CHIPS)':
 'VSS_C57': CDS_PINID='VSS_C57';
NODE_NAME     U25 C61
 '@T6G_MB_LIB.T6G(SCH_1):PAGE31_I19@PURE_QUANTA.GENOA_SP5(CHIPS)':
 'VSS_C61': CDS_PINID='VSS_C61';
NODE_NAME     U25 C64
 '@T6G_MB_LIB.T6G(SCH_1):PAGE31_I19@PURE_QUANTA.GENOA_SP5(CHIPS)':
 'VSS_C64': CDS_PINID='VSS_C64';
NODE_NAME     U25 C67
 '@T6G_MB_LIB.T6G(SCH_1):PAGE31_I19@PURE_QUANTA.GENOA_SP5(CHIPS)':
 'VSS_C67': CDS_PINID='VSS_C67';
NODE_NAME     U25 C69
 '@T6G_MB_LIB.T6G(SCH_1):PAGE31_I19@PURE_QUANTA.GENOA_SP5(CHIPS)':
 'VSS_C69': CDS_PINID='VSS_C69';
NODE_NAME     U25 C71
 '@T6G_MB_LIB.T6G(SCH_1):PAGE31_I19@PURE_QUANTA.GENOA_SP5(CHIPS)':
 'VSS_C71': CDS_PINID='VSS_C71';
NODE_NAME     U25 C73
 '@T6G_MB_LIB.T6G(SCH_1):PAGE31_I19@PURE_QUANTA.GENOA_SP5(CHIPS)':
 'VSS_C73': CDS_PINID='VSS_C73';
NODE_NAME     U25 C75
 '@T6G_MB_LIB.T6G(SCH_1):PAGE31_I19@PURE_QUANTA.GENOA_SP5(CHIPS)':
 'VSS_C75': CDS_PINID='VSS_C75';
NODE_NAME     U25 D2
 '@T6G_MB_LIB.T6G(SCH_1):PAGE31_I19@PURE_QUANTA.GENOA_SP5(CHIPS)':
 'VSS_D2': CDS_PINID='VSS_D2';
NODE_NAME     U25 D3
 '@T6G_MB_LIB.T6G(SCH_1):PAGE31_I19@PURE_QUANTA.GENOA_SP5(CHIPS)':
 'VSS_D3': CDS_PINID='VSS_D3';
NODE_NAME     U25 D5
 '@T6G_MB_LIB.T6G(SCH_1):PAGE31_I19@PURE_QUANTA.GENOA_SP5(CHIPS)':
 'VSS_D5': CDS_PINID='VSS_D5';
NODE_NAME     U25 D6
 '@T6G_MB_LIB.T6G(SCH_1):PAGE31_I19@PURE_QUANTA.GENOA_SP5(CHIPS)':
 'VSS_D6': CDS_PINID='VSS_D6';
NODE_NAME     U25 D9
 '@T6G_MB_LIB.T6G(SCH_1):PAGE31_I19@PURE_QUANTA.GENOA_SP5(CHIPS)':
 'VSS_D9': CDS_PINID='VSS_D9';
NODE_NAME     U25 D10
 '@T6G_MB_LIB.T6G(SCH_1):PAGE31_I19@PURE_QUANTA.GENOA_SP5(CHIPS)':
 'VSS_D10': CDS_PINID='VSS_D10';
NODE_NAME     U25 D12
 '@T6G_MB_LIB.T6G(SCH_1):PAGE31_I19@PURE_QUANTA.GENOA_SP5(CHIPS)':
 'VSS_D12': CDS_PINID='VSS_D12';
NODE_NAME     U25 D13
 '@T6G_MB_LIB.T6G(SCH_1):PAGE31_I19@PURE_QUANTA.GENOA_SP5(CHIPS)':
 'VSS_D13': CDS_PINID='VSS_D13';
NODE_NAME     U25 D16
 '@T6G_MB_LIB.T6G(SCH_1):PAGE31_I19@PURE_QUANTA.GENOA_SP5(CHIPS)':
 'VSS_D16': CDS_PINID='VSS_D16';
NODE_NAME     U25 D17
 '@T6G_MB_LIB.T6G(SCH_1):PAGE31_I19@PURE_QUANTA.GENOA_SP5(CHIPS)':
 'VSS_D17': CDS_PINID='VSS_D17';
NODE_NAME     U25 D19
 '@T6G_MB_LIB.T6G(SCH_1):PAGE31_I19@PURE_QUANTA.GENOA_SP5(CHIPS)':
 'VSS_D19': CDS_PINID='VSS_D19';
NODE_NAME     U25 D20
 '@T6G_MB_LIB.T6G(SCH_1):PAGE31_I19@PURE_QUANTA.GENOA_SP5(CHIPS)':
 'VSS_D20': CDS_PINID='VSS_D20';
NODE_NAME     U25 D21
 '@T6G_MB_LIB.T6G(SCH_1):PAGE31_I19@PURE_QUANTA.GENOA_SP5(CHIPS)':
 'VSS_D21': CDS_PINID='VSS_D21';
NODE_NAME     U25 D24
 '@T6G_MB_LIB.T6G(SCH_1):PAGE31_I19@PURE_QUANTA.GENOA_SP5(CHIPS)':
 'VSS_D24': CDS_PINID='VSS_D24';
NODE_NAME     U25 D25
 '@T6G_MB_LIB.T6G(SCH_1):PAGE31_I19@PURE_QUANTA.GENOA_SP5(CHIPS)':
 'VSS_D25': CDS_PINID='VSS_D25';
NODE_NAME     U25 D26
 '@T6G_MB_LIB.T6G(SCH_1):PAGE31_I19@PURE_QUANTA.GENOA_SP5(CHIPS)':
 'VSS_D26': CDS_PINID='VSS_D26';
NODE_NAME     U25 D27
 '@T6G_MB_LIB.T6G(SCH_1):PAGE31_I19@PURE_QUANTA.GENOA_SP5(CHIPS)':
 'VSS_D27': CDS_PINID='VSS_D27';
NODE_NAME     U25 D28
 '@T6G_MB_LIB.T6G(SCH_1):PAGE31_I19@PURE_QUANTA.GENOA_SP5(CHIPS)':
 'VSS_D28': CDS_PINID='VSS_D28';
NODE_NAME     U25 D29
 '@T6G_MB_LIB.T6G(SCH_1):PAGE31_I19@PURE_QUANTA.GENOA_SP5(CHIPS)':
 'VSS_D29': CDS_PINID='VSS_D29';
NODE_NAME     U25 D30
 '@T6G_MB_LIB.T6G(SCH_1):PAGE31_I19@PURE_QUANTA.GENOA_SP5(CHIPS)':
 'VSS_D30': CDS_PINID='VSS_D30';
NODE_NAME     U25 D31
 '@T6G_MB_LIB.T6G(SCH_1):PAGE31_I19@PURE_QUANTA.GENOA_SP5(CHIPS)':
 'VSS_D31': CDS_PINID='VSS_D31';
NODE_NAME     U25 D35
 '@T6G_MB_LIB.T6G(SCH_1):PAGE31_I19@PURE_QUANTA.GENOA_SP5(CHIPS)':
 'VSS_D35': CDS_PINID='VSS_D35';
NODE_NAME     U25 D37
 '@T6G_MB_LIB.T6G(SCH_1):PAGE31_I19@PURE_QUANTA.GENOA_SP5(CHIPS)':
 'VSS_D37': CDS_PINID='VSS_D37';
NODE_NAME     U25 D39
 '@T6G_MB_LIB.T6G(SCH_1):PAGE31_I19@PURE_QUANTA.GENOA_SP5(CHIPS)':
 'VSS_D39': CDS_PINID='VSS_D39';
NODE_NAME     U25 D40
 '@T6G_MB_LIB.T6G(SCH_1):PAGE31_I19@PURE_QUANTA.GENOA_SP5(CHIPS)':
 'VSS_D40': CDS_PINID='VSS_D40';
NODE_NAME     U25 D41
 '@T6G_MB_LIB.T6G(SCH_1):PAGE31_I19@PURE_QUANTA.GENOA_SP5(CHIPS)':
 'VSS_D41': CDS_PINID='VSS_D41';
NODE_NAME     U25 D42
 '@T6G_MB_LIB.T6G(SCH_1):PAGE31_I19@PURE_QUANTA.GENOA_SP5(CHIPS)':
 'VSS_D42': CDS_PINID='VSS_D42';
NODE_NAME     U25 D43
 '@T6G_MB_LIB.T6G(SCH_1):PAGE31_I19@PURE_QUANTA.GENOA_SP5(CHIPS)':
 'VSS_D43': CDS_PINID='VSS_D43';
NODE_NAME     U25 D44
 '@T6G_MB_LIB.T6G(SCH_1):PAGE31_I19@PURE_QUANTA.GENOA_SP5(CHIPS)':
 'VSS_D44': CDS_PINID='VSS_D44';
NODE_NAME     U25 D45
 '@T6G_MB_LIB.T6G(SCH_1):PAGE31_I19@PURE_QUANTA.GENOA_SP5(CHIPS)':
 'VSS_D45': CDS_PINID='VSS_D45';
NODE_NAME     U25 D46
 '@T6G_MB_LIB.T6G(SCH_1):PAGE31_I19@PURE_QUANTA.GENOA_SP5(CHIPS)':
 'VSS_D46': CDS_PINID='VSS_D46';
NODE_NAME     U25 D47
 '@T6G_MB_LIB.T6G(SCH_1):PAGE31_I19@PURE_QUANTA.GENOA_SP5(CHIPS)':
 'VSS_D47': CDS_PINID='VSS_D47';
NODE_NAME     U25 D48
 '@T6G_MB_LIB.T6G(SCH_1):PAGE31_I19@PURE_QUANTA.GENOA_SP5(CHIPS)':
 'VSS_D48': CDS_PINID='VSS_D48';
NODE_NAME     U25 D49
 '@T6G_MB_LIB.T6G(SCH_1):PAGE31_I19@PURE_QUANTA.GENOA_SP5(CHIPS)':
 'VSS_D49': CDS_PINID='VSS_D49';
NODE_NAME     U25 D50
 '@T6G_MB_LIB.T6G(SCH_1):PAGE31_I19@PURE_QUANTA.GENOA_SP5(CHIPS)':
 'VSS_D50': CDS_PINID='VSS_D50';
NODE_NAME     U25 D51
 '@T6G_MB_LIB.T6G(SCH_1):PAGE31_I19@PURE_QUANTA.GENOA_SP5(CHIPS)':
 'VSS_D51': CDS_PINID='VSS_D51';
NODE_NAME     U25 D52
 '@T6G_MB_LIB.T6G(SCH_1):PAGE31_I19@PURE_QUANTA.GENOA_SP5(CHIPS)':
 'VSS_D52': CDS_PINID='VSS_D52';
NODE_NAME     U25 D53
 '@T6G_MB_LIB.T6G(SCH_1):PAGE31_I19@PURE_QUANTA.GENOA_SP5(CHIPS)':
 'VSS_D53': CDS_PINID='VSS_D53';
NODE_NAME     U25 D54
 '@T6G_MB_LIB.T6G(SCH_1):PAGE31_I19@PURE_QUANTA.GENOA_SP5(CHIPS)':
 'VSS_D54': CDS_PINID='VSS_D54';
NODE_NAME     U25 D57
 '@T6G_MB_LIB.T6G(SCH_1):PAGE31_I19@PURE_QUANTA.GENOA_SP5(CHIPS)':
 'VSS_D57': CDS_PINID='VSS_D57';
NODE_NAME     U25 D59
 '@T6G_MB_LIB.T6G(SCH_1):PAGE31_I19@PURE_QUANTA.GENOA_SP5(CHIPS)':
 'VSS_D59': CDS_PINID='VSS_D59';
NODE_NAME     U25 D60
 '@T6G_MB_LIB.T6G(SCH_1):PAGE31_I19@PURE_QUANTA.GENOA_SP5(CHIPS)':
 'VSS_D60': CDS_PINID='VSS_D60';
NODE_NAME     U25 D61
 '@T6G_MB_LIB.T6G(SCH_1):PAGE31_I19@PURE_QUANTA.GENOA_SP5(CHIPS)':
 'VSS_D61': CDS_PINID='VSS_D61';
NODE_NAME     U25 D63
 '@T6G_MB_LIB.T6G(SCH_1):PAGE31_I19@PURE_QUANTA.GENOA_SP5(CHIPS)':
 'VSS_D63': CDS_PINID='VSS_D63';
NODE_NAME     U25 D64
 '@T6G_MB_LIB.T6G(SCH_1):PAGE31_I19@PURE_QUANTA.GENOA_SP5(CHIPS)':
 'VSS_D64': CDS_PINID='VSS_D64';
NODE_NAME     U25 D66
 '@T6G_MB_LIB.T6G(SCH_1):PAGE31_I19@PURE_QUANTA.GENOA_SP5(CHIPS)':
 'VSS_D66': CDS_PINID='VSS_D66';
NODE_NAME     U25 D67
 '@T6G_MB_LIB.T6G(SCH_1):PAGE31_I19@PURE_QUANTA.GENOA_SP5(CHIPS)':
 'VSS_D67': CDS_PINID='VSS_D67';
NODE_NAME     U25 D70
 '@T6G_MB_LIB.T6G(SCH_1):PAGE31_I19@PURE_QUANTA.GENOA_SP5(CHIPS)':
 'VSS_D70': CDS_PINID='VSS_D70';
NODE_NAME     U25 D71
 '@T6G_MB_LIB.T6G(SCH_1):PAGE31_I19@PURE_QUANTA.GENOA_SP5(CHIPS)':
 'VSS_D71': CDS_PINID='VSS_D71';
NODE_NAME     U25 D73
 '@T6G_MB_LIB.T6G(SCH_1):PAGE31_I19@PURE_QUANTA.GENOA_SP5(CHIPS)':
 'VSS_D73': CDS_PINID='VSS_D73';
NODE_NAME     U25 D74
 '@T6G_MB_LIB.T6G(SCH_1):PAGE31_I19@PURE_QUANTA.GENOA_SP5(CHIPS)':
 'VSS_D74': CDS_PINID='VSS_D74';
NODE_NAME     U25 E1
 '@T6G_MB_LIB.T6G(SCH_1):PAGE31_I19@PURE_QUANTA.GENOA_SP5(CHIPS)':
 'VSS_E1': CDS_PINID='VSS_E1';
NODE_NAME     U25 E3
 '@T6G_MB_LIB.T6G(SCH_1):PAGE31_I19@PURE_QUANTA.GENOA_SP5(CHIPS)':
 'VSS_E3': CDS_PINID='VSS_E3';
NODE_NAME     U25 E6
 '@T6G_MB_LIB.T6G(SCH_1):PAGE31_I19@PURE_QUANTA.GENOA_SP5(CHIPS)':
 'VSS_E6': CDS_PINID='VSS_E6';
NODE_NAME     U25 E7
 '@T6G_MB_LIB.T6G(SCH_1):PAGE31_I19@PURE_QUANTA.GENOA_SP5(CHIPS)':
 'VSS_E7': CDS_PINID='VSS_E7';
NODE_NAME     U25 E8
 '@T6G_MB_LIB.T6G(SCH_1):PAGE31_I19@PURE_QUANTA.GENOA_SP5(CHIPS)':
 'VSS_E8': CDS_PINID='VSS_E8';
NODE_NAME     U25 E10
 '@T6G_MB_LIB.T6G(SCH_1):PAGE31_I19@PURE_QUANTA.GENOA_SP5(CHIPS)':
 'VSS_E10': CDS_PINID='VSS_E10';
NODE_NAME     U25 E13
 '@T6G_MB_LIB.T6G(SCH_1):PAGE31_I19@PURE_QUANTA.GENOA_SP5(CHIPS)':
 'VSS_E13': CDS_PINID='VSS_E13';
NODE_NAME     U25 E14
 '@T6G_MB_LIB.T6G(SCH_1):PAGE31_I19@PURE_QUANTA.GENOA_SP5(CHIPS)':
 'VSS_E14': CDS_PINID='VSS_E14';
NODE_NAME     U25 E15
 '@T6G_MB_LIB.T6G(SCH_1):PAGE31_I19@PURE_QUANTA.GENOA_SP5(CHIPS)':
 'VSS_E15': CDS_PINID='VSS_E15';
NODE_NAME     U25 E17
 '@T6G_MB_LIB.T6G(SCH_1):PAGE31_I19@PURE_QUANTA.GENOA_SP5(CHIPS)':
 'VSS_E17': CDS_PINID='VSS_E17';
NODE_NAME     U25 E18
 '@T6G_MB_LIB.T6G(SCH_1):PAGE31_I19@PURE_QUANTA.GENOA_SP5(CHIPS)':
 'VSS_E18': CDS_PINID='VSS_E18';
NODE_NAME     U25 E20
 '@T6G_MB_LIB.T6G(SCH_1):PAGE31_I19@PURE_QUANTA.GENOA_SP5(CHIPS)':
 'VSS_E20': CDS_PINID='VSS_E20';
NODE_NAME     U25 E21
 '@T6G_MB_LIB.T6G(SCH_1):PAGE31_I19@PURE_QUANTA.GENOA_SP5(CHIPS)':
 'VSS_E21': CDS_PINID='VSS_E21';
NODE_NAME     U25 E52
 '@T6G_MB_LIB.T6G(SCH_1):PAGE31_I19@PURE_QUANTA.GENOA_SP5(CHIPS)':
 'VSS_E52': CDS_PINID='VSS_E52';
NODE_NAME     U25 E53
 '@T6G_MB_LIB.T6G(SCH_1):PAGE31_I19@PURE_QUANTA.GENOA_SP5(CHIPS)':
 'VSS_E53': CDS_PINID='VSS_E53';
NODE_NAME     U25 E55
 '@T6G_MB_LIB.T6G(SCH_1):PAGE31_I19@PURE_QUANTA.GENOA_SP5(CHIPS)':
 'VSS_E55': CDS_PINID='VSS_E55';
NODE_NAME     U25 E56
 '@T6G_MB_LIB.T6G(SCH_1):PAGE31_I19@PURE_QUANTA.GENOA_SP5(CHIPS)':
 'VSS_E56': CDS_PINID='VSS_E56';
NODE_NAME     U25 E58
 '@T6G_MB_LIB.T6G(SCH_1):PAGE31_I19@PURE_QUANTA.GENOA_SP5(CHIPS)':
 'VSS_E58': CDS_PINID='VSS_E58';
NODE_NAME     U25 E59
 '@T6G_MB_LIB.T6G(SCH_1):PAGE31_I19@PURE_QUANTA.GENOA_SP5(CHIPS)':
 'VSS_E59': CDS_PINID='VSS_E59';
NODE_NAME     U25 E61
 '@T6G_MB_LIB.T6G(SCH_1):PAGE31_I19@PURE_QUANTA.GENOA_SP5(CHIPS)':
 'VSS_E61': CDS_PINID='VSS_E61';
NODE_NAME     U25 E62
 '@T6G_MB_LIB.T6G(SCH_1):PAGE31_I19@PURE_QUANTA.GENOA_SP5(CHIPS)':
 'VSS_E62': CDS_PINID='VSS_E62';
NODE_NAME     U25 E63
 '@T6G_MB_LIB.T6G(SCH_1):PAGE31_I19@PURE_QUANTA.GENOA_SP5(CHIPS)':
 'VSS_E63': CDS_PINID='VSS_E63';
NODE_NAME     U25 E65
 '@T6G_MB_LIB.T6G(SCH_1):PAGE31_I19@PURE_QUANTA.GENOA_SP5(CHIPS)':
 'VSS_E65': CDS_PINID='VSS_E65';
NODE_NAME     U25 E66
 '@T6G_MB_LIB.T6G(SCH_1):PAGE31_I19@PURE_QUANTA.GENOA_SP5(CHIPS)':
 'VSS_E66': CDS_PINID='VSS_E66';
NODE_NAME     U25 E68
 '@T6G_MB_LIB.T6G(SCH_1):PAGE31_I19@PURE_QUANTA.GENOA_SP5(CHIPS)':
 'VSS_E68': CDS_PINID='VSS_E68';
NODE_NAME     U25 E69
 '@T6G_MB_LIB.T6G(SCH_1):PAGE31_I19@PURE_QUANTA.GENOA_SP5(CHIPS)':
 'VSS_E69': CDS_PINID='VSS_E69';
NODE_NAME     U25 E70
 '@T6G_MB_LIB.T6G(SCH_1):PAGE31_I19@PURE_QUANTA.GENOA_SP5(CHIPS)':
 'VSS_E70': CDS_PINID='VSS_E70';
NODE_NAME     U25 E72
 '@T6G_MB_LIB.T6G(SCH_1):PAGE31_I19@PURE_QUANTA.GENOA_SP5(CHIPS)':
 'VSS_E72': CDS_PINID='VSS_E72';
NODE_NAME     U25 E73
 '@T6G_MB_LIB.T6G(SCH_1):PAGE31_I19@PURE_QUANTA.GENOA_SP5(CHIPS)':
 'VSS_E73': CDS_PINID='VSS_E73';
NODE_NAME     U25 E75
 '@T6G_MB_LIB.T6G(SCH_1):PAGE31_I19@PURE_QUANTA.GENOA_SP5(CHIPS)':
 'VSS_E75': CDS_PINID='VSS_E75';
NODE_NAME     U25 F3
 '@T6G_MB_LIB.T6G(SCH_1):PAGE31_I19@PURE_QUANTA.GENOA_SP5(CHIPS)':
 'VSS_F3': CDS_PINID='VSS_F3';
NODE_NAME     U25 F5
 '@T6G_MB_LIB.T6G(SCH_1):PAGE31_I19@PURE_QUANTA.GENOA_SP5(CHIPS)':
 'VSS_F5': CDS_PINID='VSS_F5';
NODE_NAME     U25 F8
 '@T6G_MB_LIB.T6G(SCH_1):PAGE31_I19@PURE_QUANTA.GENOA_SP5(CHIPS)':
 'VSS_F8': CDS_PINID='VSS_F8';
NODE_NAME     U25 F10
 '@T6G_MB_LIB.T6G(SCH_1):PAGE31_I19@PURE_QUANTA.GENOA_SP5(CHIPS)':
 'VSS_F10': CDS_PINID='VSS_F10';
NODE_NAME     U25 F12
 '@T6G_MB_LIB.T6G(SCH_1):PAGE31_I19@PURE_QUANTA.GENOA_SP5(CHIPS)':
 'VSS_F12': CDS_PINID='VSS_F12';
NODE_NAME     U25 F15
 '@T6G_MB_LIB.T6G(SCH_1):PAGE31_I19@PURE_QUANTA.GENOA_SP5(CHIPS)':
 'VSS_F15': CDS_PINID='VSS_F15';
NODE_NAME     U25 F17
 '@T6G_MB_LIB.T6G(SCH_1):PAGE31_I19@PURE_QUANTA.GENOA_SP5(CHIPS)':
 'VSS_F17': CDS_PINID='VSS_F17';
NODE_NAME     U25 F19
 '@T6G_MB_LIB.T6G(SCH_1):PAGE31_I19@PURE_QUANTA.GENOA_SP5(CHIPS)':
 'VSS_F19': CDS_PINID='VSS_F19';
NODE_NAME     U25 F23
 '@T6G_MB_LIB.T6G(SCH_1):PAGE31_I19@PURE_QUANTA.GENOA_SP5(CHIPS)':
 'VSS_F23': CDS_PINID='VSS_F23';
NODE_NAME     U25 F24
 '@T6G_MB_LIB.T6G(SCH_1):PAGE31_I19@PURE_QUANTA.GENOA_SP5(CHIPS)':
 'VSS_F24': CDS_PINID='VSS_F24';
NODE_NAME     U25 F26
 '@T6G_MB_LIB.T6G(SCH_1):PAGE31_I19@PURE_QUANTA.GENOA_SP5(CHIPS)':
 'VSS_F26': CDS_PINID='VSS_F26';
NODE_NAME     U25 F27
 '@T6G_MB_LIB.T6G(SCH_1):PAGE31_I19@PURE_QUANTA.GENOA_SP5(CHIPS)':
 'VSS_F27': CDS_PINID='VSS_F27';
NODE_NAME     U25 F29
 '@T6G_MB_LIB.T6G(SCH_1):PAGE31_I19@PURE_QUANTA.GENOA_SP5(CHIPS)':
 'VSS_F29': CDS_PINID='VSS_F29';
NODE_NAME     U25 F30
 '@T6G_MB_LIB.T6G(SCH_1):PAGE31_I19@PURE_QUANTA.GENOA_SP5(CHIPS)':
 'VSS_F30': CDS_PINID='VSS_F30';
NODE_NAME     U25 F32
 '@T6G_MB_LIB.T6G(SCH_1):PAGE31_I19@PURE_QUANTA.GENOA_SP5(CHIPS)':
 'VSS_F32': CDS_PINID='VSS_F32';
NODE_NAME     U25 F33
 '@T6G_MB_LIB.T6G(SCH_1):PAGE31_I19@PURE_QUANTA.GENOA_SP5(CHIPS)':
 'VSS_F33': CDS_PINID='VSS_F33';
NODE_NAME     U25 F35
 '@T6G_MB_LIB.T6G(SCH_1):PAGE31_I19@PURE_QUANTA.GENOA_SP5(CHIPS)':
 'VSS_F35': CDS_PINID='VSS_F35';
NODE_NAME     U25 F36
 '@T6G_MB_LIB.T6G(SCH_1):PAGE31_I19@PURE_QUANTA.GENOA_SP5(CHIPS)':
 'VSS_F36': CDS_PINID='VSS_F36';
NODE_NAME     U25 F37
 '@T6G_MB_LIB.T6G(SCH_1):PAGE31_I19@PURE_QUANTA.GENOA_SP5(CHIPS)':
 'VSS_F37': CDS_PINID='VSS_F37';
NODE_NAME     U25 F39
 '@T6G_MB_LIB.T6G(SCH_1):PAGE31_I19@PURE_QUANTA.GENOA_SP5(CHIPS)':
 'VSS_F39': CDS_PINID='VSS_F39';
NODE_NAME     U25 F40
 '@T6G_MB_LIB.T6G(SCH_1):PAGE31_I19@PURE_QUANTA.GENOA_SP5(CHIPS)':
 'VSS_F40': CDS_PINID='VSS_F40';
NODE_NAME     U25 F41
 '@T6G_MB_LIB.T6G(SCH_1):PAGE31_I19@PURE_QUANTA.GENOA_SP5(CHIPS)':
 'VSS_F41': CDS_PINID='VSS_F41';
NODE_NAME     U25 F43
 '@T6G_MB_LIB.T6G(SCH_1):PAGE31_I19@PURE_QUANTA.GENOA_SP5(CHIPS)':
 'VSS_F43': CDS_PINID='VSS_F43';
NODE_NAME     U25 F44
 '@T6G_MB_LIB.T6G(SCH_1):PAGE31_I19@PURE_QUANTA.GENOA_SP5(CHIPS)':
 'VSS_F44': CDS_PINID='VSS_F44';
NODE_NAME     U25 F46
 '@T6G_MB_LIB.T6G(SCH_1):PAGE31_I19@PURE_QUANTA.GENOA_SP5(CHIPS)':
 'VSS_F46': CDS_PINID='VSS_F46';
NODE_NAME     U25 F47
 '@T6G_MB_LIB.T6G(SCH_1):PAGE31_I19@PURE_QUANTA.GENOA_SP5(CHIPS)':
 'VSS_F47': CDS_PINID='VSS_F47';
NODE_NAME     U25 F49
 '@T6G_MB_LIB.T6G(SCH_1):PAGE31_I19@PURE_QUANTA.GENOA_SP5(CHIPS)':
 'VSS_F49': CDS_PINID='VSS_F49';
NODE_NAME     U25 F50
 '@T6G_MB_LIB.T6G(SCH_1):PAGE31_I19@PURE_QUANTA.GENOA_SP5(CHIPS)':
 'VSS_F50': CDS_PINID='VSS_F50';
NODE_NAME     U25 F52
 '@T6G_MB_LIB.T6G(SCH_1):PAGE31_I19@PURE_QUANTA.GENOA_SP5(CHIPS)':
 'VSS_F52': CDS_PINID='VSS_F52';
NODE_NAME     U25 F53
 '@T6G_MB_LIB.T6G(SCH_1):PAGE31_I19@PURE_QUANTA.GENOA_SP5(CHIPS)':
 'VSS_F53': CDS_PINID='VSS_F53';
NODE_NAME     U25 F57
 '@T6G_MB_LIB.T6G(SCH_1):PAGE31_I19@PURE_QUANTA.GENOA_SP5(CHIPS)':
 'VSS_F57': CDS_PINID='VSS_F57';
NODE_NAME     U25 F59
 '@T6G_MB_LIB.T6G(SCH_1):PAGE31_I19@PURE_QUANTA.GENOA_SP5(CHIPS)':
 'VSS_F59': CDS_PINID='VSS_F59';
NODE_NAME     U25 F61
 '@T6G_MB_LIB.T6G(SCH_1):PAGE31_I19@PURE_QUANTA.GENOA_SP5(CHIPS)':
 'VSS_F61': CDS_PINID='VSS_F61';
NODE_NAME     U25 F64
 '@T6G_MB_LIB.T6G(SCH_1):PAGE31_I19@PURE_QUANTA.GENOA_SP5(CHIPS)':
 'VSS_F64': CDS_PINID='VSS_F64';
NODE_NAME     U25 F66
 '@T6G_MB_LIB.T6G(SCH_1):PAGE31_I19@PURE_QUANTA.GENOA_SP5(CHIPS)':
 'VSS_F66': CDS_PINID='VSS_F66';
NODE_NAME     U25 F68
 '@T6G_MB_LIB.T6G(SCH_1):PAGE31_I19@PURE_QUANTA.GENOA_SP5(CHIPS)':
 'VSS_F68': CDS_PINID='VSS_F68';
NODE_NAME     U25 F71
 '@T6G_MB_LIB.T6G(SCH_1):PAGE31_I19@PURE_QUANTA.GENOA_SP5(CHIPS)':
 'VSS_F71': CDS_PINID='VSS_F71';
NODE_NAME     U25 F73
 '@T6G_MB_LIB.T6G(SCH_1):PAGE31_I19@PURE_QUANTA.GENOA_SP5(CHIPS)':
 'VSS_F73': CDS_PINID='VSS_F73';
NODE_NAME     U25 G1
 '@T6G_MB_LIB.T6G(SCH_1):PAGE31_I19@PURE_QUANTA.GENOA_SP5(CHIPS)':
 'VSS_G1': CDS_PINID='VSS_G1';
NODE_NAME     U25 G4
 '@T6G_MB_LIB.T6G(SCH_1):PAGE31_I19@PURE_QUANTA.GENOA_SP5(CHIPS)':
 'VSS_G4': CDS_PINID='VSS_G4';
NODE_NAME     U25 G6
 '@T6G_MB_LIB.T6G(SCH_1):PAGE31_I19@PURE_QUANTA.GENOA_SP5(CHIPS)':
 'VSS_G6': CDS_PINID='VSS_G6';
NODE_NAME     U25 G8
 '@T6G_MB_LIB.T6G(SCH_1):PAGE31_I19@PURE_QUANTA.GENOA_SP5(CHIPS)':
 'VSS_G8': CDS_PINID='VSS_G8';
NODE_NAME     U25 G11
 '@T6G_MB_LIB.T6G(SCH_1):PAGE31_I19@PURE_QUANTA.GENOA_SP5(CHIPS)':
 'VSS_G11': CDS_PINID='VSS_G11';
NODE_NAME     U25 G13
 '@T6G_MB_LIB.T6G(SCH_1):PAGE31_I19@PURE_QUANTA.GENOA_SP5(CHIPS)':
 'VSS_G13': CDS_PINID='VSS_G13';
NODE_NAME     U25 G15
 '@T6G_MB_LIB.T6G(SCH_1):PAGE31_I19@PURE_QUANTA.GENOA_SP5(CHIPS)':
 'VSS_G15': CDS_PINID='VSS_G15';
NODE_NAME     U25 G18
 '@T6G_MB_LIB.T6G(SCH_1):PAGE31_I19@PURE_QUANTA.GENOA_SP5(CHIPS)':
 'VSS_G18': CDS_PINID='VSS_G18';
NODE_NAME     U25 G20
 '@T6G_MB_LIB.T6G(SCH_1):PAGE31_I19@PURE_QUANTA.GENOA_SP5(CHIPS)':
 'VSS_G20': CDS_PINID='VSS_G20';
NODE_NAME     U25 G22
 '@T6G_MB_LIB.T6G(SCH_1):PAGE31_I19@PURE_QUANTA.GENOA_SP5(CHIPS)':
 'VSS_G22': CDS_PINID='VSS_G22';
NODE_NAME     U25 G25
 '@T6G_MB_LIB.T6G(SCH_1):PAGE31_I19@PURE_QUANTA.GENOA_SP5(CHIPS)':
 'VSS_G25': CDS_PINID='VSS_G25';
NODE_NAME     U25 G28
 '@T6G_MB_LIB.T6G(SCH_1):PAGE31_I19@PURE_QUANTA.GENOA_SP5(CHIPS)':
 'VSS_G28': CDS_PINID='VSS_G28';
NODE_NAME     U25 G31
 '@T6G_MB_LIB.T6G(SCH_1):PAGE31_I19@PURE_QUANTA.GENOA_SP5(CHIPS)':
 'VSS_G31': CDS_PINID='VSS_G31';
NODE_NAME     U25 G34
 '@T6G_MB_LIB.T6G(SCH_1):PAGE31_I19@PURE_QUANTA.GENOA_SP5(CHIPS)':
 'VSS_G34': CDS_PINID='VSS_G34';
NODE_NAME     U25 G42
 '@T6G_MB_LIB.T6G(SCH_1):PAGE31_I19@PURE_QUANTA.GENOA_SP5(CHIPS)':
 'VSS_G42': CDS_PINID='VSS_G42';
NODE_NAME     U25 G45
 '@T6G_MB_LIB.T6G(SCH_1):PAGE31_I19@PURE_QUANTA.GENOA_SP5(CHIPS)':
 'VSS_G45': CDS_PINID='VSS_G45';
NODE_NAME     U25 G48
 '@T6G_MB_LIB.T6G(SCH_1):PAGE31_I19@PURE_QUANTA.GENOA_SP5(CHIPS)':
 'VSS_G48': CDS_PINID='VSS_G48';
NODE_NAME     U25 G51
 '@T6G_MB_LIB.T6G(SCH_1):PAGE31_I19@PURE_QUANTA.GENOA_SP5(CHIPS)':
 'VSS_G51': CDS_PINID='VSS_G51';
NODE_NAME     U25 G54
 '@T6G_MB_LIB.T6G(SCH_1):PAGE31_I19@PURE_QUANTA.GENOA_SP5(CHIPS)':
 'VSS_G54': CDS_PINID='VSS_G54';
NODE_NAME     U25 G56
 '@T6G_MB_LIB.T6G(SCH_1):PAGE31_I19@PURE_QUANTA.GENOA_SP5(CHIPS)':
 'VSS_G56': CDS_PINID='VSS_G56';
NODE_NAME     U25 G58
 '@T6G_MB_LIB.T6G(SCH_1):PAGE31_I19@PURE_QUANTA.GENOA_SP5(CHIPS)':
 'VSS_G58': CDS_PINID='VSS_G58';
NODE_NAME     U25 G61
 '@T6G_MB_LIB.T6G(SCH_1):PAGE31_I19@PURE_QUANTA.GENOA_SP5(CHIPS)':
 'VSS_G61': CDS_PINID='VSS_G61';
NODE_NAME     U25 G63
 '@T6G_MB_LIB.T6G(SCH_1):PAGE31_I19@PURE_QUANTA.GENOA_SP5(CHIPS)':
 'VSS_G63': CDS_PINID='VSS_G63';
NODE_NAME     U25 G65
 '@T6G_MB_LIB.T6G(SCH_1):PAGE31_I19@PURE_QUANTA.GENOA_SP5(CHIPS)':
 'VSS_G65': CDS_PINID='VSS_G65';
NODE_NAME     U25 G68
 '@T6G_MB_LIB.T6G(SCH_1):PAGE31_I19@PURE_QUANTA.GENOA_SP5(CHIPS)':
 'VSS_G68': CDS_PINID='VSS_G68';
NODE_NAME     U25 G70
 '@T6G_MB_LIB.T6G(SCH_1):PAGE31_I19@PURE_QUANTA.GENOA_SP5(CHIPS)':
 'VSS_G70': CDS_PINID='VSS_G70';
NODE_NAME     U25 G72
 '@T6G_MB_LIB.T6G(SCH_1):PAGE31_I19@PURE_QUANTA.GENOA_SP5(CHIPS)':
 'VSS_G72': CDS_PINID='VSS_G72';
NODE_NAME     U25 G75
 '@T6G_MB_LIB.T6G(SCH_1):PAGE31_I19@PURE_QUANTA.GENOA_SP5(CHIPS)':
 'VSS_G75': CDS_PINID='VSS_G75';
NODE_NAME     U25 H3
 '@T6G_MB_LIB.T6G(SCH_1):PAGE31_I19@PURE_QUANTA.GENOA_SP5(CHIPS)':
 'VSS_H3': CDS_PINID='VSS_H3';
NODE_NAME     U25 H8
 '@T6G_MB_LIB.T6G(SCH_1):PAGE31_I19@PURE_QUANTA.GENOA_SP5(CHIPS)':
 'VSS_H8': CDS_PINID='VSS_H8';
NODE_NAME     U25 H10
 '@T6G_MB_LIB.T6G(SCH_1):PAGE31_I19@PURE_QUANTA.GENOA_SP5(CHIPS)':
 'VSS_H10': CDS_PINID='VSS_H10';
NODE_NAME     U25 H15
 '@T6G_MB_LIB.T6G(SCH_1):PAGE31_I19@PURE_QUANTA.GENOA_SP5(CHIPS)':
 'VSS_H15': CDS_PINID='VSS_H15';
NODE_NAME     U25 H17
 '@T6G_MB_LIB.T6G(SCH_1):PAGE31_I19@PURE_QUANTA.GENOA_SP5(CHIPS)':
 'VSS_H17': CDS_PINID='VSS_H17';
NODE_NAME     U25 H22
 '@T6G_MB_LIB.T6G(SCH_1):PAGE31_I19@PURE_QUANTA.GENOA_SP5(CHIPS)':
 'VSS_H22': CDS_PINID='VSS_H22';
NODE_NAME     U25 H25
 '@T6G_MB_LIB.T6G(SCH_1):PAGE31_I19@PURE_QUANTA.GENOA_SP5(CHIPS)':
 'VSS_H25': CDS_PINID='VSS_H25';
NODE_NAME     U25 H28
 '@T6G_MB_LIB.T6G(SCH_1):PAGE31_I19@PURE_QUANTA.GENOA_SP5(CHIPS)':
 'VSS_H28': CDS_PINID='VSS_H28';
NODE_NAME     U25 H31
 '@T6G_MB_LIB.T6G(SCH_1):PAGE31_I19@PURE_QUANTA.GENOA_SP5(CHIPS)':
 'VSS_H31': CDS_PINID='VSS_H31';
NODE_NAME     U25 H34
 '@T6G_MB_LIB.T6G(SCH_1):PAGE31_I19@PURE_QUANTA.GENOA_SP5(CHIPS)':
 'VSS_H34': CDS_PINID='VSS_H34';
NODE_NAME     U25 H37
 '@T6G_MB_LIB.T6G(SCH_1):PAGE31_I19@PURE_QUANTA.GENOA_SP5(CHIPS)':
 'VSS_H37': CDS_PINID='VSS_H37';
NODE_NAME     U25 H39
 '@T6G_MB_LIB.T6G(SCH_1):PAGE31_I19@PURE_QUANTA.GENOA_SP5(CHIPS)':
 'VSS_H39': CDS_PINID='VSS_H39';
NODE_NAME     U25 H42
 '@T6G_MB_LIB.T6G(SCH_1):PAGE31_I19@PURE_QUANTA.GENOA_SP5(CHIPS)':
 'VSS_H42': CDS_PINID='VSS_H42';
NODE_NAME     U25 H45
 '@T6G_MB_LIB.T6G(SCH_1):PAGE31_I19@PURE_QUANTA.GENOA_SP5(CHIPS)':
 'VSS_H45': CDS_PINID='VSS_H45';
NODE_NAME     U25 H48
 '@T6G_MB_LIB.T6G(SCH_1):PAGE31_I19@PURE_QUANTA.GENOA_SP5(CHIPS)':
 'VSS_H48': CDS_PINID='VSS_H48';
NODE_NAME     U25 H51
 '@T6G_MB_LIB.T6G(SCH_1):PAGE31_I19@PURE_QUANTA.GENOA_SP5(CHIPS)':
 'VSS_H51': CDS_PINID='VSS_H51';
NODE_NAME     U25 H54
 '@T6G_MB_LIB.T6G(SCH_1):PAGE31_I19@PURE_QUANTA.GENOA_SP5(CHIPS)':
 'VSS_H54': CDS_PINID='VSS_H54';
NODE_NAME     U25 H59
 '@T6G_MB_LIB.T6G(SCH_1):PAGE31_I19@PURE_QUANTA.GENOA_SP5(CHIPS)':
 'VSS_H59': CDS_PINID='VSS_H59';
NODE_NAME     U25 H61
 '@T6G_MB_LIB.T6G(SCH_1):PAGE31_I19@PURE_QUANTA.GENOA_SP5(CHIPS)':
 'VSS_H61': CDS_PINID='VSS_H61';
NODE_NAME     U25 H66
 '@T6G_MB_LIB.T6G(SCH_1):PAGE31_I19@PURE_QUANTA.GENOA_SP5(CHIPS)':
 'VSS_H66': CDS_PINID='VSS_H66';
NODE_NAME     U25 H68
 '@T6G_MB_LIB.T6G(SCH_1):PAGE31_I19@PURE_QUANTA.GENOA_SP5(CHIPS)':
 'VSS_H68': CDS_PINID='VSS_H68';
NODE_NAME     U25 H73
 '@T6G_MB_LIB.T6G(SCH_1):PAGE31_I19@PURE_QUANTA.GENOA_SP5(CHIPS)':
 'VSS_H73': CDS_PINID='VSS_H73';
NODE_NAME     U25 J1
 '@T6G_MB_LIB.T6G(SCH_1):PAGE31_I19@PURE_QUANTA.GENOA_SP5(CHIPS)':
 'VSS_J1': CDS_PINID='VSS_J1';
NODE_NAME     U25 J4
 '@T6G_MB_LIB.T6G(SCH_1):PAGE31_I19@PURE_QUANTA.GENOA_SP5(CHIPS)':
 'VSS_J4': CDS_PINID='VSS_J4';
NODE_NAME     U25 J6
 '@T6G_MB_LIB.T6G(SCH_1):PAGE31_I19@PURE_QUANTA.GENOA_SP5(CHIPS)':
 'VSS_J6': CDS_PINID='VSS_J6';
NODE_NAME     U25 J8
 '@T6G_MB_LIB.T6G(SCH_1):PAGE31_I19@PURE_QUANTA.GENOA_SP5(CHIPS)':
 'VSS_J8': CDS_PINID='VSS_J8';
NODE_NAME     U25 J11
 '@T6G_MB_LIB.T6G(SCH_1):PAGE31_I19@PURE_QUANTA.GENOA_SP5(CHIPS)':
 'VSS_J11': CDS_PINID='VSS_J11';
NODE_NAME     U25 J13
 '@T6G_MB_LIB.T6G(SCH_1):PAGE31_I19@PURE_QUANTA.GENOA_SP5(CHIPS)':
 'VSS_J13': CDS_PINID='VSS_J13';
NODE_NAME     U25 J15
 '@T6G_MB_LIB.T6G(SCH_1):PAGE31_I20@PURE_QUANTA.GENOA_SP5(CHIPS)':
 'VSS_J15': CDS_PINID='VSS_J15';
NODE_NAME     U25 J18
 '@T6G_MB_LIB.T6G(SCH_1):PAGE31_I20@PURE_QUANTA.GENOA_SP5(CHIPS)':
 'VSS_J18': CDS_PINID='VSS_J18';
NODE_NAME     U25 J20
 '@T6G_MB_LIB.T6G(SCH_1):PAGE31_I20@PURE_QUANTA.GENOA_SP5(CHIPS)':
 'VSS_J20': CDS_PINID='VSS_J20';
NODE_NAME     U25 J22
 '@T6G_MB_LIB.T6G(SCH_1):PAGE31_I20@PURE_QUANTA.GENOA_SP5(CHIPS)':
 'VSS_J22': CDS_PINID='VSS_J22';
NODE_NAME     U25 J25
 '@T6G_MB_LIB.T6G(SCH_1):PAGE31_I20@PURE_QUANTA.GENOA_SP5(CHIPS)':
 'VSS_J25': CDS_PINID='VSS_J25';
NODE_NAME     U25 J28
 '@T6G_MB_LIB.T6G(SCH_1):PAGE31_I20@PURE_QUANTA.GENOA_SP5(CHIPS)':
 'VSS_J28': CDS_PINID='VSS_J28';
NODE_NAME     U25 J31
 '@T6G_MB_LIB.T6G(SCH_1):PAGE31_I20@PURE_QUANTA.GENOA_SP5(CHIPS)':
 'VSS_J31': CDS_PINID='VSS_J31';
NODE_NAME     U25 J34
 '@T6G_MB_LIB.T6G(SCH_1):PAGE31_I20@PURE_QUANTA.GENOA_SP5(CHIPS)':
 'VSS_J34': CDS_PINID='VSS_J34';
NODE_NAME     U25 J42
 '@T6G_MB_LIB.T6G(SCH_1):PAGE31_I20@PURE_QUANTA.GENOA_SP5(CHIPS)':
 'VSS_J42': CDS_PINID='VSS_J42';
NODE_NAME     U25 J45
 '@T6G_MB_LIB.T6G(SCH_1):PAGE31_I20@PURE_QUANTA.GENOA_SP5(CHIPS)':
 'VSS_J45': CDS_PINID='VSS_J45';
NODE_NAME     U25 J48
 '@T6G_MB_LIB.T6G(SCH_1):PAGE31_I20@PURE_QUANTA.GENOA_SP5(CHIPS)':
 'VSS_J48': CDS_PINID='VSS_J48';
NODE_NAME     U25 J51
 '@T6G_MB_LIB.T6G(SCH_1):PAGE31_I20@PURE_QUANTA.GENOA_SP5(CHIPS)':
 'VSS_J51': CDS_PINID='VSS_J51';
NODE_NAME     U25 J54
 '@T6G_MB_LIB.T6G(SCH_1):PAGE31_I20@PURE_QUANTA.GENOA_SP5(CHIPS)':
 'VSS_J54': CDS_PINID='VSS_J54';
NODE_NAME     U25 J56
 '@T6G_MB_LIB.T6G(SCH_1):PAGE31_I20@PURE_QUANTA.GENOA_SP5(CHIPS)':
 'VSS_J56': CDS_PINID='VSS_J56';
NODE_NAME     U25 J58
 '@T6G_MB_LIB.T6G(SCH_1):PAGE31_I20@PURE_QUANTA.GENOA_SP5(CHIPS)':
 'VSS_J58': CDS_PINID='VSS_J58';
NODE_NAME     U25 J61
 '@T6G_MB_LIB.T6G(SCH_1):PAGE31_I20@PURE_QUANTA.GENOA_SP5(CHIPS)':
 'VSS_J61': CDS_PINID='VSS_J61';
NODE_NAME     U25 J63
 '@T6G_MB_LIB.T6G(SCH_1):PAGE31_I20@PURE_QUANTA.GENOA_SP5(CHIPS)':
 'VSS_J63': CDS_PINID='VSS_J63';
NODE_NAME     U25 J65
 '@T6G_MB_LIB.T6G(SCH_1):PAGE31_I20@PURE_QUANTA.GENOA_SP5(CHIPS)':
 'VSS_J65': CDS_PINID='VSS_J65';
NODE_NAME     U25 J68
 '@T6G_MB_LIB.T6G(SCH_1):PAGE31_I20@PURE_QUANTA.GENOA_SP5(CHIPS)':
 'VSS_J68': CDS_PINID='VSS_J68';
NODE_NAME     U25 J70
 '@T6G_MB_LIB.T6G(SCH_1):PAGE31_I20@PURE_QUANTA.GENOA_SP5(CHIPS)':
 'VSS_J70': CDS_PINID='VSS_J70';
NODE_NAME     U25 J72
 '@T6G_MB_LIB.T6G(SCH_1):PAGE31_I20@PURE_QUANTA.GENOA_SP5(CHIPS)':
 'VSS_J72': CDS_PINID='VSS_J72';
NODE_NAME     U25 J75
 '@T6G_MB_LIB.T6G(SCH_1):PAGE31_I20@PURE_QUANTA.GENOA_SP5(CHIPS)':
 'VSS_J75': CDS_PINID='VSS_J75';
NODE_NAME     U25 K3
 '@T6G_MB_LIB.T6G(SCH_1):PAGE31_I20@PURE_QUANTA.GENOA_SP5(CHIPS)':
 'VSS_K3': CDS_PINID='VSS_K3';
NODE_NAME     U25 K5
 '@T6G_MB_LIB.T6G(SCH_1):PAGE31_I20@PURE_QUANTA.GENOA_SP5(CHIPS)':
 'VSS_K5': CDS_PINID='VSS_K5';
NODE_NAME     U25 K8
 '@T6G_MB_LIB.T6G(SCH_1):PAGE31_I20@PURE_QUANTA.GENOA_SP5(CHIPS)':
 'VSS_K8': CDS_PINID='VSS_K8';
NODE_NAME     U25 K10
 '@T6G_MB_LIB.T6G(SCH_1):PAGE31_I20@PURE_QUANTA.GENOA_SP5(CHIPS)':
 'VSS_K10': CDS_PINID='VSS_K10';
NODE_NAME     U25 K12
 '@T6G_MB_LIB.T6G(SCH_1):PAGE31_I20@PURE_QUANTA.GENOA_SP5(CHIPS)':
 'VSS_K12': CDS_PINID='VSS_K12';
NODE_NAME     U25 K15
 '@T6G_MB_LIB.T6G(SCH_1):PAGE31_I20@PURE_QUANTA.GENOA_SP5(CHIPS)':
 'VSS_K15': CDS_PINID='VSS_K15';
NODE_NAME     U25 K17
 '@T6G_MB_LIB.T6G(SCH_1):PAGE31_I20@PURE_QUANTA.GENOA_SP5(CHIPS)':
 'VSS_K17': CDS_PINID='VSS_K17';
NODE_NAME     U25 K19
 '@T6G_MB_LIB.T6G(SCH_1):PAGE31_I20@PURE_QUANTA.GENOA_SP5(CHIPS)':
 'VSS_K19': CDS_PINID='VSS_K19';
NODE_NAME     U25 K24
 '@T6G_MB_LIB.T6G(SCH_1):PAGE31_I20@PURE_QUANTA.GENOA_SP5(CHIPS)':
 'VSS_K24': CDS_PINID='VSS_K24';
NODE_NAME     U25 K25
 '@T6G_MB_LIB.T6G(SCH_1):PAGE31_I20@PURE_QUANTA.GENOA_SP5(CHIPS)':
 'VSS_K25': CDS_PINID='VSS_K25';
NODE_NAME     U25 K26
 '@T6G_MB_LIB.T6G(SCH_1):PAGE31_I20@PURE_QUANTA.GENOA_SP5(CHIPS)':
 'VSS_K26': CDS_PINID='VSS_K26';
NODE_NAME     U25 K27
 '@T6G_MB_LIB.T6G(SCH_1):PAGE31_I20@PURE_QUANTA.GENOA_SP5(CHIPS)':
 'VSS_K27': CDS_PINID='VSS_K27';
NODE_NAME     U25 K28
 '@T6G_MB_LIB.T6G(SCH_1):PAGE31_I20@PURE_QUANTA.GENOA_SP5(CHIPS)':
 'VSS_K28': CDS_PINID='VSS_K28';
NODE_NAME     U25 K29
 '@T6G_MB_LIB.T6G(SCH_1):PAGE31_I20@PURE_QUANTA.GENOA_SP5(CHIPS)':
 'VSS_K29': CDS_PINID='VSS_K29';
NODE_NAME     U25 K30
 '@T6G_MB_LIB.T6G(SCH_1):PAGE31_I20@PURE_QUANTA.GENOA_SP5(CHIPS)':
 'VSS_K30': CDS_PINID='VSS_K30';
NODE_NAME     U25 K31
 '@T6G_MB_LIB.T6G(SCH_1):PAGE31_I20@PURE_QUANTA.GENOA_SP5(CHIPS)':
 'VSS_K31': CDS_PINID='VSS_K31';
NODE_NAME     U25 K32
 '@T6G_MB_LIB.T6G(SCH_1):PAGE31_I20@PURE_QUANTA.GENOA_SP5(CHIPS)':
 'VSS_K32': CDS_PINID='VSS_K32';
NODE_NAME     U25 K33
 '@T6G_MB_LIB.T6G(SCH_1):PAGE31_I20@PURE_QUANTA.GENOA_SP5(CHIPS)':
 'VSS_K33': CDS_PINID='VSS_K33';
NODE_NAME     U25 K34
 '@T6G_MB_LIB.T6G(SCH_1):PAGE31_I20@PURE_QUANTA.GENOA_SP5(CHIPS)':
 'VSS_K34': CDS_PINID='VSS_K34';
NODE_NAME     U25 K37
 '@T6G_MB_LIB.T6G(SCH_1):PAGE31_I20@PURE_QUANTA.GENOA_SP5(CHIPS)':
 'VSS_K37': CDS_PINID='VSS_K37';
NODE_NAME     U25 K39
 '@T6G_MB_LIB.T6G(SCH_1):PAGE31_I20@PURE_QUANTA.GENOA_SP5(CHIPS)':
 'VSS_K39': CDS_PINID='VSS_K39';
NODE_NAME     U25 K42
 '@T6G_MB_LIB.T6G(SCH_1):PAGE31_I20@PURE_QUANTA.GENOA_SP5(CHIPS)':
 'VSS_K42': CDS_PINID='VSS_K42';
NODE_NAME     U25 K43
 '@T6G_MB_LIB.T6G(SCH_1):PAGE31_I20@PURE_QUANTA.GENOA_SP5(CHIPS)':
 'VSS_K43': CDS_PINID='VSS_K43';
NODE_NAME     U25 K44
 '@T6G_MB_LIB.T6G(SCH_1):PAGE31_I20@PURE_QUANTA.GENOA_SP5(CHIPS)':
 'VSS_K44': CDS_PINID='VSS_K44';
NODE_NAME     U25 K45
 '@T6G_MB_LIB.T6G(SCH_1):PAGE31_I20@PURE_QUANTA.GENOA_SP5(CHIPS)':
 'VSS_K45': CDS_PINID='VSS_K45';
NODE_NAME     U25 K46
 '@T6G_MB_LIB.T6G(SCH_1):PAGE31_I20@PURE_QUANTA.GENOA_SP5(CHIPS)':
 'VSS_K46': CDS_PINID='VSS_K46';
NODE_NAME     U25 K47
 '@T6G_MB_LIB.T6G(SCH_1):PAGE31_I20@PURE_QUANTA.GENOA_SP5(CHIPS)':
 'VSS_K47': CDS_PINID='VSS_K47';
NODE_NAME     U25 K48
 '@T6G_MB_LIB.T6G(SCH_1):PAGE31_I20@PURE_QUANTA.GENOA_SP5(CHIPS)':
 'VSS_K48': CDS_PINID='VSS_K48';
NODE_NAME     U25 K49
 '@T6G_MB_LIB.T6G(SCH_1):PAGE31_I20@PURE_QUANTA.GENOA_SP5(CHIPS)':
 'VSS_K49': CDS_PINID='VSS_K49';
NODE_NAME     U25 K50
 '@T6G_MB_LIB.T6G(SCH_1):PAGE31_I20@PURE_QUANTA.GENOA_SP5(CHIPS)':
 'VSS_K50': CDS_PINID='VSS_K50';
NODE_NAME     U25 K51
 '@T6G_MB_LIB.T6G(SCH_1):PAGE31_I20@PURE_QUANTA.GENOA_SP5(CHIPS)':
 'VSS_K51': CDS_PINID='VSS_K51';
NODE_NAME     U25 K52
 '@T6G_MB_LIB.T6G(SCH_1):PAGE31_I20@PURE_QUANTA.GENOA_SP5(CHIPS)':
 'VSS_K52': CDS_PINID='VSS_K52';
NODE_NAME     U25 K53
 '@T6G_MB_LIB.T6G(SCH_1):PAGE31_I20@PURE_QUANTA.GENOA_SP5(CHIPS)':
 'VSS_K53': CDS_PINID='VSS_K53';
NODE_NAME     U25 K57
 '@T6G_MB_LIB.T6G(SCH_1):PAGE31_I20@PURE_QUANTA.GENOA_SP5(CHIPS)':
 'VSS_K57': CDS_PINID='VSS_K57';
NODE_NAME     U25 K61
 '@T6G_MB_LIB.T6G(SCH_1):PAGE31_I20@PURE_QUANTA.GENOA_SP5(CHIPS)':
 'VSS_K61': CDS_PINID='VSS_K61';
NODE_NAME     U25 K64
 '@T6G_MB_LIB.T6G(SCH_1):PAGE31_I20@PURE_QUANTA.GENOA_SP5(CHIPS)':
 'VSS_K64': CDS_PINID='VSS_K64';
NODE_NAME     U25 K66
 '@T6G_MB_LIB.T6G(SCH_1):PAGE31_I20@PURE_QUANTA.GENOA_SP5(CHIPS)':
 'VSS_K66': CDS_PINID='VSS_K66';
NODE_NAME     U25 K68
 '@T6G_MB_LIB.T6G(SCH_1):PAGE31_I20@PURE_QUANTA.GENOA_SP5(CHIPS)':
 'VSS_K68': CDS_PINID='VSS_K68';
NODE_NAME     U25 K71
 '@T6G_MB_LIB.T6G(SCH_1):PAGE31_I20@PURE_QUANTA.GENOA_SP5(CHIPS)':
 'VSS_K71': CDS_PINID='VSS_K71';
NODE_NAME     U25 K73
 '@T6G_MB_LIB.T6G(SCH_1):PAGE31_I20@PURE_QUANTA.GENOA_SP5(CHIPS)':
 'VSS_K73': CDS_PINID='VSS_K73';
NODE_NAME     U25 L1
 '@T6G_MB_LIB.T6G(SCH_1):PAGE31_I20@PURE_QUANTA.GENOA_SP5(CHIPS)':
 'VSS_L1': CDS_PINID='VSS_L1';
NODE_NAME     U25 L6
 '@T6G_MB_LIB.T6G(SCH_1):PAGE31_I20@PURE_QUANTA.GENOA_SP5(CHIPS)':
 'VSS_L6': CDS_PINID='VSS_L6';
NODE_NAME     U25 L8
 '@T6G_MB_LIB.T6G(SCH_1):PAGE31_I20@PURE_QUANTA.GENOA_SP5(CHIPS)':
 'VSS_L8': CDS_PINID='VSS_L8';
NODE_NAME     U25 L13
 '@T6G_MB_LIB.T6G(SCH_1):PAGE31_I20@PURE_QUANTA.GENOA_SP5(CHIPS)':
 'VSS_L13': CDS_PINID='VSS_L13';
NODE_NAME     U25 L15
 '@T6G_MB_LIB.T6G(SCH_1):PAGE31_I20@PURE_QUANTA.GENOA_SP5(CHIPS)':
 'VSS_L15': CDS_PINID='VSS_L15';
NODE_NAME     U25 L20
 '@T6G_MB_LIB.T6G(SCH_1):PAGE31_I20@PURE_QUANTA.GENOA_SP5(CHIPS)':
 'VSS_L20': CDS_PINID='VSS_L20';
NODE_NAME     U25 L22
 '@T6G_MB_LIB.T6G(SCH_1):PAGE31_I20@PURE_QUANTA.GENOA_SP5(CHIPS)':
 'VSS_L22': CDS_PINID='VSS_L22';
NODE_NAME     U25 L25
 '@T6G_MB_LIB.T6G(SCH_1):PAGE31_I20@PURE_QUANTA.GENOA_SP5(CHIPS)':
 'VSS_L25': CDS_PINID='VSS_L25';
NODE_NAME     U25 L28
 '@T6G_MB_LIB.T6G(SCH_1):PAGE31_I20@PURE_QUANTA.GENOA_SP5(CHIPS)':
 'VSS_L28': CDS_PINID='VSS_L28';
NODE_NAME     U25 L31
 '@T6G_MB_LIB.T6G(SCH_1):PAGE31_I20@PURE_QUANTA.GENOA_SP5(CHIPS)':
 'VSS_L31': CDS_PINID='VSS_L31';
NODE_NAME     U25 L34
 '@T6G_MB_LIB.T6G(SCH_1):PAGE31_I20@PURE_QUANTA.GENOA_SP5(CHIPS)':
 'VSS_L34': CDS_PINID='VSS_L34';
NODE_NAME     U25 L35
 '@T6G_MB_LIB.T6G(SCH_1):PAGE31_I20@PURE_QUANTA.GENOA_SP5(CHIPS)':
 'VSS_L35': CDS_PINID='VSS_L35';
NODE_NAME     U25 L36
 '@T6G_MB_LIB.T6G(SCH_1):PAGE31_I20@PURE_QUANTA.GENOA_SP5(CHIPS)':
 'VSS_L36': CDS_PINID='VSS_L36';
NODE_NAME     U25 L40
 '@T6G_MB_LIB.T6G(SCH_1):PAGE31_I20@PURE_QUANTA.GENOA_SP5(CHIPS)':
 'VSS_L40': CDS_PINID='VSS_L40';
NODE_NAME     U25 L41
 '@T6G_MB_LIB.T6G(SCH_1):PAGE31_I20@PURE_QUANTA.GENOA_SP5(CHIPS)':
 'VSS_L41': CDS_PINID='VSS_L41';
NODE_NAME     U25 L42
 '@T6G_MB_LIB.T6G(SCH_1):PAGE31_I20@PURE_QUANTA.GENOA_SP5(CHIPS)':
 'VSS_L42': CDS_PINID='VSS_L42';
NODE_NAME     U25 L45
 '@T6G_MB_LIB.T6G(SCH_1):PAGE31_I20@PURE_QUANTA.GENOA_SP5(CHIPS)':
 'VSS_L45': CDS_PINID='VSS_L45';
NODE_NAME     U25 L48
 '@T6G_MB_LIB.T6G(SCH_1):PAGE31_I20@PURE_QUANTA.GENOA_SP5(CHIPS)':
 'VSS_L48': CDS_PINID='VSS_L48';
NODE_NAME     U25 L51
 '@T6G_MB_LIB.T6G(SCH_1):PAGE31_I20@PURE_QUANTA.GENOA_SP5(CHIPS)':
 'VSS_L51': CDS_PINID='VSS_L51';
NODE_NAME     U25 L54
 '@T6G_MB_LIB.T6G(SCH_1):PAGE31_I20@PURE_QUANTA.GENOA_SP5(CHIPS)':
 'VSS_L54': CDS_PINID='VSS_L54';
NODE_NAME     U25 L56
 '@T6G_MB_LIB.T6G(SCH_1):PAGE31_I20@PURE_QUANTA.GENOA_SP5(CHIPS)':
 'VSS_L56': CDS_PINID='VSS_L56';
NODE_NAME     U25 L61
 '@T6G_MB_LIB.T6G(SCH_1):PAGE31_I20@PURE_QUANTA.GENOA_SP5(CHIPS)':
 'VSS_L61': CDS_PINID='VSS_L61';
NODE_NAME     U25 L63
 '@T6G_MB_LIB.T6G(SCH_1):PAGE31_I20@PURE_QUANTA.GENOA_SP5(CHIPS)':
 'VSS_L63': CDS_PINID='VSS_L63';
NODE_NAME     U25 L68
 '@T6G_MB_LIB.T6G(SCH_1):PAGE31_I20@PURE_QUANTA.GENOA_SP5(CHIPS)':
 'VSS_L68': CDS_PINID='VSS_L68';
NODE_NAME     U25 L70
 '@T6G_MB_LIB.T6G(SCH_1):PAGE31_I20@PURE_QUANTA.GENOA_SP5(CHIPS)':
 'VSS_L70': CDS_PINID='VSS_L70';
NODE_NAME     U25 L75
 '@T6G_MB_LIB.T6G(SCH_1):PAGE31_I20@PURE_QUANTA.GENOA_SP5(CHIPS)':
 'VSS_L75': CDS_PINID='VSS_L75';
NODE_NAME     U25 M3
 '@T6G_MB_LIB.T6G(SCH_1):PAGE31_I20@PURE_QUANTA.GENOA_SP5(CHIPS)':
 'VSS_M3': CDS_PINID='VSS_M3';
NODE_NAME     U25 M5
 '@T6G_MB_LIB.T6G(SCH_1):PAGE31_I20@PURE_QUANTA.GENOA_SP5(CHIPS)':
 'VSS_M5': CDS_PINID='VSS_M5';
NODE_NAME     U25 M8
 '@T6G_MB_LIB.T6G(SCH_1):PAGE31_I20@PURE_QUANTA.GENOA_SP5(CHIPS)':
 'VSS_M8': CDS_PINID='VSS_M8';
NODE_NAME     U25 M10
 '@T6G_MB_LIB.T6G(SCH_1):PAGE31_I20@PURE_QUANTA.GENOA_SP5(CHIPS)':
 'VSS_M10': CDS_PINID='VSS_M10';
NODE_NAME     U25 M12
 '@T6G_MB_LIB.T6G(SCH_1):PAGE31_I20@PURE_QUANTA.GENOA_SP5(CHIPS)':
 'VSS_M12': CDS_PINID='VSS_M12';
NODE_NAME     U25 M15
 '@T6G_MB_LIB.T6G(SCH_1):PAGE31_I20@PURE_QUANTA.GENOA_SP5(CHIPS)':
 'VSS_M15': CDS_PINID='VSS_M15';
NODE_NAME     U25 M17
 '@T6G_MB_LIB.T6G(SCH_1):PAGE31_I20@PURE_QUANTA.GENOA_SP5(CHIPS)':
 'VSS_M17': CDS_PINID='VSS_M17';
NODE_NAME     U25 M19
 '@T6G_MB_LIB.T6G(SCH_1):PAGE31_I20@PURE_QUANTA.GENOA_SP5(CHIPS)':
 'VSS_M19': CDS_PINID='VSS_M19';
NODE_NAME     U25 M22
 '@T6G_MB_LIB.T6G(SCH_1):PAGE31_I20@PURE_QUANTA.GENOA_SP5(CHIPS)':
 'VSS_M22': CDS_PINID='VSS_M22';
NODE_NAME     U25 M25
 '@T6G_MB_LIB.T6G(SCH_1):PAGE31_I20@PURE_QUANTA.GENOA_SP5(CHIPS)':
 'VSS_M25': CDS_PINID='VSS_M25';
NODE_NAME     U25 M28
 '@T6G_MB_LIB.T6G(SCH_1):PAGE31_I20@PURE_QUANTA.GENOA_SP5(CHIPS)':
 'VSS_M28': CDS_PINID='VSS_M28';
NODE_NAME     U25 M31
 '@T6G_MB_LIB.T6G(SCH_1):PAGE31_I20@PURE_QUANTA.GENOA_SP5(CHIPS)':
 'VSS_M31': CDS_PINID='VSS_M31';
NODE_NAME     U25 M34
 '@T6G_MB_LIB.T6G(SCH_1):PAGE31_I20@PURE_QUANTA.GENOA_SP5(CHIPS)':
 'VSS_M34': CDS_PINID='VSS_M34';
NODE_NAME     U25 M37
 '@T6G_MB_LIB.T6G(SCH_1):PAGE31_I20@PURE_QUANTA.GENOA_SP5(CHIPS)':
 'VSS_M37': CDS_PINID='VSS_M37';
NODE_NAME     U25 M39
 '@T6G_MB_LIB.T6G(SCH_1):PAGE31_I20@PURE_QUANTA.GENOA_SP5(CHIPS)':
 'VSS_M39': CDS_PINID='VSS_M39';
NODE_NAME     U25 M42
 '@T6G_MB_LIB.T6G(SCH_1):PAGE31_I20@PURE_QUANTA.GENOA_SP5(CHIPS)':
 'VSS_M42': CDS_PINID='VSS_M42';
NODE_NAME     U25 M45
 '@T6G_MB_LIB.T6G(SCH_1):PAGE31_I20@PURE_QUANTA.GENOA_SP5(CHIPS)':
 'VSS_M45': CDS_PINID='VSS_M45';
NODE_NAME     U25 M48
 '@T6G_MB_LIB.T6G(SCH_1):PAGE31_I20@PURE_QUANTA.GENOA_SP5(CHIPS)':
 'VSS_M48': CDS_PINID='VSS_M48';
NODE_NAME     U25 M51
 '@T6G_MB_LIB.T6G(SCH_1):PAGE31_I20@PURE_QUANTA.GENOA_SP5(CHIPS)':
 'VSS_M51': CDS_PINID='VSS_M51';
NODE_NAME     U25 M54
 '@T6G_MB_LIB.T6G(SCH_1):PAGE31_I20@PURE_QUANTA.GENOA_SP5(CHIPS)':
 'VSS_M54': CDS_PINID='VSS_M54';
NODE_NAME     U25 M57
 '@T6G_MB_LIB.T6G(SCH_1):PAGE31_I20@PURE_QUANTA.GENOA_SP5(CHIPS)':
 'VSS_M57': CDS_PINID='VSS_M57';
NODE_NAME     U25 M59
 '@T6G_MB_LIB.T6G(SCH_1):PAGE31_I20@PURE_QUANTA.GENOA_SP5(CHIPS)':
 'VSS_M59': CDS_PINID='VSS_M59';
NODE_NAME     U25 M61
 '@T6G_MB_LIB.T6G(SCH_1):PAGE31_I20@PURE_QUANTA.GENOA_SP5(CHIPS)':
 'VSS_M61': CDS_PINID='VSS_M61';
NODE_NAME     U25 M64
 '@T6G_MB_LIB.T6G(SCH_1):PAGE31_I20@PURE_QUANTA.GENOA_SP5(CHIPS)':
 'VSS_M64': CDS_PINID='VSS_M64';
NODE_NAME     U25 M66
 '@T6G_MB_LIB.T6G(SCH_1):PAGE31_I20@PURE_QUANTA.GENOA_SP5(CHIPS)':
 'VSS_M66': CDS_PINID='VSS_M66';
NODE_NAME     U25 M68
 '@T6G_MB_LIB.T6G(SCH_1):PAGE31_I20@PURE_QUANTA.GENOA_SP5(CHIPS)':
 'VSS_M68': CDS_PINID='VSS_M68';
NODE_NAME     U25 M71
 '@T6G_MB_LIB.T6G(SCH_1):PAGE31_I20@PURE_QUANTA.GENOA_SP5(CHIPS)':
 'VSS_M71': CDS_PINID='VSS_M71';
NODE_NAME     U25 M73
 '@T6G_MB_LIB.T6G(SCH_1):PAGE31_I20@PURE_QUANTA.GENOA_SP5(CHIPS)':
 'VSS_M73': CDS_PINID='VSS_M73';
NODE_NAME     U25 N1
 '@T6G_MB_LIB.T6G(SCH_1):PAGE31_I20@PURE_QUANTA.GENOA_SP5(CHIPS)':
 'VSS_N1': CDS_PINID='VSS_N1';
NODE_NAME     U25 N4
 '@T6G_MB_LIB.T6G(SCH_1):PAGE31_I20@PURE_QUANTA.GENOA_SP5(CHIPS)':
 'VSS_N4': CDS_PINID='VSS_N4';
NODE_NAME     U25 N6
 '@T6G_MB_LIB.T6G(SCH_1):PAGE31_I20@PURE_QUANTA.GENOA_SP5(CHIPS)':
 'VSS_N6': CDS_PINID='VSS_N6';
NODE_NAME     U25 N8
 '@T6G_MB_LIB.T6G(SCH_1):PAGE31_I20@PURE_QUANTA.GENOA_SP5(CHIPS)':
 'VSS_N8': CDS_PINID='VSS_N8';
NODE_NAME     U25 N11
 '@T6G_MB_LIB.T6G(SCH_1):PAGE31_I20@PURE_QUANTA.GENOA_SP5(CHIPS)':
 'VSS_N11': CDS_PINID='VSS_N11';
NODE_NAME     U25 N13
 '@T6G_MB_LIB.T6G(SCH_1):PAGE31_I20@PURE_QUANTA.GENOA_SP5(CHIPS)':
 'VSS_N13': CDS_PINID='VSS_N13';
NODE_NAME     U25 N15
 '@T6G_MB_LIB.T6G(SCH_1):PAGE31_I20@PURE_QUANTA.GENOA_SP5(CHIPS)':
 'VSS_N15': CDS_PINID='VSS_N15';
NODE_NAME     U25 N18
 '@T6G_MB_LIB.T6G(SCH_1):PAGE31_I20@PURE_QUANTA.GENOA_SP5(CHIPS)':
 'VSS_N18': CDS_PINID='VSS_N18';
NODE_NAME     U25 N20
 '@T6G_MB_LIB.T6G(SCH_1):PAGE31_I20@PURE_QUANTA.GENOA_SP5(CHIPS)':
 'VSS_N20': CDS_PINID='VSS_N20';
NODE_NAME     U25 N22
 '@T6G_MB_LIB.T6G(SCH_1):PAGE31_I20@PURE_QUANTA.GENOA_SP5(CHIPS)':
 'VSS_N22': CDS_PINID='VSS_N22';
NODE_NAME     U25 N25
 '@T6G_MB_LIB.T6G(SCH_1):PAGE31_I20@PURE_QUANTA.GENOA_SP5(CHIPS)':
 'VSS_N25': CDS_PINID='VSS_N25';
NODE_NAME     U25 N28
 '@T6G_MB_LIB.T6G(SCH_1):PAGE31_I20@PURE_QUANTA.GENOA_SP5(CHIPS)':
 'VSS_N28': CDS_PINID='VSS_N28';
NODE_NAME     U25 N31
 '@T6G_MB_LIB.T6G(SCH_1):PAGE31_I20@PURE_QUANTA.GENOA_SP5(CHIPS)':
 'VSS_N31': CDS_PINID='VSS_N31';
NODE_NAME     U25 N34
 '@T6G_MB_LIB.T6G(SCH_1):PAGE31_I20@PURE_QUANTA.GENOA_SP5(CHIPS)':
 'VSS_N34': CDS_PINID='VSS_N34';
NODE_NAME     U25 N42
 '@T6G_MB_LIB.T6G(SCH_1):PAGE31_I20@PURE_QUANTA.GENOA_SP5(CHIPS)':
 'VSS_N42': CDS_PINID='VSS_N42';
NODE_NAME     U25 N45
 '@T6G_MB_LIB.T6G(SCH_1):PAGE31_I20@PURE_QUANTA.GENOA_SP5(CHIPS)':
 'VSS_N45': CDS_PINID='VSS_N45';
NODE_NAME     U25 N48
 '@T6G_MB_LIB.T6G(SCH_1):PAGE31_I20@PURE_QUANTA.GENOA_SP5(CHIPS)':
 'VSS_N48': CDS_PINID='VSS_N48';
NODE_NAME     U25 N51
 '@T6G_MB_LIB.T6G(SCH_1):PAGE31_I20@PURE_QUANTA.GENOA_SP5(CHIPS)':
 'VSS_N51': CDS_PINID='VSS_N51';
NODE_NAME     U25 N54
 '@T6G_MB_LIB.T6G(SCH_1):PAGE31_I20@PURE_QUANTA.GENOA_SP5(CHIPS)':
 'VSS_N54': CDS_PINID='VSS_N54';
NODE_NAME     U25 N56
 '@T6G_MB_LIB.T6G(SCH_1):PAGE31_I20@PURE_QUANTA.GENOA_SP5(CHIPS)':
 'VSS_N56': CDS_PINID='VSS_N56';
NODE_NAME     U25 N58
 '@T6G_MB_LIB.T6G(SCH_1):PAGE31_I20@PURE_QUANTA.GENOA_SP5(CHIPS)':
 'VSS_N58': CDS_PINID='VSS_N58';
NODE_NAME     U25 N61
 '@T6G_MB_LIB.T6G(SCH_1):PAGE31_I20@PURE_QUANTA.GENOA_SP5(CHIPS)':
 'VSS_N61': CDS_PINID='VSS_N61';
NODE_NAME     U25 N63
 '@T6G_MB_LIB.T6G(SCH_1):PAGE31_I20@PURE_QUANTA.GENOA_SP5(CHIPS)':
 'VSS_N63': CDS_PINID='VSS_N63';
NODE_NAME     U25 N65
 '@T6G_MB_LIB.T6G(SCH_1):PAGE31_I20@PURE_QUANTA.GENOA_SP5(CHIPS)':
 'VSS_N65': CDS_PINID='VSS_N65';
NODE_NAME     U25 N68
 '@T6G_MB_LIB.T6G(SCH_1):PAGE31_I20@PURE_QUANTA.GENOA_SP5(CHIPS)':
 'VSS_N68': CDS_PINID='VSS_N68';
NODE_NAME     U25 N70
 '@T6G_MB_LIB.T6G(SCH_1):PAGE31_I20@PURE_QUANTA.GENOA_SP5(CHIPS)':
 'VSS_N70': CDS_PINID='VSS_N70';
NODE_NAME     U25 N72
 '@T6G_MB_LIB.T6G(SCH_1):PAGE31_I20@PURE_QUANTA.GENOA_SP5(CHIPS)':
 'VSS_N72': CDS_PINID='VSS_N72';
NODE_NAME     U25 N75
 '@T6G_MB_LIB.T6G(SCH_1):PAGE31_I20@PURE_QUANTA.GENOA_SP5(CHIPS)':
 'VSS_N75': CDS_PINID='VSS_N75';
NODE_NAME     U25 P3
 '@T6G_MB_LIB.T6G(SCH_1):PAGE31_I20@PURE_QUANTA.GENOA_SP5(CHIPS)':
 'VSS_P3': CDS_PINID='VSS_P3';
NODE_NAME     U25 P8
 '@T6G_MB_LIB.T6G(SCH_1):PAGE31_I20@PURE_QUANTA.GENOA_SP5(CHIPS)':
 'VSS_P8': CDS_PINID='VSS_P8';
NODE_NAME     U25 P10
 '@T6G_MB_LIB.T6G(SCH_1):PAGE31_I20@PURE_QUANTA.GENOA_SP5(CHIPS)':
 'VSS_P10': CDS_PINID='VSS_P10';
NODE_NAME     U25 P15
 '@T6G_MB_LIB.T6G(SCH_1):PAGE31_I20@PURE_QUANTA.GENOA_SP5(CHIPS)':
 'VSS_P15': CDS_PINID='VSS_P15';
NODE_NAME     U25 P17
 '@T6G_MB_LIB.T6G(SCH_1):PAGE31_I20@PURE_QUANTA.GENOA_SP5(CHIPS)':
 'VSS_P17': CDS_PINID='VSS_P17';
NODE_NAME     U25 P23
 '@T6G_MB_LIB.T6G(SCH_1):PAGE31_I20@PURE_QUANTA.GENOA_SP5(CHIPS)':
 'VSS_P23': CDS_PINID='VSS_P23';
NODE_NAME     U25 P24
 '@T6G_MB_LIB.T6G(SCH_1):PAGE31_I20@PURE_QUANTA.GENOA_SP5(CHIPS)':
 'VSS_P24': CDS_PINID='VSS_P24';
NODE_NAME     U25 P26
 '@T6G_MB_LIB.T6G(SCH_1):PAGE31_I20@PURE_QUANTA.GENOA_SP5(CHIPS)':
 'VSS_P26': CDS_PINID='VSS_P26';
NODE_NAME     U25 P27
 '@T6G_MB_LIB.T6G(SCH_1):PAGE31_I20@PURE_QUANTA.GENOA_SP5(CHIPS)':
 'VSS_P27': CDS_PINID='VSS_P27';
NODE_NAME     U25 P28
 '@T6G_MB_LIB.T6G(SCH_1):PAGE31_I20@PURE_QUANTA.GENOA_SP5(CHIPS)':
 'VSS_P28': CDS_PINID='VSS_P28';
NODE_NAME     U25 P29
 '@T6G_MB_LIB.T6G(SCH_1):PAGE31_I20@PURE_QUANTA.GENOA_SP5(CHIPS)':
 'VSS_P29': CDS_PINID='VSS_P29';
NODE_NAME     U25 P30
 '@T6G_MB_LIB.T6G(SCH_1):PAGE31_I20@PURE_QUANTA.GENOA_SP5(CHIPS)':
 'VSS_P30': CDS_PINID='VSS_P30';
NODE_NAME     U25 P31
 '@T6G_MB_LIB.T6G(SCH_1):PAGE31_I20@PURE_QUANTA.GENOA_SP5(CHIPS)':
 'VSS_P31': CDS_PINID='VSS_P31';
NODE_NAME     U25 P32
 '@T6G_MB_LIB.T6G(SCH_1):PAGE31_I20@PURE_QUANTA.GENOA_SP5(CHIPS)':
 'VSS_P32': CDS_PINID='VSS_P32';
NODE_NAME     U25 P33
 '@T6G_MB_LIB.T6G(SCH_1):PAGE31_I20@PURE_QUANTA.GENOA_SP5(CHIPS)':
 'VSS_P33': CDS_PINID='VSS_P33';
NODE_NAME     U25 P34
 '@T6G_MB_LIB.T6G(SCH_1):PAGE31_I20@PURE_QUANTA.GENOA_SP5(CHIPS)':
 'VSS_P34': CDS_PINID='VSS_P34';
NODE_NAME     U25 P37
 '@T6G_MB_LIB.T6G(SCH_1):PAGE31_I20@PURE_QUANTA.GENOA_SP5(CHIPS)':
 'VSS_P37': CDS_PINID='VSS_P37';
NODE_NAME     U25 P39
 '@T6G_MB_LIB.T6G(SCH_1):PAGE31_I20@PURE_QUANTA.GENOA_SP5(CHIPS)':
 'VSS_P39': CDS_PINID='VSS_P39';
NODE_NAME     U25 P42
 '@T6G_MB_LIB.T6G(SCH_1):PAGE31_I20@PURE_QUANTA.GENOA_SP5(CHIPS)':
 'VSS_P42': CDS_PINID='VSS_P42';
NODE_NAME     U25 P43
 '@T6G_MB_LIB.T6G(SCH_1):PAGE31_I20@PURE_QUANTA.GENOA_SP5(CHIPS)':
 'VSS_P43': CDS_PINID='VSS_P43';
NODE_NAME     U25 P44
 '@T6G_MB_LIB.T6G(SCH_1):PAGE31_I20@PURE_QUANTA.GENOA_SP5(CHIPS)':
 'VSS_P44': CDS_PINID='VSS_P44';
NODE_NAME     U25 P45
 '@T6G_MB_LIB.T6G(SCH_1):PAGE31_I20@PURE_QUANTA.GENOA_SP5(CHIPS)':
 'VSS_P45': CDS_PINID='VSS_P45';
NODE_NAME     U25 P46
 '@T6G_MB_LIB.T6G(SCH_1):PAGE31_I20@PURE_QUANTA.GENOA_SP5(CHIPS)':
 'VSS_P46': CDS_PINID='VSS_P46';
NODE_NAME     U25 P47
 '@T6G_MB_LIB.T6G(SCH_1):PAGE31_I20@PURE_QUANTA.GENOA_SP5(CHIPS)':
 'VSS_P47': CDS_PINID='VSS_P47';
NODE_NAME     U25 P48
 '@T6G_MB_LIB.T6G(SCH_1):PAGE31_I20@PURE_QUANTA.GENOA_SP5(CHIPS)':
 'VSS_P48': CDS_PINID='VSS_P48';
NODE_NAME     U25 P49
 '@T6G_MB_LIB.T6G(SCH_1):PAGE31_I20@PURE_QUANTA.GENOA_SP5(CHIPS)':
 'VSS_P49': CDS_PINID='VSS_P49';
NODE_NAME     U25 P50
 '@T6G_MB_LIB.T6G(SCH_1):PAGE31_I20@PURE_QUANTA.GENOA_SP5(CHIPS)':
 'VSS_P50': CDS_PINID='VSS_P50';
NODE_NAME     U25 P51
 '@T6G_MB_LIB.T6G(SCH_1):PAGE31_I20@PURE_QUANTA.GENOA_SP5(CHIPS)':
 'VSS_P51': CDS_PINID='VSS_P51';
NODE_NAME     U25 P52
 '@T6G_MB_LIB.T6G(SCH_1):PAGE31_I20@PURE_QUANTA.GENOA_SP5(CHIPS)':
 'VSS_P52': CDS_PINID='VSS_P52';
NODE_NAME     U25 P53
 '@T6G_MB_LIB.T6G(SCH_1):PAGE31_I20@PURE_QUANTA.GENOA_SP5(CHIPS)':
 'VSS_P53': CDS_PINID='VSS_P53';
NODE_NAME     U25 P59
 '@T6G_MB_LIB.T6G(SCH_1):PAGE31_I20@PURE_QUANTA.GENOA_SP5(CHIPS)':
 'VSS_P59': CDS_PINID='VSS_P59';
NODE_NAME     U25 P61
 '@T6G_MB_LIB.T6G(SCH_1):PAGE31_I20@PURE_QUANTA.GENOA_SP5(CHIPS)':
 'VSS_P61': CDS_PINID='VSS_P61';
NODE_NAME     U25 P66
 '@T6G_MB_LIB.T6G(SCH_1):PAGE31_I20@PURE_QUANTA.GENOA_SP5(CHIPS)':
 'VSS_P66': CDS_PINID='VSS_P66';
NODE_NAME     U25 P73
 '@T6G_MB_LIB.T6G(SCH_1):PAGE31_I20@PURE_QUANTA.GENOA_SP5(CHIPS)':
 'VSS_P73': CDS_PINID='VSS_P73';
NODE_NAME     U25 R1
 '@T6G_MB_LIB.T6G(SCH_1):PAGE31_I20@PURE_QUANTA.GENOA_SP5(CHIPS)':
 'VSS_R1': CDS_PINID='VSS_R1';
NODE_NAME     U25 R4
 '@T6G_MB_LIB.T6G(SCH_1):PAGE31_I20@PURE_QUANTA.GENOA_SP5(CHIPS)':
 'VSS_R4': CDS_PINID='VSS_R4';
NODE_NAME     U25 R6
 '@T6G_MB_LIB.T6G(SCH_1):PAGE31_I20@PURE_QUANTA.GENOA_SP5(CHIPS)':
 'VSS_R6': CDS_PINID='VSS_R6';
NODE_NAME     U25 R8
 '@T6G_MB_LIB.T6G(SCH_1):PAGE31_I20@PURE_QUANTA.GENOA_SP5(CHIPS)':
 'VSS_R8': CDS_PINID='VSS_R8';
NODE_NAME     U25 R11
 '@T6G_MB_LIB.T6G(SCH_1):PAGE31_I20@PURE_QUANTA.GENOA_SP5(CHIPS)':
 'VSS_R11': CDS_PINID='VSS_R11';
NODE_NAME     U25 R13
 '@T6G_MB_LIB.T6G(SCH_1):PAGE31_I20@PURE_QUANTA.GENOA_SP5(CHIPS)':
 'VSS_R13': CDS_PINID='VSS_R13';
NODE_NAME     U25 R15
 '@T6G_MB_LIB.T6G(SCH_1):PAGE31_I20@PURE_QUANTA.GENOA_SP5(CHIPS)':
 'VSS_R15': CDS_PINID='VSS_R15';
NODE_NAME     U25 R18
 '@T6G_MB_LIB.T6G(SCH_1):PAGE31_I20@PURE_QUANTA.GENOA_SP5(CHIPS)':
 'VSS_R18': CDS_PINID='VSS_R18';
NODE_NAME     U25 R20
 '@T6G_MB_LIB.T6G(SCH_1):PAGE31_I20@PURE_QUANTA.GENOA_SP5(CHIPS)':
 'VSS_R20': CDS_PINID='VSS_R20';
NODE_NAME     U25 R22
 '@T6G_MB_LIB.T6G(SCH_1):PAGE31_I20@PURE_QUANTA.GENOA_SP5(CHIPS)':
 'VSS_R22': CDS_PINID='VSS_R22';
NODE_NAME     U25 R25
 '@T6G_MB_LIB.T6G(SCH_1):PAGE31_I20@PURE_QUANTA.GENOA_SP5(CHIPS)':
 'VSS_R25': CDS_PINID='VSS_R25';
NODE_NAME     U25 R28
 '@T6G_MB_LIB.T6G(SCH_1):PAGE31_I20@PURE_QUANTA.GENOA_SP5(CHIPS)':
 'VSS_R28': CDS_PINID='VSS_R28';
NODE_NAME     U25 R31
 '@T6G_MB_LIB.T6G(SCH_1):PAGE31_I20@PURE_QUANTA.GENOA_SP5(CHIPS)':
 'VSS_R31': CDS_PINID='VSS_R31';
NODE_NAME     U25 R34
 '@T6G_MB_LIB.T6G(SCH_1):PAGE31_I20@PURE_QUANTA.GENOA_SP5(CHIPS)':
 'VSS_R34': CDS_PINID='VSS_R34';
NODE_NAME     U25 R35
 '@T6G_MB_LIB.T6G(SCH_1):PAGE31_I20@PURE_QUANTA.GENOA_SP5(CHIPS)':
 'VSS_R35': CDS_PINID='VSS_R35';
NODE_NAME     U25 R36
 '@T6G_MB_LIB.T6G(SCH_1):PAGE31_I20@PURE_QUANTA.GENOA_SP5(CHIPS)':
 'VSS_R36': CDS_PINID='VSS_R36';
NODE_NAME     U25 R40
 '@T6G_MB_LIB.T6G(SCH_1):PAGE31_I20@PURE_QUANTA.GENOA_SP5(CHIPS)':
 'VSS_R40': CDS_PINID='VSS_R40';
NODE_NAME     U25 R41
 '@T6G_MB_LIB.T6G(SCH_1):PAGE31_I20@PURE_QUANTA.GENOA_SP5(CHIPS)':
 'VSS_R41': CDS_PINID='VSS_R41';
NODE_NAME     U25 R42
 '@T6G_MB_LIB.T6G(SCH_1):PAGE31_I20@PURE_QUANTA.GENOA_SP5(CHIPS)':
 'VSS_R42': CDS_PINID='VSS_R42';
NODE_NAME     U25 R45
 '@T6G_MB_LIB.T6G(SCH_1):PAGE31_I20@PURE_QUANTA.GENOA_SP5(CHIPS)':
 'VSS_R45': CDS_PINID='VSS_R45';
NODE_NAME     U25 R48
 '@T6G_MB_LIB.T6G(SCH_1):PAGE31_I20@PURE_QUANTA.GENOA_SP5(CHIPS)':
 'VSS_R48': CDS_PINID='VSS_R48';
NODE_NAME     U25 R51
 '@T6G_MB_LIB.T6G(SCH_1):PAGE31_I20@PURE_QUANTA.GENOA_SP5(CHIPS)':
 'VSS_R51': CDS_PINID='VSS_R51';
NODE_NAME     U25 R54
 '@T6G_MB_LIB.T6G(SCH_1):PAGE31_I20@PURE_QUANTA.GENOA_SP5(CHIPS)':
 'VSS_R54': CDS_PINID='VSS_R54';
NODE_NAME     U25 R56
 '@T6G_MB_LIB.T6G(SCH_1):PAGE31_I20@PURE_QUANTA.GENOA_SP5(CHIPS)':
 'VSS_R56': CDS_PINID='VSS_R56';
NODE_NAME     U25 R58
 '@T6G_MB_LIB.T6G(SCH_1):PAGE31_I20@PURE_QUANTA.GENOA_SP5(CHIPS)':
 'VSS_R58': CDS_PINID='VSS_R58';
NODE_NAME     U25 R61
 '@T6G_MB_LIB.T6G(SCH_1):PAGE31_I20@PURE_QUANTA.GENOA_SP5(CHIPS)':
 'VSS_R61': CDS_PINID='VSS_R61';
NODE_NAME     U25 R63
 '@T6G_MB_LIB.T6G(SCH_1):PAGE31_I20@PURE_QUANTA.GENOA_SP5(CHIPS)':
 'VSS_R63': CDS_PINID='VSS_R63';
NODE_NAME     U25 R65
 '@T6G_MB_LIB.T6G(SCH_1):PAGE31_I20@PURE_QUANTA.GENOA_SP5(CHIPS)':
 'VSS_R65': CDS_PINID='VSS_R65';
NODE_NAME     U25 R68
 '@T6G_MB_LIB.T6G(SCH_1):PAGE31_I20@PURE_QUANTA.GENOA_SP5(CHIPS)':
 'VSS_R68': CDS_PINID='VSS_R68';
NODE_NAME     U25 R70
 '@T6G_MB_LIB.T6G(SCH_1):PAGE31_I20@PURE_QUANTA.GENOA_SP5(CHIPS)':
 'VSS_R70': CDS_PINID='VSS_R70';
NODE_NAME     U25 R72
 '@T6G_MB_LIB.T6G(SCH_1):PAGE31_I20@PURE_QUANTA.GENOA_SP5(CHIPS)':
 'VSS_R72': CDS_PINID='VSS_R72';
NODE_NAME     U25 R75
 '@T6G_MB_LIB.T6G(SCH_1):PAGE31_I20@PURE_QUANTA.GENOA_SP5(CHIPS)':
 'VSS_R75': CDS_PINID='VSS_R75';
NODE_NAME     U25 T3
 '@T6G_MB_LIB.T6G(SCH_1):PAGE31_I20@PURE_QUANTA.GENOA_SP5(CHIPS)':
 'VSS_T3': CDS_PINID='VSS_T3';
NODE_NAME     U25 T5
 '@T6G_MB_LIB.T6G(SCH_1):PAGE31_I20@PURE_QUANTA.GENOA_SP5(CHIPS)':
 'VSS_T5': CDS_PINID='VSS_T5';
NODE_NAME     U25 T8
 '@T6G_MB_LIB.T6G(SCH_1):PAGE31_I20@PURE_QUANTA.GENOA_SP5(CHIPS)':
 'VSS_T8': CDS_PINID='VSS_T8';
NODE_NAME     U25 T10
 '@T6G_MB_LIB.T6G(SCH_1):PAGE31_I20@PURE_QUANTA.GENOA_SP5(CHIPS)':
 'VSS_T10': CDS_PINID='VSS_T10';
NODE_NAME     U25 T12
 '@T6G_MB_LIB.T6G(SCH_1):PAGE31_I20@PURE_QUANTA.GENOA_SP5(CHIPS)':
 'VSS_T12': CDS_PINID='VSS_T12';
NODE_NAME     U25 T15
 '@T6G_MB_LIB.T6G(SCH_1):PAGE31_I20@PURE_QUANTA.GENOA_SP5(CHIPS)':
 'VSS_T15': CDS_PINID='VSS_T15';
NODE_NAME     U25 T17
 '@T6G_MB_LIB.T6G(SCH_1):PAGE31_I20@PURE_QUANTA.GENOA_SP5(CHIPS)':
 'VSS_T17': CDS_PINID='VSS_T17';
NODE_NAME     U25 T19
 '@T6G_MB_LIB.T6G(SCH_1):PAGE31_I20@PURE_QUANTA.GENOA_SP5(CHIPS)':
 'VSS_T19': CDS_PINID='VSS_T19';
NODE_NAME     U25 T22
 '@T6G_MB_LIB.T6G(SCH_1):PAGE31_I20@PURE_QUANTA.GENOA_SP5(CHIPS)':
 'VSS_T22': CDS_PINID='VSS_T22';
NODE_NAME     U25 T25
 '@T6G_MB_LIB.T6G(SCH_1):PAGE31_I20@PURE_QUANTA.GENOA_SP5(CHIPS)':
 'VSS_T25': CDS_PINID='VSS_T25';
NODE_NAME     U25 T28
 '@T6G_MB_LIB.T6G(SCH_1):PAGE31_I20@PURE_QUANTA.GENOA_SP5(CHIPS)':
 'VSS_T28': CDS_PINID='VSS_T28';
NODE_NAME     U25 T31
 '@T6G_MB_LIB.T6G(SCH_1):PAGE31_I20@PURE_QUANTA.GENOA_SP5(CHIPS)':
 'VSS_T31': CDS_PINID='VSS_T31';
NODE_NAME     U25 T34
 '@T6G_MB_LIB.T6G(SCH_1):PAGE31_I20@PURE_QUANTA.GENOA_SP5(CHIPS)':
 'VSS_T34': CDS_PINID='VSS_T34';
NODE_NAME     U25 T37
 '@T6G_MB_LIB.T6G(SCH_1):PAGE31_I20@PURE_QUANTA.GENOA_SP5(CHIPS)':
 'VSS_T37': CDS_PINID='VSS_T37';
NODE_NAME     U25 T39
 '@T6G_MB_LIB.T6G(SCH_1):PAGE31_I20@PURE_QUANTA.GENOA_SP5(CHIPS)':
 'VSS_T39': CDS_PINID='VSS_T39';
NODE_NAME     U25 T42
 '@T6G_MB_LIB.T6G(SCH_1):PAGE31_I20@PURE_QUANTA.GENOA_SP5(CHIPS)':
 'VSS_T42': CDS_PINID='VSS_T42';
NODE_NAME     U25 T45
 '@T6G_MB_LIB.T6G(SCH_1):PAGE31_I20@PURE_QUANTA.GENOA_SP5(CHIPS)':
 'VSS_T45': CDS_PINID='VSS_T45';
NODE_NAME     U25 T48
 '@T6G_MB_LIB.T6G(SCH_1):PAGE31_I20@PURE_QUANTA.GENOA_SP5(CHIPS)':
 'VSS_T48': CDS_PINID='VSS_T48';
NODE_NAME     U25 T51
 '@T6G_MB_LIB.T6G(SCH_1):PAGE31_I20@PURE_QUANTA.GENOA_SP5(CHIPS)':
 'VSS_T51': CDS_PINID='VSS_T51';
NODE_NAME     U25 T54
 '@T6G_MB_LIB.T6G(SCH_1):PAGE31_I20@PURE_QUANTA.GENOA_SP5(CHIPS)':
 'VSS_T54': CDS_PINID='VSS_T54';
NODE_NAME     U25 T57
 '@T6G_MB_LIB.T6G(SCH_1):PAGE31_I20@PURE_QUANTA.GENOA_SP5(CHIPS)':
 'VSS_T57': CDS_PINID='VSS_T57';
NODE_NAME     U25 T59
 '@T6G_MB_LIB.T6G(SCH_1):PAGE31_I20@PURE_QUANTA.GENOA_SP5(CHIPS)':
 'VSS_T59': CDS_PINID='VSS_T59';
NODE_NAME     U25 T61
 '@T6G_MB_LIB.T6G(SCH_1):PAGE31_I20@PURE_QUANTA.GENOA_SP5(CHIPS)':
 'VSS_T61': CDS_PINID='VSS_T61';
NODE_NAME     U25 T64
 '@T6G_MB_LIB.T6G(SCH_1):PAGE31_I20@PURE_QUANTA.GENOA_SP5(CHIPS)':
 'VSS_T64': CDS_PINID='VSS_T64';
NODE_NAME     U25 AA1
 '@T6G_MB_LIB.T6G(SCH_1):PAGE31_I21@PURE_QUANTA.GENOA_SP5(CHIPS)':
 'VSS_AA1': CDS_PINID='VSS_AA1';
NODE_NAME     U25 AA4
 '@T6G_MB_LIB.T6G(SCH_1):PAGE31_I21@PURE_QUANTA.GENOA_SP5(CHIPS)':
 'VSS_AA4': CDS_PINID='VSS_AA4';
NODE_NAME     U25 AA6
 '@T6G_MB_LIB.T6G(SCH_1):PAGE31_I21@PURE_QUANTA.GENOA_SP5(CHIPS)':
 'VSS_AA6': CDS_PINID='VSS_AA6';
NODE_NAME     U25 AA8
 '@T6G_MB_LIB.T6G(SCH_1):PAGE31_I21@PURE_QUANTA.GENOA_SP5(CHIPS)':
 'VSS_AA8': CDS_PINID='VSS_AA8';
NODE_NAME     U25 AA11
 '@T6G_MB_LIB.T6G(SCH_1):PAGE31_I21@PURE_QUANTA.GENOA_SP5(CHIPS)':
 'VSS_AA11': CDS_PINID='VSS_AA11';
NODE_NAME     U25 AA13
 '@T6G_MB_LIB.T6G(SCH_1):PAGE31_I21@PURE_QUANTA.GENOA_SP5(CHIPS)':
 'VSS_AA13': CDS_PINID='VSS_AA13';
NODE_NAME     U25 AA15
 '@T6G_MB_LIB.T6G(SCH_1):PAGE31_I21@PURE_QUANTA.GENOA_SP5(CHIPS)':
 'VSS_AA15': CDS_PINID='VSS_AA15';
NODE_NAME     U25 AA18
 '@T6G_MB_LIB.T6G(SCH_1):PAGE31_I21@PURE_QUANTA.GENOA_SP5(CHIPS)':
 'VSS_AA18': CDS_PINID='VSS_AA18';
NODE_NAME     U25 AA20
 '@T6G_MB_LIB.T6G(SCH_1):PAGE31_I21@PURE_QUANTA.GENOA_SP5(CHIPS)':
 'VSS_AA20': CDS_PINID='VSS_AA20';
NODE_NAME     U25 AA31
 '@T6G_MB_LIB.T6G(SCH_1):PAGE31_I21@PURE_QUANTA.GENOA_SP5(CHIPS)':
 'VSS_AA31': CDS_PINID='VSS_AA31';
NODE_NAME     U25 AA34
 '@T6G_MB_LIB.T6G(SCH_1):PAGE31_I21@PURE_QUANTA.GENOA_SP5(CHIPS)':
 'VSS_AA34': CDS_PINID='VSS_AA34';
NODE_NAME     U25 AA35
 '@T6G_MB_LIB.T6G(SCH_1):PAGE31_I21@PURE_QUANTA.GENOA_SP5(CHIPS)':
 'VSS_AA35': CDS_PINID='VSS_AA35';
NODE_NAME     U25 AA36
 '@T6G_MB_LIB.T6G(SCH_1):PAGE31_I21@PURE_QUANTA.GENOA_SP5(CHIPS)':
 'VSS_AA36': CDS_PINID='VSS_AA36';
NODE_NAME     U25 AA40
 '@T6G_MB_LIB.T6G(SCH_1):PAGE31_I21@PURE_QUANTA.GENOA_SP5(CHIPS)':
 'VSS_AA40': CDS_PINID='VSS_AA40';
NODE_NAME     U25 AA41
 '@T6G_MB_LIB.T6G(SCH_1):PAGE31_I21@PURE_QUANTA.GENOA_SP5(CHIPS)':
 'VSS_AA41': CDS_PINID='VSS_AA41';
NODE_NAME     U25 AA45
 '@T6G_MB_LIB.T6G(SCH_1):PAGE31_I21@PURE_QUANTA.GENOA_SP5(CHIPS)':
 'VSS_AA45': CDS_PINID='VSS_AA45';
NODE_NAME     U25 AA56
 '@T6G_MB_LIB.T6G(SCH_1):PAGE31_I21@PURE_QUANTA.GENOA_SP5(CHIPS)':
 'VSS_AA56': CDS_PINID='VSS_AA56';
NODE_NAME     U25 AA58
 '@T6G_MB_LIB.T6G(SCH_1):PAGE31_I21@PURE_QUANTA.GENOA_SP5(CHIPS)':
 'VSS_AA58': CDS_PINID='VSS_AA58';
NODE_NAME     U25 AA61
 '@T6G_MB_LIB.T6G(SCH_1):PAGE31_I21@PURE_QUANTA.GENOA_SP5(CHIPS)':
 'VSS_AA61': CDS_PINID='VSS_AA61';
NODE_NAME     U25 AA63
 '@T6G_MB_LIB.T6G(SCH_1):PAGE31_I21@PURE_QUANTA.GENOA_SP5(CHIPS)':
 'VSS_AA63': CDS_PINID='VSS_AA63';
NODE_NAME     U25 AA65
 '@T6G_MB_LIB.T6G(SCH_1):PAGE31_I21@PURE_QUANTA.GENOA_SP5(CHIPS)':
 'VSS_AA65': CDS_PINID='VSS_AA65';
NODE_NAME     U25 AA68
 '@T6G_MB_LIB.T6G(SCH_1):PAGE31_I21@PURE_QUANTA.GENOA_SP5(CHIPS)':
 'VSS_AA68': CDS_PINID='VSS_AA68';
NODE_NAME     U25 AA70
 '@T6G_MB_LIB.T6G(SCH_1):PAGE31_I21@PURE_QUANTA.GENOA_SP5(CHIPS)':
 'VSS_AA70': CDS_PINID='VSS_AA70';
NODE_NAME     U25 AA75
 '@T6G_MB_LIB.T6G(SCH_1):PAGE31_I21@PURE_QUANTA.GENOA_SP5(CHIPS)':
 'VSS_AA75': CDS_PINID='VSS_AA75';
NODE_NAME     U25 AB3
 '@T6G_MB_LIB.T6G(SCH_1):PAGE31_I21@PURE_QUANTA.GENOA_SP5(CHIPS)':
 'VSS_AB3': CDS_PINID='VSS_AB3';
NODE_NAME     U25 AB5
 '@T6G_MB_LIB.T6G(SCH_1):PAGE31_I21@PURE_QUANTA.GENOA_SP5(CHIPS)':
 'VSS_AB5': CDS_PINID='VSS_AB5';
NODE_NAME     U25 AB8
 '@T6G_MB_LIB.T6G(SCH_1):PAGE31_I21@PURE_QUANTA.GENOA_SP5(CHIPS)':
 'VSS_AB8': CDS_PINID='VSS_AB8';
NODE_NAME     U25 AB10
 '@T6G_MB_LIB.T6G(SCH_1):PAGE31_I21@PURE_QUANTA.GENOA_SP5(CHIPS)':
 'VSS_AB10': CDS_PINID='VSS_AB10';
NODE_NAME     U25 AB12
 '@T6G_MB_LIB.T6G(SCH_1):PAGE31_I21@PURE_QUANTA.GENOA_SP5(CHIPS)':
 'VSS_AB12': CDS_PINID='VSS_AB12';
NODE_NAME     U25 AB15
 '@T6G_MB_LIB.T6G(SCH_1):PAGE31_I21@PURE_QUANTA.GENOA_SP5(CHIPS)':
 'VSS_AB15': CDS_PINID='VSS_AB15';
NODE_NAME     U25 AB17
 '@T6G_MB_LIB.T6G(SCH_1):PAGE31_I21@PURE_QUANTA.GENOA_SP5(CHIPS)':
 'VSS_AB17': CDS_PINID='VSS_AB17';
NODE_NAME     U25 AB19
 '@T6G_MB_LIB.T6G(SCH_1):PAGE31_I21@PURE_QUANTA.GENOA_SP5(CHIPS)':
 'VSS_AB19': CDS_PINID='VSS_AB19';
NODE_NAME     U25 AB22
 '@T6G_MB_LIB.T6G(SCH_1):PAGE31_I21@PURE_QUANTA.GENOA_SP5(CHIPS)':
 'VSS_AB22': CDS_PINID='VSS_AB22';
NODE_NAME     U25 AB25
 '@T6G_MB_LIB.T6G(SCH_1):PAGE31_I21@PURE_QUANTA.GENOA_SP5(CHIPS)':
 'VSS_AB25': CDS_PINID='VSS_AB25';
NODE_NAME     U25 AB28
 '@T6G_MB_LIB.T6G(SCH_1):PAGE31_I21@PURE_QUANTA.GENOA_SP5(CHIPS)':
 'VSS_AB28': CDS_PINID='VSS_AB28';
NODE_NAME     U25 AB31
 '@T6G_MB_LIB.T6G(SCH_1):PAGE31_I21@PURE_QUANTA.GENOA_SP5(CHIPS)':
 'VSS_AB31': CDS_PINID='VSS_AB31';
NODE_NAME     U25 AB34
 '@T6G_MB_LIB.T6G(SCH_1):PAGE31_I21@PURE_QUANTA.GENOA_SP5(CHIPS)':
 'VSS_AB34': CDS_PINID='VSS_AB34';
NODE_NAME     U25 AB37
 '@T6G_MB_LIB.T6G(SCH_1):PAGE31_I21@PURE_QUANTA.GENOA_SP5(CHIPS)':
 'VSS_AB37': CDS_PINID='VSS_AB37';
NODE_NAME     U25 AB39
 '@T6G_MB_LIB.T6G(SCH_1):PAGE31_I21@PURE_QUANTA.GENOA_SP5(CHIPS)':
 'VSS_AB39': CDS_PINID='VSS_AB39';
NODE_NAME     U25 AB42
 '@T6G_MB_LIB.T6G(SCH_1):PAGE31_I21@PURE_QUANTA.GENOA_SP5(CHIPS)':
 'VSS_AB42': CDS_PINID='VSS_AB42';
NODE_NAME     U25 AB45
 '@T6G_MB_LIB.T6G(SCH_1):PAGE31_I21@PURE_QUANTA.GENOA_SP5(CHIPS)':
 'VSS_AB45': CDS_PINID='VSS_AB45';
NODE_NAME     U25 AB48
 '@T6G_MB_LIB.T6G(SCH_1):PAGE31_I21@PURE_QUANTA.GENOA_SP5(CHIPS)':
 'VSS_AB48': CDS_PINID='VSS_AB48';
NODE_NAME     U25 AB51
 '@T6G_MB_LIB.T6G(SCH_1):PAGE31_I21@PURE_QUANTA.GENOA_SP5(CHIPS)':
 'VSS_AB51': CDS_PINID='VSS_AB51';
NODE_NAME     U25 AB54
 '@T6G_MB_LIB.T6G(SCH_1):PAGE31_I21@PURE_QUANTA.GENOA_SP5(CHIPS)':
 'VSS_AB54': CDS_PINID='VSS_AB54';
NODE_NAME     U25 AB57
 '@T6G_MB_LIB.T6G(SCH_1):PAGE31_I21@PURE_QUANTA.GENOA_SP5(CHIPS)':
 'VSS_AB57': CDS_PINID='VSS_AB57';
NODE_NAME     U25 AB59
 '@T6G_MB_LIB.T6G(SCH_1):PAGE31_I21@PURE_QUANTA.GENOA_SP5(CHIPS)':
 'VSS_AB59': CDS_PINID='VSS_AB59';
NODE_NAME     U25 AB61
 '@T6G_MB_LIB.T6G(SCH_1):PAGE31_I21@PURE_QUANTA.GENOA_SP5(CHIPS)':
 'VSS_AB61': CDS_PINID='VSS_AB61';
NODE_NAME     U25 AB64
 '@T6G_MB_LIB.T6G(SCH_1):PAGE31_I21@PURE_QUANTA.GENOA_SP5(CHIPS)':
 'VSS_AB64': CDS_PINID='VSS_AB64';
NODE_NAME     U25 AB66
 '@T6G_MB_LIB.T6G(SCH_1):PAGE31_I21@PURE_QUANTA.GENOA_SP5(CHIPS)':
 'VSS_AB66': CDS_PINID='VSS_AB66';
NODE_NAME     U25 AB68
 '@T6G_MB_LIB.T6G(SCH_1):PAGE31_I21@PURE_QUANTA.GENOA_SP5(CHIPS)':
 'VSS_AB68': CDS_PINID='VSS_AB68';
NODE_NAME     U25 AB71
 '@T6G_MB_LIB.T6G(SCH_1):PAGE31_I21@PURE_QUANTA.GENOA_SP5(CHIPS)':
 'VSS_AB71': CDS_PINID='VSS_AB71';
NODE_NAME     U25 AB73
 '@T6G_MB_LIB.T6G(SCH_1):PAGE31_I21@PURE_QUANTA.GENOA_SP5(CHIPS)':
 'VSS_AB73': CDS_PINID='VSS_AB73';
NODE_NAME     U25 AC1
 '@T6G_MB_LIB.T6G(SCH_1):PAGE31_I21@PURE_QUANTA.GENOA_SP5(CHIPS)':
 'VSS_AC1': CDS_PINID='VSS_AC1';
NODE_NAME     U25 AC6
 '@T6G_MB_LIB.T6G(SCH_1):PAGE31_I21@PURE_QUANTA.GENOA_SP5(CHIPS)':
 'VSS_AC6': CDS_PINID='VSS_AC6';
NODE_NAME     U25 AC8
 '@T6G_MB_LIB.T6G(SCH_1):PAGE31_I21@PURE_QUANTA.GENOA_SP5(CHIPS)':
 'VSS_AC8': CDS_PINID='VSS_AC8';
NODE_NAME     U25 AC13
 '@T6G_MB_LIB.T6G(SCH_1):PAGE31_I21@PURE_QUANTA.GENOA_SP5(CHIPS)':
 'VSS_AC13': CDS_PINID='VSS_AC13';
NODE_NAME     U25 AC15
 '@T6G_MB_LIB.T6G(SCH_1):PAGE31_I21@PURE_QUANTA.GENOA_SP5(CHIPS)':
 'VSS_AC15': CDS_PINID='VSS_AC15';
NODE_NAME     U25 AC20
 '@T6G_MB_LIB.T6G(SCH_1):PAGE31_I21@PURE_QUANTA.GENOA_SP5(CHIPS)':
 'VSS_AC20': CDS_PINID='VSS_AC20';
NODE_NAME     U25 AC22
 '@T6G_MB_LIB.T6G(SCH_1):PAGE31_I21@PURE_QUANTA.GENOA_SP5(CHIPS)':
 'VSS_AC22': CDS_PINID='VSS_AC22';
NODE_NAME     U25 AC25
 '@T6G_MB_LIB.T6G(SCH_1):PAGE31_I21@PURE_QUANTA.GENOA_SP5(CHIPS)':
 'VSS_AC25': CDS_PINID='VSS_AC25';
NODE_NAME     U25 AC28
 '@T6G_MB_LIB.T6G(SCH_1):PAGE31_I21@PURE_QUANTA.GENOA_SP5(CHIPS)':
 'VSS_AC28': CDS_PINID='VSS_AC28';
NODE_NAME     U25 AC31
 '@T6G_MB_LIB.T6G(SCH_1):PAGE31_I21@PURE_QUANTA.GENOA_SP5(CHIPS)':
 'VSS_AC31': CDS_PINID='VSS_AC31';
NODE_NAME     U25 AC34
 '@T6G_MB_LIB.T6G(SCH_1):PAGE31_I21@PURE_QUANTA.GENOA_SP5(CHIPS)':
 'VSS_AC34': CDS_PINID='VSS_AC34';
NODE_NAME     U25 AC42
 '@T6G_MB_LIB.T6G(SCH_1):PAGE31_I21@PURE_QUANTA.GENOA_SP5(CHIPS)':
 'VSS_AC42': CDS_PINID='VSS_AC42';
NODE_NAME     U25 AC45
 '@T6G_MB_LIB.T6G(SCH_1):PAGE31_I21@PURE_QUANTA.GENOA_SP5(CHIPS)':
 'VSS_AC45': CDS_PINID='VSS_AC45';
NODE_NAME     U25 AC48
 '@T6G_MB_LIB.T6G(SCH_1):PAGE31_I21@PURE_QUANTA.GENOA_SP5(CHIPS)':
 'VSS_AC48': CDS_PINID='VSS_AC48';
NODE_NAME     U25 AC51
 '@T6G_MB_LIB.T6G(SCH_1):PAGE31_I21@PURE_QUANTA.GENOA_SP5(CHIPS)':
 'VSS_AC51': CDS_PINID='VSS_AC51';
NODE_NAME     U25 AC54
 '@T6G_MB_LIB.T6G(SCH_1):PAGE31_I21@PURE_QUANTA.GENOA_SP5(CHIPS)':
 'VSS_AC54': CDS_PINID='VSS_AC54';
NODE_NAME     U25 AC56
 '@T6G_MB_LIB.T6G(SCH_1):PAGE31_I21@PURE_QUANTA.GENOA_SP5(CHIPS)':
 'VSS_AC56': CDS_PINID='VSS_AC56';
NODE_NAME     U25 AC61
 '@T6G_MB_LIB.T6G(SCH_1):PAGE31_I21@PURE_QUANTA.GENOA_SP5(CHIPS)':
 'VSS_AC61': CDS_PINID='VSS_AC61';
NODE_NAME     U25 AC63
 '@T6G_MB_LIB.T6G(SCH_1):PAGE31_I21@PURE_QUANTA.GENOA_SP5(CHIPS)':
 'VSS_AC63': CDS_PINID='VSS_AC63';
NODE_NAME     U25 AC68
 '@T6G_MB_LIB.T6G(SCH_1):PAGE31_I21@PURE_QUANTA.GENOA_SP5(CHIPS)':
 'VSS_AC68': CDS_PINID='VSS_AC68';
NODE_NAME     U25 AC70
 '@T6G_MB_LIB.T6G(SCH_1):PAGE31_I21@PURE_QUANTA.GENOA_SP5(CHIPS)':
 'VSS_AC70': CDS_PINID='VSS_AC70';
NODE_NAME     U25 AC75
 '@T6G_MB_LIB.T6G(SCH_1):PAGE31_I21@PURE_QUANTA.GENOA_SP5(CHIPS)':
 'VSS_AC75': CDS_PINID='VSS_AC75';
NODE_NAME     U25 AD3
 '@T6G_MB_LIB.T6G(SCH_1):PAGE31_I21@PURE_QUANTA.GENOA_SP5(CHIPS)':
 'VSS_AD3': CDS_PINID='VSS_AD3';
NODE_NAME     U25 AD5
 '@T6G_MB_LIB.T6G(SCH_1):PAGE31_I21@PURE_QUANTA.GENOA_SP5(CHIPS)':
 'VSS_AD5': CDS_PINID='VSS_AD5';
NODE_NAME     U25 AD8
 '@T6G_MB_LIB.T6G(SCH_1):PAGE31_I21@PURE_QUANTA.GENOA_SP5(CHIPS)':
 'VSS_AD8': CDS_PINID='VSS_AD8';
NODE_NAME     U25 AD10
 '@T6G_MB_LIB.T6G(SCH_1):PAGE31_I21@PURE_QUANTA.GENOA_SP5(CHIPS)':
 'VSS_AD10': CDS_PINID='VSS_AD10';
NODE_NAME     U25 AD12
 '@T6G_MB_LIB.T6G(SCH_1):PAGE31_I21@PURE_QUANTA.GENOA_SP5(CHIPS)':
 'VSS_AD12': CDS_PINID='VSS_AD12';
NODE_NAME     U25 AD15
 '@T6G_MB_LIB.T6G(SCH_1):PAGE31_I21@PURE_QUANTA.GENOA_SP5(CHIPS)':
 'VSS_AD15': CDS_PINID='VSS_AD15';
NODE_NAME     U25 AD17
 '@T6G_MB_LIB.T6G(SCH_1):PAGE31_I21@PURE_QUANTA.GENOA_SP5(CHIPS)':
 'VSS_AD17': CDS_PINID='VSS_AD17';
NODE_NAME     U25 AD19
 '@T6G_MB_LIB.T6G(SCH_1):PAGE31_I21@PURE_QUANTA.GENOA_SP5(CHIPS)':
 'VSS_AD19': CDS_PINID='VSS_AD19';
NODE_NAME     U25 AD23
 '@T6G_MB_LIB.T6G(SCH_1):PAGE31_I21@PURE_QUANTA.GENOA_SP5(CHIPS)':
 'VSS_AD23': CDS_PINID='VSS_AD23';
NODE_NAME     U25 AD24
 '@T6G_MB_LIB.T6G(SCH_1):PAGE31_I21@PURE_QUANTA.GENOA_SP5(CHIPS)':
 'VSS_AD24': CDS_PINID='VSS_AD24';
NODE_NAME     U25 AD25
 '@T6G_MB_LIB.T6G(SCH_1):PAGE31_I21@PURE_QUANTA.GENOA_SP5(CHIPS)':
 'VSS_AD25': CDS_PINID='VSS_AD25';
NODE_NAME     U25 AD26
 '@T6G_MB_LIB.T6G(SCH_1):PAGE31_I21@PURE_QUANTA.GENOA_SP5(CHIPS)':
 'VSS_AD26': CDS_PINID='VSS_AD26';
NODE_NAME     U25 AD27
 '@T6G_MB_LIB.T6G(SCH_1):PAGE31_I21@PURE_QUANTA.GENOA_SP5(CHIPS)':
 'VSS_AD27': CDS_PINID='VSS_AD27';
NODE_NAME     U25 AD28
 '@T6G_MB_LIB.T6G(SCH_1):PAGE31_I21@PURE_QUANTA.GENOA_SP5(CHIPS)':
 'VSS_AD28': CDS_PINID='VSS_AD28';
NODE_NAME     U25 AD29
 '@T6G_MB_LIB.T6G(SCH_1):PAGE31_I21@PURE_QUANTA.GENOA_SP5(CHIPS)':
 'VSS_AD29': CDS_PINID='VSS_AD29';
NODE_NAME     U25 AD30
 '@T6G_MB_LIB.T6G(SCH_1):PAGE31_I21@PURE_QUANTA.GENOA_SP5(CHIPS)':
 'VSS_AD30': CDS_PINID='VSS_AD30';
NODE_NAME     U25 AD32
 '@T6G_MB_LIB.T6G(SCH_1):PAGE31_I21@PURE_QUANTA.GENOA_SP5(CHIPS)':
 'VSS_AD32': CDS_PINID='VSS_AD32';
NODE_NAME     U25 AD33
 '@T6G_MB_LIB.T6G(SCH_1):PAGE31_I21@PURE_QUANTA.GENOA_SP5(CHIPS)':
 'VSS_AD33': CDS_PINID='VSS_AD33';
NODE_NAME     U25 AD34
 '@T6G_MB_LIB.T6G(SCH_1):PAGE31_I21@PURE_QUANTA.GENOA_SP5(CHIPS)':
 'VSS_AD34': CDS_PINID='VSS_AD34';
NODE_NAME     U25 AD37
 '@T6G_MB_LIB.T6G(SCH_1):PAGE31_I21@PURE_QUANTA.GENOA_SP5(CHIPS)':
 'VSS_AD37': CDS_PINID='VSS_AD37';
NODE_NAME     U25 AD39
 '@T6G_MB_LIB.T6G(SCH_1):PAGE31_I21@PURE_QUANTA.GENOA_SP5(CHIPS)':
 'VSS_AD39': CDS_PINID='VSS_AD39';
NODE_NAME     U25 AD42
 '@T6G_MB_LIB.T6G(SCH_1):PAGE31_I21@PURE_QUANTA.GENOA_SP5(CHIPS)':
 'VSS_AD42': CDS_PINID='VSS_AD42';
NODE_NAME     U25 AD43
 '@T6G_MB_LIB.T6G(SCH_1):PAGE31_I21@PURE_QUANTA.GENOA_SP5(CHIPS)':
 'VSS_AD43': CDS_PINID='VSS_AD43';
NODE_NAME     U25 AD44
 '@T6G_MB_LIB.T6G(SCH_1):PAGE31_I21@PURE_QUANTA.GENOA_SP5(CHIPS)':
 'VSS_AD44': CDS_PINID='VSS_AD44';
NODE_NAME     U25 AD45
 '@T6G_MB_LIB.T6G(SCH_1):PAGE31_I21@PURE_QUANTA.GENOA_SP5(CHIPS)':
 'VSS_AD45': CDS_PINID='VSS_AD45';
NODE_NAME     U25 AD46
 '@T6G_MB_LIB.T6G(SCH_1):PAGE31_I21@PURE_QUANTA.GENOA_SP5(CHIPS)':
 'VSS_AD46': CDS_PINID='VSS_AD46';
NODE_NAME     U25 AD47
 '@T6G_MB_LIB.T6G(SCH_1):PAGE31_I21@PURE_QUANTA.GENOA_SP5(CHIPS)':
 'VSS_AD47': CDS_PINID='VSS_AD47';
NODE_NAME     U25 AD48
 '@T6G_MB_LIB.T6G(SCH_1):PAGE31_I21@PURE_QUANTA.GENOA_SP5(CHIPS)':
 'VSS_AD48': CDS_PINID='VSS_AD48';
NODE_NAME     U25 T66
 '@T6G_MB_LIB.T6G(SCH_1):PAGE31_I21@PURE_QUANTA.GENOA_SP5(CHIPS)':
 'VSS_T66': CDS_PINID='VSS_T66';
NODE_NAME     U25 T68
 '@T6G_MB_LIB.T6G(SCH_1):PAGE31_I21@PURE_QUANTA.GENOA_SP5(CHIPS)':
 'VSS_T68': CDS_PINID='VSS_T68';
NODE_NAME     U25 T71
 '@T6G_MB_LIB.T6G(SCH_1):PAGE31_I21@PURE_QUANTA.GENOA_SP5(CHIPS)':
 'VSS_T71': CDS_PINID='VSS_T71';
NODE_NAME     U25 T73
 '@T6G_MB_LIB.T6G(SCH_1):PAGE31_I21@PURE_QUANTA.GENOA_SP5(CHIPS)':
 'VSS_T73': CDS_PINID='VSS_T73';
NODE_NAME     U25 U1
 '@T6G_MB_LIB.T6G(SCH_1):PAGE31_I21@PURE_QUANTA.GENOA_SP5(CHIPS)':
 'VSS_U1': CDS_PINID='VSS_U1';
NODE_NAME     U25 U6
 '@T6G_MB_LIB.T6G(SCH_1):PAGE31_I21@PURE_QUANTA.GENOA_SP5(CHIPS)':
 'VSS_U6': CDS_PINID='VSS_U6';
NODE_NAME     U25 U8
 '@T6G_MB_LIB.T6G(SCH_1):PAGE31_I21@PURE_QUANTA.GENOA_SP5(CHIPS)':
 'VSS_U8': CDS_PINID='VSS_U8';
NODE_NAME     U25 U13
 '@T6G_MB_LIB.T6G(SCH_1):PAGE31_I21@PURE_QUANTA.GENOA_SP5(CHIPS)':
 'VSS_U13': CDS_PINID='VSS_U13';
NODE_NAME     U25 U15
 '@T6G_MB_LIB.T6G(SCH_1):PAGE31_I21@PURE_QUANTA.GENOA_SP5(CHIPS)':
 'VSS_U15': CDS_PINID='VSS_U15';
NODE_NAME     U25 U20
 '@T6G_MB_LIB.T6G(SCH_1):PAGE31_I21@PURE_QUANTA.GENOA_SP5(CHIPS)':
 'VSS_U20': CDS_PINID='VSS_U20';
NODE_NAME     U25 U22
 '@T6G_MB_LIB.T6G(SCH_1):PAGE31_I21@PURE_QUANTA.GENOA_SP5(CHIPS)':
 'VSS_U22': CDS_PINID='VSS_U22';
NODE_NAME     U25 U25
 '@T6G_MB_LIB.T6G(SCH_1):PAGE31_I21@PURE_QUANTA.GENOA_SP5(CHIPS)':
 'VSS_U25': CDS_PINID='VSS_U25';
NODE_NAME     U25 U28
 '@T6G_MB_LIB.T6G(SCH_1):PAGE31_I21@PURE_QUANTA.GENOA_SP5(CHIPS)':
 'VSS_U28': CDS_PINID='VSS_U28';
NODE_NAME     U25 U31
 '@T6G_MB_LIB.T6G(SCH_1):PAGE31_I21@PURE_QUANTA.GENOA_SP5(CHIPS)':
 'VSS_U31': CDS_PINID='VSS_U31';
NODE_NAME     U25 U34
 '@T6G_MB_LIB.T6G(SCH_1):PAGE31_I21@PURE_QUANTA.GENOA_SP5(CHIPS)':
 'VSS_U34': CDS_PINID='VSS_U34';
NODE_NAME     U25 U42
 '@T6G_MB_LIB.T6G(SCH_1):PAGE31_I21@PURE_QUANTA.GENOA_SP5(CHIPS)':
 'VSS_U42': CDS_PINID='VSS_U42';
NODE_NAME     U25 U45
 '@T6G_MB_LIB.T6G(SCH_1):PAGE31_I21@PURE_QUANTA.GENOA_SP5(CHIPS)':
 'VSS_U45': CDS_PINID='VSS_U45';
NODE_NAME     U25 U48
 '@T6G_MB_LIB.T6G(SCH_1):PAGE31_I21@PURE_QUANTA.GENOA_SP5(CHIPS)':
 'VSS_U48': CDS_PINID='VSS_U48';
NODE_NAME     U25 U51
 '@T6G_MB_LIB.T6G(SCH_1):PAGE31_I21@PURE_QUANTA.GENOA_SP5(CHIPS)':
 'VSS_U51': CDS_PINID='VSS_U51';
NODE_NAME     U25 U54
 '@T6G_MB_LIB.T6G(SCH_1):PAGE31_I21@PURE_QUANTA.GENOA_SP5(CHIPS)':
 'VSS_U54': CDS_PINID='VSS_U54';
NODE_NAME     U25 U56
 '@T6G_MB_LIB.T6G(SCH_1):PAGE31_I21@PURE_QUANTA.GENOA_SP5(CHIPS)':
 'VSS_U56': CDS_PINID='VSS_U56';
NODE_NAME     U25 U61
 '@T6G_MB_LIB.T6G(SCH_1):PAGE31_I21@PURE_QUANTA.GENOA_SP5(CHIPS)':
 'VSS_U61': CDS_PINID='VSS_U61';
NODE_NAME     U25 U63
 '@T6G_MB_LIB.T6G(SCH_1):PAGE31_I21@PURE_QUANTA.GENOA_SP5(CHIPS)':
 'VSS_U63': CDS_PINID='VSS_U63';
NODE_NAME     U25 U68
 '@T6G_MB_LIB.T6G(SCH_1):PAGE31_I21@PURE_QUANTA.GENOA_SP5(CHIPS)':
 'VSS_U68': CDS_PINID='VSS_U68';
NODE_NAME     U25 U70
 '@T6G_MB_LIB.T6G(SCH_1):PAGE31_I21@PURE_QUANTA.GENOA_SP5(CHIPS)':
 'VSS_U70': CDS_PINID='VSS_U70';
NODE_NAME     U25 U75
 '@T6G_MB_LIB.T6G(SCH_1):PAGE31_I21@PURE_QUANTA.GENOA_SP5(CHIPS)':
 'VSS_U75': CDS_PINID='VSS_U75';
NODE_NAME     U25 V3
 '@T6G_MB_LIB.T6G(SCH_1):PAGE31_I21@PURE_QUANTA.GENOA_SP5(CHIPS)':
 'VSS_V3': CDS_PINID='VSS_V3';
NODE_NAME     U25 V5
 '@T6G_MB_LIB.T6G(SCH_1):PAGE31_I21@PURE_QUANTA.GENOA_SP5(CHIPS)':
 'VSS_V5': CDS_PINID='VSS_V5';
NODE_NAME     U25 V8
 '@T6G_MB_LIB.T6G(SCH_1):PAGE31_I21@PURE_QUANTA.GENOA_SP5(CHIPS)':
 'VSS_V8': CDS_PINID='VSS_V8';
NODE_NAME     U25 V10
 '@T6G_MB_LIB.T6G(SCH_1):PAGE31_I21@PURE_QUANTA.GENOA_SP5(CHIPS)':
 'VSS_V10': CDS_PINID='VSS_V10';
NODE_NAME     U25 V12
 '@T6G_MB_LIB.T6G(SCH_1):PAGE31_I21@PURE_QUANTA.GENOA_SP5(CHIPS)':
 'VSS_V12': CDS_PINID='VSS_V12';
NODE_NAME     U25 V15
 '@T6G_MB_LIB.T6G(SCH_1):PAGE31_I21@PURE_QUANTA.GENOA_SP5(CHIPS)':
 'VSS_V15': CDS_PINID='VSS_V15';
NODE_NAME     U25 V17
 '@T6G_MB_LIB.T6G(SCH_1):PAGE31_I21@PURE_QUANTA.GENOA_SP5(CHIPS)':
 'VSS_V17': CDS_PINID='VSS_V17';
NODE_NAME     U25 V19
 '@T6G_MB_LIB.T6G(SCH_1):PAGE31_I21@PURE_QUANTA.GENOA_SP5(CHIPS)':
 'VSS_V19': CDS_PINID='VSS_V19';
NODE_NAME     U25 V23
 '@T6G_MB_LIB.T6G(SCH_1):PAGE31_I21@PURE_QUANTA.GENOA_SP5(CHIPS)':
 'VSS_V23': CDS_PINID='VSS_V23';
NODE_NAME     U25 V24
 '@T6G_MB_LIB.T6G(SCH_1):PAGE31_I21@PURE_QUANTA.GENOA_SP5(CHIPS)':
 'VSS_V24': CDS_PINID='VSS_V24';
NODE_NAME     U25 V25
 '@T6G_MB_LIB.T6G(SCH_1):PAGE31_I21@PURE_QUANTA.GENOA_SP5(CHIPS)':
 'VSS_V25': CDS_PINID='VSS_V25';
NODE_NAME     U25 V26
 '@T6G_MB_LIB.T6G(SCH_1):PAGE31_I21@PURE_QUANTA.GENOA_SP5(CHIPS)':
 'VSS_V26': CDS_PINID='VSS_V26';
NODE_NAME     U25 V28
 '@T6G_MB_LIB.T6G(SCH_1):PAGE31_I21@PURE_QUANTA.GENOA_SP5(CHIPS)':
 'VSS_V28': CDS_PINID='VSS_V28';
NODE_NAME     U25 V29
 '@T6G_MB_LIB.T6G(SCH_1):PAGE31_I21@PURE_QUANTA.GENOA_SP5(CHIPS)':
 'VSS_V29': CDS_PINID='VSS_V29';
NODE_NAME     U25 V30
 '@T6G_MB_LIB.T6G(SCH_1):PAGE31_I21@PURE_QUANTA.GENOA_SP5(CHIPS)':
 'VSS_V30': CDS_PINID='VSS_V30';
NODE_NAME     U25 V31
 '@T6G_MB_LIB.T6G(SCH_1):PAGE31_I21@PURE_QUANTA.GENOA_SP5(CHIPS)':
 'VSS_V31': CDS_PINID='VSS_V31';
NODE_NAME     U25 V32
 '@T6G_MB_LIB.T6G(SCH_1):PAGE31_I21@PURE_QUANTA.GENOA_SP5(CHIPS)':
 'VSS_V32': CDS_PINID='VSS_V32';
NODE_NAME     U25 V33
 '@T6G_MB_LIB.T6G(SCH_1):PAGE31_I21@PURE_QUANTA.GENOA_SP5(CHIPS)':
 'VSS_V33': CDS_PINID='VSS_V33';
NODE_NAME     U25 V34
 '@T6G_MB_LIB.T6G(SCH_1):PAGE31_I21@PURE_QUANTA.GENOA_SP5(CHIPS)':
 'VSS_V34': CDS_PINID='VSS_V34';
NODE_NAME     U25 V37
 '@T6G_MB_LIB.T6G(SCH_1):PAGE31_I21@PURE_QUANTA.GENOA_SP5(CHIPS)':
 'VSS_V37': CDS_PINID='VSS_V37';
NODE_NAME     U25 V39
 '@T6G_MB_LIB.T6G(SCH_1):PAGE31_I21@PURE_QUANTA.GENOA_SP5(CHIPS)':
 'VSS_V39': CDS_PINID='VSS_V39';
NODE_NAME     U25 V42
 '@T6G_MB_LIB.T6G(SCH_1):PAGE31_I21@PURE_QUANTA.GENOA_SP5(CHIPS)':
 'VSS_V42': CDS_PINID='VSS_V42';
NODE_NAME     U25 V43
 '@T6G_MB_LIB.T6G(SCH_1):PAGE31_I21@PURE_QUANTA.GENOA_SP5(CHIPS)':
 'VSS_V43': CDS_PINID='VSS_V43';
NODE_NAME     U25 V44
 '@T6G_MB_LIB.T6G(SCH_1):PAGE31_I21@PURE_QUANTA.GENOA_SP5(CHIPS)':
 'VSS_V44': CDS_PINID='VSS_V44';
NODE_NAME     U25 V45
 '@T6G_MB_LIB.T6G(SCH_1):PAGE31_I21@PURE_QUANTA.GENOA_SP5(CHIPS)':
 'VSS_V45': CDS_PINID='VSS_V45';
NODE_NAME     U25 V46
 '@T6G_MB_LIB.T6G(SCH_1):PAGE31_I21@PURE_QUANTA.GENOA_SP5(CHIPS)':
 'VSS_V46': CDS_PINID='VSS_V46';
NODE_NAME     U25 V47
 '@T6G_MB_LIB.T6G(SCH_1):PAGE31_I21@PURE_QUANTA.GENOA_SP5(CHIPS)':
 'VSS_V47': CDS_PINID='VSS_V47';
NODE_NAME     U25 V48
 '@T6G_MB_LIB.T6G(SCH_1):PAGE31_I21@PURE_QUANTA.GENOA_SP5(CHIPS)':
 'VSS_V48': CDS_PINID='VSS_V48';
NODE_NAME     U25 V49
 '@T6G_MB_LIB.T6G(SCH_1):PAGE31_I21@PURE_QUANTA.GENOA_SP5(CHIPS)':
 'VSS_V49': CDS_PINID='VSS_V49';
NODE_NAME     U25 V50
 '@T6G_MB_LIB.T6G(SCH_1):PAGE31_I21@PURE_QUANTA.GENOA_SP5(CHIPS)':
 'VSS_V50': CDS_PINID='VSS_V50';
NODE_NAME     U25 V51
 '@T6G_MB_LIB.T6G(SCH_1):PAGE31_I21@PURE_QUANTA.GENOA_SP5(CHIPS)':
 'VSS_V51': CDS_PINID='VSS_V51';
NODE_NAME     U25 V52
 '@T6G_MB_LIB.T6G(SCH_1):PAGE31_I21@PURE_QUANTA.GENOA_SP5(CHIPS)':
 'VSS_V52': CDS_PINID='VSS_V52';
NODE_NAME     U25 V53
 '@T6G_MB_LIB.T6G(SCH_1):PAGE31_I21@PURE_QUANTA.GENOA_SP5(CHIPS)':
 'VSS_V53': CDS_PINID='VSS_V53';
NODE_NAME     U25 V57
 '@T6G_MB_LIB.T6G(SCH_1):PAGE31_I21@PURE_QUANTA.GENOA_SP5(CHIPS)':
 'VSS_V57': CDS_PINID='VSS_V57';
NODE_NAME     U25 V59
 '@T6G_MB_LIB.T6G(SCH_1):PAGE31_I21@PURE_QUANTA.GENOA_SP5(CHIPS)':
 'VSS_V59': CDS_PINID='VSS_V59';
NODE_NAME     U25 V61
 '@T6G_MB_LIB.T6G(SCH_1):PAGE31_I21@PURE_QUANTA.GENOA_SP5(CHIPS)':
 'VSS_V61': CDS_PINID='VSS_V61';
NODE_NAME     U25 V64
 '@T6G_MB_LIB.T6G(SCH_1):PAGE31_I21@PURE_QUANTA.GENOA_SP5(CHIPS)':
 'VSS_V64': CDS_PINID='VSS_V64';
NODE_NAME     U25 V66
 '@T6G_MB_LIB.T6G(SCH_1):PAGE31_I21@PURE_QUANTA.GENOA_SP5(CHIPS)':
 'VSS_V66': CDS_PINID='VSS_V66';
NODE_NAME     U25 V71
 '@T6G_MB_LIB.T6G(SCH_1):PAGE31_I21@PURE_QUANTA.GENOA_SP5(CHIPS)':
 'VSS_V71': CDS_PINID='VSS_V71';
NODE_NAME     U25 V73
 '@T6G_MB_LIB.T6G(SCH_1):PAGE31_I21@PURE_QUANTA.GENOA_SP5(CHIPS)':
 'VSS_V73': CDS_PINID='VSS_V73';
NODE_NAME     U25 W1
 '@T6G_MB_LIB.T6G(SCH_1):PAGE31_I21@PURE_QUANTA.GENOA_SP5(CHIPS)':
 'VSS_W1': CDS_PINID='VSS_W1';
NODE_NAME     U25 W4
 '@T6G_MB_LIB.T6G(SCH_1):PAGE31_I21@PURE_QUANTA.GENOA_SP5(CHIPS)':
 'VSS_W4': CDS_PINID='VSS_W4';
NODE_NAME     U25 W6
 '@T6G_MB_LIB.T6G(SCH_1):PAGE31_I21@PURE_QUANTA.GENOA_SP5(CHIPS)':
 'VSS_W6': CDS_PINID='VSS_W6';
NODE_NAME     U25 W8
 '@T6G_MB_LIB.T6G(SCH_1):PAGE31_I21@PURE_QUANTA.GENOA_SP5(CHIPS)':
 'VSS_W8': CDS_PINID='VSS_W8';
NODE_NAME     U25 W11
 '@T6G_MB_LIB.T6G(SCH_1):PAGE31_I21@PURE_QUANTA.GENOA_SP5(CHIPS)':
 'VSS_W11': CDS_PINID='VSS_W11';
NODE_NAME     U25 W13
 '@T6G_MB_LIB.T6G(SCH_1):PAGE31_I21@PURE_QUANTA.GENOA_SP5(CHIPS)':
 'VSS_W13': CDS_PINID='VSS_W13';
NODE_NAME     U25 W15
 '@T6G_MB_LIB.T6G(SCH_1):PAGE31_I21@PURE_QUANTA.GENOA_SP5(CHIPS)':
 'VSS_W15': CDS_PINID='VSS_W15';
NODE_NAME     U25 W18
 '@T6G_MB_LIB.T6G(SCH_1):PAGE31_I21@PURE_QUANTA.GENOA_SP5(CHIPS)':
 'VSS_W18': CDS_PINID='VSS_W18';
NODE_NAME     U25 W20
 '@T6G_MB_LIB.T6G(SCH_1):PAGE31_I21@PURE_QUANTA.GENOA_SP5(CHIPS)':
 'VSS_W20': CDS_PINID='VSS_W20';
NODE_NAME     U25 W22
 '@T6G_MB_LIB.T6G(SCH_1):PAGE31_I21@PURE_QUANTA.GENOA_SP5(CHIPS)':
 'VSS_W22': CDS_PINID='VSS_W22';
NODE_NAME     U25 W25
 '@T6G_MB_LIB.T6G(SCH_1):PAGE31_I21@PURE_QUANTA.GENOA_SP5(CHIPS)':
 'VSS_W25': CDS_PINID='VSS_W25';
NODE_NAME     U25 W28
 '@T6G_MB_LIB.T6G(SCH_1):PAGE31_I21@PURE_QUANTA.GENOA_SP5(CHIPS)':
 'VSS_W28': CDS_PINID='VSS_W28';
NODE_NAME     U25 W34
 '@T6G_MB_LIB.T6G(SCH_1):PAGE31_I21@PURE_QUANTA.GENOA_SP5(CHIPS)':
 'VSS_W34': CDS_PINID='VSS_W34';
NODE_NAME     U25 W35
 '@T6G_MB_LIB.T6G(SCH_1):PAGE31_I21@PURE_QUANTA.GENOA_SP5(CHIPS)':
 'VSS_W35': CDS_PINID='VSS_W35';
NODE_NAME     U25 W36
 '@T6G_MB_LIB.T6G(SCH_1):PAGE31_I21@PURE_QUANTA.GENOA_SP5(CHIPS)':
 'VSS_W36': CDS_PINID='VSS_W36';
NODE_NAME     U25 W40
 '@T6G_MB_LIB.T6G(SCH_1):PAGE31_I21@PURE_QUANTA.GENOA_SP5(CHIPS)':
 'VSS_W40': CDS_PINID='VSS_W40';
NODE_NAME     U25 W41
 '@T6G_MB_LIB.T6G(SCH_1):PAGE31_I21@PURE_QUANTA.GENOA_SP5(CHIPS)':
 'VSS_W41': CDS_PINID='VSS_W41';
NODE_NAME     U25 W42
 '@T6G_MB_LIB.T6G(SCH_1):PAGE31_I21@PURE_QUANTA.GENOA_SP5(CHIPS)':
 'VSS_W42': CDS_PINID='VSS_W42';
NODE_NAME     U25 W45
 '@T6G_MB_LIB.T6G(SCH_1):PAGE31_I21@PURE_QUANTA.GENOA_SP5(CHIPS)':
 'VSS_W45': CDS_PINID='VSS_W45';
NODE_NAME     U25 W48
 '@T6G_MB_LIB.T6G(SCH_1):PAGE31_I21@PURE_QUANTA.GENOA_SP5(CHIPS)':
 'VSS_W48': CDS_PINID='VSS_W48';
NODE_NAME     U25 W51
 '@T6G_MB_LIB.T6G(SCH_1):PAGE31_I21@PURE_QUANTA.GENOA_SP5(CHIPS)':
 'VSS_W51': CDS_PINID='VSS_W51';
NODE_NAME     U25 W54
 '@T6G_MB_LIB.T6G(SCH_1):PAGE31_I21@PURE_QUANTA.GENOA_SP5(CHIPS)':
 'VSS_W54': CDS_PINID='VSS_W54';
NODE_NAME     U25 W56
 '@T6G_MB_LIB.T6G(SCH_1):PAGE31_I21@PURE_QUANTA.GENOA_SP5(CHIPS)':
 'VSS_W56': CDS_PINID='VSS_W56';
NODE_NAME     U25 W58
 '@T6G_MB_LIB.T6G(SCH_1):PAGE31_I21@PURE_QUANTA.GENOA_SP5(CHIPS)':
 'VSS_W58': CDS_PINID='VSS_W58';
NODE_NAME     U25 W61
 '@T6G_MB_LIB.T6G(SCH_1):PAGE31_I21@PURE_QUANTA.GENOA_SP5(CHIPS)':
 'VSS_W61': CDS_PINID='VSS_W61';
NODE_NAME     U25 W63
 '@T6G_MB_LIB.T6G(SCH_1):PAGE31_I21@PURE_QUANTA.GENOA_SP5(CHIPS)':
 'VSS_W63': CDS_PINID='VSS_W63';
NODE_NAME     U25 W65
 '@T6G_MB_LIB.T6G(SCH_1):PAGE31_I21@PURE_QUANTA.GENOA_SP5(CHIPS)':
 'VSS_W65': CDS_PINID='VSS_W65';
NODE_NAME     U25 W68
 '@T6G_MB_LIB.T6G(SCH_1):PAGE31_I21@PURE_QUANTA.GENOA_SP5(CHIPS)':
 'VSS_W68': CDS_PINID='VSS_W68';
NODE_NAME     U25 W70
 '@T6G_MB_LIB.T6G(SCH_1):PAGE31_I21@PURE_QUANTA.GENOA_SP5(CHIPS)':
 'VSS_W70': CDS_PINID='VSS_W70';
NODE_NAME     U25 W72
 '@T6G_MB_LIB.T6G(SCH_1):PAGE31_I21@PURE_QUANTA.GENOA_SP5(CHIPS)':
 'VSS_W72': CDS_PINID='VSS_W72';
NODE_NAME     U25 W75
 '@T6G_MB_LIB.T6G(SCH_1):PAGE31_I21@PURE_QUANTA.GENOA_SP5(CHIPS)':
 'VSS_W75': CDS_PINID='VSS_W75';
NODE_NAME     U25 Y3
 '@T6G_MB_LIB.T6G(SCH_1):PAGE31_I21@PURE_QUANTA.GENOA_SP5(CHIPS)':
 'VSS_Y3': CDS_PINID='VSS_Y3';
NODE_NAME     U25 Y8
 '@T6G_MB_LIB.T6G(SCH_1):PAGE31_I21@PURE_QUANTA.GENOA_SP5(CHIPS)':
 'VSS_Y8': CDS_PINID='VSS_Y8';
NODE_NAME     U25 Y10
 '@T6G_MB_LIB.T6G(SCH_1):PAGE31_I21@PURE_QUANTA.GENOA_SP5(CHIPS)':
 'VSS_Y10': CDS_PINID='VSS_Y10';
NODE_NAME     U25 Y15
 '@T6G_MB_LIB.T6G(SCH_1):PAGE31_I21@PURE_QUANTA.GENOA_SP5(CHIPS)':
 'VSS_Y15': CDS_PINID='VSS_Y15';
NODE_NAME     U25 Y17
 '@T6G_MB_LIB.T6G(SCH_1):PAGE31_I21@PURE_QUANTA.GENOA_SP5(CHIPS)':
 'VSS_Y17': CDS_PINID='VSS_Y17';
NODE_NAME     U25 Y22
 '@T6G_MB_LIB.T6G(SCH_1):PAGE31_I21@PURE_QUANTA.GENOA_SP5(CHIPS)':
 'VSS_Y22': CDS_PINID='VSS_Y22';
NODE_NAME     U25 Y23
 '@T6G_MB_LIB.T6G(SCH_1):PAGE31_I21@PURE_QUANTA.GENOA_SP5(CHIPS)':
 'VSS_Y23': CDS_PINID='VSS_Y23';
NODE_NAME     U25 Y24
 '@T6G_MB_LIB.T6G(SCH_1):PAGE31_I21@PURE_QUANTA.GENOA_SP5(CHIPS)':
 'VSS_Y24': CDS_PINID='VSS_Y24';
NODE_NAME     U25 Y25
 '@T6G_MB_LIB.T6G(SCH_1):PAGE31_I21@PURE_QUANTA.GENOA_SP5(CHIPS)':
 'VSS_Y25': CDS_PINID='VSS_Y25';
NODE_NAME     U25 Y26
 '@T6G_MB_LIB.T6G(SCH_1):PAGE31_I21@PURE_QUANTA.GENOA_SP5(CHIPS)':
 'VSS_Y26': CDS_PINID='VSS_Y26';
NODE_NAME     U25 Y27
 '@T6G_MB_LIB.T6G(SCH_1):PAGE31_I21@PURE_QUANTA.GENOA_SP5(CHIPS)':
 'VSS_Y27': CDS_PINID='VSS_Y27';
NODE_NAME     U25 Y28
 '@T6G_MB_LIB.T6G(SCH_1):PAGE31_I21@PURE_QUANTA.GENOA_SP5(CHIPS)':
 'VSS_Y28': CDS_PINID='VSS_Y28';
NODE_NAME     U25 Y31
 '@T6G_MB_LIB.T6G(SCH_1):PAGE31_I21@PURE_QUANTA.GENOA_SP5(CHIPS)':
 'VSS_Y31': CDS_PINID='VSS_Y31';
NODE_NAME     U25 Y32
 '@T6G_MB_LIB.T6G(SCH_1):PAGE31_I21@PURE_QUANTA.GENOA_SP5(CHIPS)':
 'VSS_Y32': CDS_PINID='VSS_Y32';
NODE_NAME     U25 Y33
 '@T6G_MB_LIB.T6G(SCH_1):PAGE31_I21@PURE_QUANTA.GENOA_SP5(CHIPS)':
 'VSS_Y33': CDS_PINID='VSS_Y33';
NODE_NAME     U25 Y34
 '@T6G_MB_LIB.T6G(SCH_1):PAGE31_I21@PURE_QUANTA.GENOA_SP5(CHIPS)':
 'VSS_Y34': CDS_PINID='VSS_Y34';
NODE_NAME     U25 Y37
 '@T6G_MB_LIB.T6G(SCH_1):PAGE31_I21@PURE_QUANTA.GENOA_SP5(CHIPS)':
 'VSS_Y37': CDS_PINID='VSS_Y37';
NODE_NAME     U25 Y39
 '@T6G_MB_LIB.T6G(SCH_1):PAGE31_I21@PURE_QUANTA.GENOA_SP5(CHIPS)':
 'VSS_Y39': CDS_PINID='VSS_Y39';
NODE_NAME     U25 Y42
 '@T6G_MB_LIB.T6G(SCH_1):PAGE31_I21@PURE_QUANTA.GENOA_SP5(CHIPS)':
 'VSS_Y42': CDS_PINID='VSS_Y42';
NODE_NAME     U25 Y43
 '@T6G_MB_LIB.T6G(SCH_1):PAGE31_I21@PURE_QUANTA.GENOA_SP5(CHIPS)':
 'VSS_Y43': CDS_PINID='VSS_Y43';
NODE_NAME     U25 Y44
 '@T6G_MB_LIB.T6G(SCH_1):PAGE31_I21@PURE_QUANTA.GENOA_SP5(CHIPS)':
 'VSS_Y44': CDS_PINID='VSS_Y44';
NODE_NAME     U25 Y45
 '@T6G_MB_LIB.T6G(SCH_1):PAGE31_I21@PURE_QUANTA.GENOA_SP5(CHIPS)':
 'VSS_Y45': CDS_PINID='VSS_Y45';
NODE_NAME     U25 Y48
 '@T6G_MB_LIB.T6G(SCH_1):PAGE31_I21@PURE_QUANTA.GENOA_SP5(CHIPS)':
 'VSS_Y48': CDS_PINID='VSS_Y48';
NODE_NAME     U25 Y49
 '@T6G_MB_LIB.T6G(SCH_1):PAGE31_I21@PURE_QUANTA.GENOA_SP5(CHIPS)':
 'VSS_Y49': CDS_PINID='VSS_Y49';
NODE_NAME     U25 Y50
 '@T6G_MB_LIB.T6G(SCH_1):PAGE31_I21@PURE_QUANTA.GENOA_SP5(CHIPS)':
 'VSS_Y50': CDS_PINID='VSS_Y50';
NODE_NAME     U25 Y51
 '@T6G_MB_LIB.T6G(SCH_1):PAGE31_I21@PURE_QUANTA.GENOA_SP5(CHIPS)':
 'VSS_Y51': CDS_PINID='VSS_Y51';
NODE_NAME     U25 Y52
 '@T6G_MB_LIB.T6G(SCH_1):PAGE31_I21@PURE_QUANTA.GENOA_SP5(CHIPS)':
 'VSS_Y52': CDS_PINID='VSS_Y52';
NODE_NAME     U25 Y53
 '@T6G_MB_LIB.T6G(SCH_1):PAGE31_I21@PURE_QUANTA.GENOA_SP5(CHIPS)':
 'VSS_Y53': CDS_PINID='VSS_Y53';
NODE_NAME     U25 Y54
 '@T6G_MB_LIB.T6G(SCH_1):PAGE31_I21@PURE_QUANTA.GENOA_SP5(CHIPS)':
 'VSS_Y54': CDS_PINID='VSS_Y54';
NODE_NAME     U25 Y59
 '@T6G_MB_LIB.T6G(SCH_1):PAGE31_I21@PURE_QUANTA.GENOA_SP5(CHIPS)':
 'VSS_Y59': CDS_PINID='VSS_Y59';
NODE_NAME     U25 Y61
 '@T6G_MB_LIB.T6G(SCH_1):PAGE31_I21@PURE_QUANTA.GENOA_SP5(CHIPS)':
 'VSS_Y61': CDS_PINID='VSS_Y61';
NODE_NAME     U25 Y66
 '@T6G_MB_LIB.T6G(SCH_1):PAGE31_I21@PURE_QUANTA.GENOA_SP5(CHIPS)':
 'VSS_Y66': CDS_PINID='VSS_Y66';
NODE_NAME     U25 Y68
 '@T6G_MB_LIB.T6G(SCH_1):PAGE31_I21@PURE_QUANTA.GENOA_SP5(CHIPS)':
 'VSS_Y68': CDS_PINID='VSS_Y68';
NODE_NAME     U25 Y73
 '@T6G_MB_LIB.T6G(SCH_1):PAGE31_I21@PURE_QUANTA.GENOA_SP5(CHIPS)':
 'VSS_Y73': CDS_PINID='VSS_Y73';
NODE_NAME     U25 AD49
 '@T6G_MB_LIB.T6G(SCH_1):PAGE31_I22@PURE_QUANTA.GENOA_SP5(CHIPS)':
 'VSS_AD49': CDS_PINID='VSS_AD49';
NODE_NAME     U25 AD50
 '@T6G_MB_LIB.T6G(SCH_1):PAGE31_I22@PURE_QUANTA.GENOA_SP5(CHIPS)':
 'VSS_AD50': CDS_PINID='VSS_AD50';
NODE_NAME     U25 AD51
 '@T6G_MB_LIB.T6G(SCH_1):PAGE31_I22@PURE_QUANTA.GENOA_SP5(CHIPS)':
 'VSS_AD51': CDS_PINID='VSS_AD51';
NODE_NAME     U25 AD52
 '@T6G_MB_LIB.T6G(SCH_1):PAGE31_I22@PURE_QUANTA.GENOA_SP5(CHIPS)':
 'VSS_AD52': CDS_PINID='VSS_AD52';
NODE_NAME     U25 AD53
 '@T6G_MB_LIB.T6G(SCH_1):PAGE31_I22@PURE_QUANTA.GENOA_SP5(CHIPS)':
 'VSS_AD53': CDS_PINID='VSS_AD53';
NODE_NAME     U25 AD57
 '@T6G_MB_LIB.T6G(SCH_1):PAGE31_I22@PURE_QUANTA.GENOA_SP5(CHIPS)':
 'VSS_AD57': CDS_PINID='VSS_AD57';
NODE_NAME     U25 AD59
 '@T6G_MB_LIB.T6G(SCH_1):PAGE31_I22@PURE_QUANTA.GENOA_SP5(CHIPS)':
 'VSS_AD59': CDS_PINID='VSS_AD59';
NODE_NAME     U25 AD61
 '@T6G_MB_LIB.T6G(SCH_1):PAGE31_I22@PURE_QUANTA.GENOA_SP5(CHIPS)':
 'VSS_AD61': CDS_PINID='VSS_AD61';
NODE_NAME     U25 AD64
 '@T6G_MB_LIB.T6G(SCH_1):PAGE31_I22@PURE_QUANTA.GENOA_SP5(CHIPS)':
 'VSS_AD64': CDS_PINID='VSS_AD64';
NODE_NAME     U25 AD66
 '@T6G_MB_LIB.T6G(SCH_1):PAGE31_I22@PURE_QUANTA.GENOA_SP5(CHIPS)':
 'VSS_AD66': CDS_PINID='VSS_AD66';
NODE_NAME     U25 AD68
 '@T6G_MB_LIB.T6G(SCH_1):PAGE31_I22@PURE_QUANTA.GENOA_SP5(CHIPS)':
 'VSS_AD68': CDS_PINID='VSS_AD68';
NODE_NAME     U25 AD71
 '@T6G_MB_LIB.T6G(SCH_1):PAGE31_I22@PURE_QUANTA.GENOA_SP5(CHIPS)':
 'VSS_AD71': CDS_PINID='VSS_AD71';
NODE_NAME     U25 AD73
 '@T6G_MB_LIB.T6G(SCH_1):PAGE31_I22@PURE_QUANTA.GENOA_SP5(CHIPS)':
 'VSS_AD73': CDS_PINID='VSS_AD73';
NODE_NAME     U25 AE1
 '@T6G_MB_LIB.T6G(SCH_1):PAGE31_I22@PURE_QUANTA.GENOA_SP5(CHIPS)':
 'VSS_AE1': CDS_PINID='VSS_AE1';
NODE_NAME     U25 AE6
 '@T6G_MB_LIB.T6G(SCH_1):PAGE31_I22@PURE_QUANTA.GENOA_SP5(CHIPS)':
 'VSS_AE6': CDS_PINID='VSS_AE6';
NODE_NAME     U25 AE8
 '@T6G_MB_LIB.T6G(SCH_1):PAGE31_I22@PURE_QUANTA.GENOA_SP5(CHIPS)':
 'VSS_AE8': CDS_PINID='VSS_AE8';
NODE_NAME     U25 AE11
 '@T6G_MB_LIB.T6G(SCH_1):PAGE31_I22@PURE_QUANTA.GENOA_SP5(CHIPS)':
 'VSS_AE11': CDS_PINID='VSS_AE11';
NODE_NAME     U25 AE13
 '@T6G_MB_LIB.T6G(SCH_1):PAGE31_I22@PURE_QUANTA.GENOA_SP5(CHIPS)':
 'VSS_AE13': CDS_PINID='VSS_AE13';
NODE_NAME     U25 AE15
 '@T6G_MB_LIB.T6G(SCH_1):PAGE31_I22@PURE_QUANTA.GENOA_SP5(CHIPS)':
 'VSS_AE15': CDS_PINID='VSS_AE15';
NODE_NAME     U25 AE18
 '@T6G_MB_LIB.T6G(SCH_1):PAGE31_I22@PURE_QUANTA.GENOA_SP5(CHIPS)':
 'VSS_AE18': CDS_PINID='VSS_AE18';
NODE_NAME     U25 AE20
 '@T6G_MB_LIB.T6G(SCH_1):PAGE31_I22@PURE_QUANTA.GENOA_SP5(CHIPS)':
 'VSS_AE20': CDS_PINID='VSS_AE20';
NODE_NAME     U25 AE22
 '@T6G_MB_LIB.T6G(SCH_1):PAGE31_I22@PURE_QUANTA.GENOA_SP5(CHIPS)':
 'VSS_AE22': CDS_PINID='VSS_AE22';
NODE_NAME     U25 AE25
 '@T6G_MB_LIB.T6G(SCH_1):PAGE31_I22@PURE_QUANTA.GENOA_SP5(CHIPS)':
 'VSS_AE25': CDS_PINID='VSS_AE25';
NODE_NAME     U25 AE28
 '@T6G_MB_LIB.T6G(SCH_1):PAGE31_I22@PURE_QUANTA.GENOA_SP5(CHIPS)':
 'VSS_AE28': CDS_PINID='VSS_AE28';
NODE_NAME     U25 AE31
 '@T6G_MB_LIB.T6G(SCH_1):PAGE31_I22@PURE_QUANTA.GENOA_SP5(CHIPS)':
 'VSS_AE31': CDS_PINID='VSS_AE31';
NODE_NAME     U25 AE34
 '@T6G_MB_LIB.T6G(SCH_1):PAGE31_I22@PURE_QUANTA.GENOA_SP5(CHIPS)':
 'VSS_AE34': CDS_PINID='VSS_AE34';
NODE_NAME     U25 AE35
 '@T6G_MB_LIB.T6G(SCH_1):PAGE31_I22@PURE_QUANTA.GENOA_SP5(CHIPS)':
 'VSS_AE35': CDS_PINID='VSS_AE35';
NODE_NAME     U25 AE36
 '@T6G_MB_LIB.T6G(SCH_1):PAGE31_I22@PURE_QUANTA.GENOA_SP5(CHIPS)':
 'VSS_AE36': CDS_PINID='VSS_AE36';
NODE_NAME     U25 AE40
 '@T6G_MB_LIB.T6G(SCH_1):PAGE31_I22@PURE_QUANTA.GENOA_SP5(CHIPS)':
 'VSS_AE40': CDS_PINID='VSS_AE40';
NODE_NAME     U25 AE41
 '@T6G_MB_LIB.T6G(SCH_1):PAGE31_I22@PURE_QUANTA.GENOA_SP5(CHIPS)':
 'VSS_AE41': CDS_PINID='VSS_AE41';
NODE_NAME     U25 AE42
 '@T6G_MB_LIB.T6G(SCH_1):PAGE31_I22@PURE_QUANTA.GENOA_SP5(CHIPS)':
 'VSS_AE42': CDS_PINID='VSS_AE42';
NODE_NAME     U25 AE45
 '@T6G_MB_LIB.T6G(SCH_1):PAGE31_I22@PURE_QUANTA.GENOA_SP5(CHIPS)':
 'VSS_AE45': CDS_PINID='VSS_AE45';
NODE_NAME     U25 AE48
 '@T6G_MB_LIB.T6G(SCH_1):PAGE31_I22@PURE_QUANTA.GENOA_SP5(CHIPS)':
 'VSS_AE48': CDS_PINID='VSS_AE48';
NODE_NAME     U25 AE51
 '@T6G_MB_LIB.T6G(SCH_1):PAGE31_I22@PURE_QUANTA.GENOA_SP5(CHIPS)':
 'VSS_AE51': CDS_PINID='VSS_AE51';
NODE_NAME     U25 AE54
 '@T6G_MB_LIB.T6G(SCH_1):PAGE31_I22@PURE_QUANTA.GENOA_SP5(CHIPS)':
 'VSS_AE54': CDS_PINID='VSS_AE54';
NODE_NAME     U25 AE56
 '@T6G_MB_LIB.T6G(SCH_1):PAGE31_I22@PURE_QUANTA.GENOA_SP5(CHIPS)':
 'VSS_AE56': CDS_PINID='VSS_AE56';
NODE_NAME     U25 AE58
 '@T6G_MB_LIB.T6G(SCH_1):PAGE31_I22@PURE_QUANTA.GENOA_SP5(CHIPS)':
 'VSS_AE58': CDS_PINID='VSS_AE58';
NODE_NAME     U25 AE61
 '@T6G_MB_LIB.T6G(SCH_1):PAGE31_I22@PURE_QUANTA.GENOA_SP5(CHIPS)':
 'VSS_AE61': CDS_PINID='VSS_AE61';
NODE_NAME     U25 AE63
 '@T6G_MB_LIB.T6G(SCH_1):PAGE31_I22@PURE_QUANTA.GENOA_SP5(CHIPS)':
 'VSS_AE63': CDS_PINID='VSS_AE63';
NODE_NAME     U25 AE65
 '@T6G_MB_LIB.T6G(SCH_1):PAGE31_I22@PURE_QUANTA.GENOA_SP5(CHIPS)':
 'VSS_AE65': CDS_PINID='VSS_AE65';
NODE_NAME     U25 AE68
 '@T6G_MB_LIB.T6G(SCH_1):PAGE31_I22@PURE_QUANTA.GENOA_SP5(CHIPS)':
 'VSS_AE68': CDS_PINID='VSS_AE68';
NODE_NAME     U25 AE70
 '@T6G_MB_LIB.T6G(SCH_1):PAGE31_I22@PURE_QUANTA.GENOA_SP5(CHIPS)':
 'VSS_AE70': CDS_PINID='VSS_AE70';
NODE_NAME     U25 AE72
 '@T6G_MB_LIB.T6G(SCH_1):PAGE31_I22@PURE_QUANTA.GENOA_SP5(CHIPS)':
 'VSS_AE72': CDS_PINID='VSS_AE72';
NODE_NAME     U25 AE75
 '@T6G_MB_LIB.T6G(SCH_1):PAGE31_I22@PURE_QUANTA.GENOA_SP5(CHIPS)':
 'VSS_AE75': CDS_PINID='VSS_AE75';
NODE_NAME     U25 AF3
 '@T6G_MB_LIB.T6G(SCH_1):PAGE31_I22@PURE_QUANTA.GENOA_SP5(CHIPS)':
 'VSS_AF3': CDS_PINID='VSS_AF3';
NODE_NAME     U25 AF8
 '@T6G_MB_LIB.T6G(SCH_1):PAGE31_I22@PURE_QUANTA.GENOA_SP5(CHIPS)':
 'VSS_AF8': CDS_PINID='VSS_AF8';
NODE_NAME     U25 AF10
 '@T6G_MB_LIB.T6G(SCH_1):PAGE31_I22@PURE_QUANTA.GENOA_SP5(CHIPS)':
 'VSS_AF10': CDS_PINID='VSS_AF10';
NODE_NAME     U25 AF15
 '@T6G_MB_LIB.T6G(SCH_1):PAGE31_I22@PURE_QUANTA.GENOA_SP5(CHIPS)':
 'VSS_AF15': CDS_PINID='VSS_AF15';
NODE_NAME     U25 AF17
 '@T6G_MB_LIB.T6G(SCH_1):PAGE31_I22@PURE_QUANTA.GENOA_SP5(CHIPS)':
 'VSS_AF17': CDS_PINID='VSS_AF17';
NODE_NAME     U25 AF22
 '@T6G_MB_LIB.T6G(SCH_1):PAGE31_I22@PURE_QUANTA.GENOA_SP5(CHIPS)':
 'VSS_AF22': CDS_PINID='VSS_AF22';
NODE_NAME     U25 AF25
 '@T6G_MB_LIB.T6G(SCH_1):PAGE31_I22@PURE_QUANTA.GENOA_SP5(CHIPS)':
 'VSS_AF25': CDS_PINID='VSS_AF25';
NODE_NAME     U25 AF28
 '@T6G_MB_LIB.T6G(SCH_1):PAGE31_I22@PURE_QUANTA.GENOA_SP5(CHIPS)':
 'VSS_AF28': CDS_PINID='VSS_AF28';
NODE_NAME     U25 AF31
 '@T6G_MB_LIB.T6G(SCH_1):PAGE31_I22@PURE_QUANTA.GENOA_SP5(CHIPS)':
 'VSS_AF31': CDS_PINID='VSS_AF31';
NODE_NAME     U25 AF34
 '@T6G_MB_LIB.T6G(SCH_1):PAGE31_I22@PURE_QUANTA.GENOA_SP5(CHIPS)':
 'VSS_AF34': CDS_PINID='VSS_AF34';
NODE_NAME     U25 AF37
 '@T6G_MB_LIB.T6G(SCH_1):PAGE31_I22@PURE_QUANTA.GENOA_SP5(CHIPS)':
 'VSS_AF37': CDS_PINID='VSS_AF37';
NODE_NAME     U25 AF39
 '@T6G_MB_LIB.T6G(SCH_1):PAGE31_I22@PURE_QUANTA.GENOA_SP5(CHIPS)':
 'VSS_AF39': CDS_PINID='VSS_AF39';
NODE_NAME     U25 AF42
 '@T6G_MB_LIB.T6G(SCH_1):PAGE31_I22@PURE_QUANTA.GENOA_SP5(CHIPS)':
 'VSS_AF42': CDS_PINID='VSS_AF42';
NODE_NAME     U25 AF45
 '@T6G_MB_LIB.T6G(SCH_1):PAGE31_I22@PURE_QUANTA.GENOA_SP5(CHIPS)':
 'VSS_AF45': CDS_PINID='VSS_AF45';
NODE_NAME     U25 AF48
 '@T6G_MB_LIB.T6G(SCH_1):PAGE31_I22@PURE_QUANTA.GENOA_SP5(CHIPS)':
 'VSS_AF48': CDS_PINID='VSS_AF48';
NODE_NAME     U25 AF51
 '@T6G_MB_LIB.T6G(SCH_1):PAGE31_I22@PURE_QUANTA.GENOA_SP5(CHIPS)':
 'VSS_AF51': CDS_PINID='VSS_AF51';
NODE_NAME     U25 AF54
 '@T6G_MB_LIB.T6G(SCH_1):PAGE31_I22@PURE_QUANTA.GENOA_SP5(CHIPS)':
 'VSS_AF54': CDS_PINID='VSS_AF54';
NODE_NAME     U25 AF59
 '@T6G_MB_LIB.T6G(SCH_1):PAGE31_I22@PURE_QUANTA.GENOA_SP5(CHIPS)':
 'VSS_AF59': CDS_PINID='VSS_AF59';
NODE_NAME     U25 AF61
 '@T6G_MB_LIB.T6G(SCH_1):PAGE31_I22@PURE_QUANTA.GENOA_SP5(CHIPS)':
 'VSS_AF61': CDS_PINID='VSS_AF61';
NODE_NAME     U25 AF66
 '@T6G_MB_LIB.T6G(SCH_1):PAGE31_I22@PURE_QUANTA.GENOA_SP5(CHIPS)':
 'VSS_AF66': CDS_PINID='VSS_AF66';
NODE_NAME     U25 AF68
 '@T6G_MB_LIB.T6G(SCH_1):PAGE31_I22@PURE_QUANTA.GENOA_SP5(CHIPS)':
 'VSS_AF68': CDS_PINID='VSS_AF68';
NODE_NAME     U25 AF73
 '@T6G_MB_LIB.T6G(SCH_1):PAGE31_I22@PURE_QUANTA.GENOA_SP5(CHIPS)':
 'VSS_AF73': CDS_PINID='VSS_AF73';
NODE_NAME     U25 AG1
 '@T6G_MB_LIB.T6G(SCH_1):PAGE31_I22@PURE_QUANTA.GENOA_SP5(CHIPS)':
 'VSS_AG1': CDS_PINID='VSS_AG1';
NODE_NAME     U25 AG4
 '@T6G_MB_LIB.T6G(SCH_1):PAGE31_I22@PURE_QUANTA.GENOA_SP5(CHIPS)':
 'VSS_AG4': CDS_PINID='VSS_AG4';
NODE_NAME     U25 AG6
 '@T6G_MB_LIB.T6G(SCH_1):PAGE31_I22@PURE_QUANTA.GENOA_SP5(CHIPS)':
 'VSS_AG6': CDS_PINID='VSS_AG6';
NODE_NAME     U25 AG8
 '@T6G_MB_LIB.T6G(SCH_1):PAGE31_I22@PURE_QUANTA.GENOA_SP5(CHIPS)':
 'VSS_AG8': CDS_PINID='VSS_AG8';
NODE_NAME     U25 AG11
 '@T6G_MB_LIB.T6G(SCH_1):PAGE31_I22@PURE_QUANTA.GENOA_SP5(CHIPS)':
 'VSS_AG11': CDS_PINID='VSS_AG11';
NODE_NAME     U25 AG13
 '@T6G_MB_LIB.T6G(SCH_1):PAGE31_I22@PURE_QUANTA.GENOA_SP5(CHIPS)':
 'VSS_AG13': CDS_PINID='VSS_AG13';
NODE_NAME     U25 AG15
 '@T6G_MB_LIB.T6G(SCH_1):PAGE31_I22@PURE_QUANTA.GENOA_SP5(CHIPS)':
 'VSS_AG15': CDS_PINID='VSS_AG15';
NODE_NAME     U25 AG18
 '@T6G_MB_LIB.T6G(SCH_1):PAGE31_I22@PURE_QUANTA.GENOA_SP5(CHIPS)':
 'VSS_AG18': CDS_PINID='VSS_AG18';
NODE_NAME     U25 AG20
 '@T6G_MB_LIB.T6G(SCH_1):PAGE31_I22@PURE_QUANTA.GENOA_SP5(CHIPS)':
 'VSS_AG20': CDS_PINID='VSS_AG20';
NODE_NAME     U25 AG22
 '@T6G_MB_LIB.T6G(SCH_1):PAGE31_I22@PURE_QUANTA.GENOA_SP5(CHIPS)':
 'VSS_AG22': CDS_PINID='VSS_AG22';
NODE_NAME     U25 AG25
 '@T6G_MB_LIB.T6G(SCH_1):PAGE31_I22@PURE_QUANTA.GENOA_SP5(CHIPS)':
 'VSS_AG25': CDS_PINID='VSS_AG25';
NODE_NAME     U25 AG28
 '@T6G_MB_LIB.T6G(SCH_1):PAGE31_I22@PURE_QUANTA.GENOA_SP5(CHIPS)':
 'VSS_AG28': CDS_PINID='VSS_AG28';
NODE_NAME     U25 AG31
 '@T6G_MB_LIB.T6G(SCH_1):PAGE31_I22@PURE_QUANTA.GENOA_SP5(CHIPS)':
 'VSS_AG31': CDS_PINID='VSS_AG31';
NODE_NAME     U25 AG34
 '@T6G_MB_LIB.T6G(SCH_1):PAGE31_I22@PURE_QUANTA.GENOA_SP5(CHIPS)':
 'VSS_AG34': CDS_PINID='VSS_AG34';
NODE_NAME     U25 AG42
 '@T6G_MB_LIB.T6G(SCH_1):PAGE31_I22@PURE_QUANTA.GENOA_SP5(CHIPS)':
 'VSS_AG42': CDS_PINID='VSS_AG42';
NODE_NAME     U25 AG45
 '@T6G_MB_LIB.T6G(SCH_1):PAGE31_I22@PURE_QUANTA.GENOA_SP5(CHIPS)':
 'VSS_AG45': CDS_PINID='VSS_AG45';
NODE_NAME     U25 AG48
 '@T6G_MB_LIB.T6G(SCH_1):PAGE31_I22@PURE_QUANTA.GENOA_SP5(CHIPS)':
 'VSS_AG48': CDS_PINID='VSS_AG48';
NODE_NAME     U25 AG51
 '@T6G_MB_LIB.T6G(SCH_1):PAGE31_I22@PURE_QUANTA.GENOA_SP5(CHIPS)':
 'VSS_AG51': CDS_PINID='VSS_AG51';
NODE_NAME     U25 AG54
 '@T6G_MB_LIB.T6G(SCH_1):PAGE31_I22@PURE_QUANTA.GENOA_SP5(CHIPS)':
 'VSS_AG54': CDS_PINID='VSS_AG54';
NODE_NAME     U25 AG56
 '@T6G_MB_LIB.T6G(SCH_1):PAGE31_I22@PURE_QUANTA.GENOA_SP5(CHIPS)':
 'VSS_AG56': CDS_PINID='VSS_AG56';
NODE_NAME     U25 AG58
 '@T6G_MB_LIB.T6G(SCH_1):PAGE31_I22@PURE_QUANTA.GENOA_SP5(CHIPS)':
 'VSS_AG58': CDS_PINID='VSS_AG58';
NODE_NAME     U25 AG61
 '@T6G_MB_LIB.T6G(SCH_1):PAGE31_I22@PURE_QUANTA.GENOA_SP5(CHIPS)':
 'VSS_AG61': CDS_PINID='VSS_AG61';
NODE_NAME     U25 AG63
 '@T6G_MB_LIB.T6G(SCH_1):PAGE31_I22@PURE_QUANTA.GENOA_SP5(CHIPS)':
 'VSS_AG63': CDS_PINID='VSS_AG63';
NODE_NAME     U25 AG65
 '@T6G_MB_LIB.T6G(SCH_1):PAGE31_I22@PURE_QUANTA.GENOA_SP5(CHIPS)':
 'VSS_AG65': CDS_PINID='VSS_AG65';
NODE_NAME     U25 AG68
 '@T6G_MB_LIB.T6G(SCH_1):PAGE31_I22@PURE_QUANTA.GENOA_SP5(CHIPS)':
 'VSS_AG68': CDS_PINID='VSS_AG68';
NODE_NAME     U25 AG70
 '@T6G_MB_LIB.T6G(SCH_1):PAGE31_I22@PURE_QUANTA.GENOA_SP5(CHIPS)':
 'VSS_AG70': CDS_PINID='VSS_AG70';
NODE_NAME     U25 AG72
 '@T6G_MB_LIB.T6G(SCH_1):PAGE31_I22@PURE_QUANTA.GENOA_SP5(CHIPS)':
 'VSS_AG72': CDS_PINID='VSS_AG72';
NODE_NAME     U25 AG75
 '@T6G_MB_LIB.T6G(SCH_1):PAGE31_I22@PURE_QUANTA.GENOA_SP5(CHIPS)':
 'VSS_AG75': CDS_PINID='VSS_AG75';
NODE_NAME     U25 AH3
 '@T6G_MB_LIB.T6G(SCH_1):PAGE31_I22@PURE_QUANTA.GENOA_SP5(CHIPS)':
 'VSS_AH3': CDS_PINID='VSS_AH3';
NODE_NAME     U25 AH5
 '@T6G_MB_LIB.T6G(SCH_1):PAGE31_I22@PURE_QUANTA.GENOA_SP5(CHIPS)':
 'VSS_AH5': CDS_PINID='VSS_AH5';
NODE_NAME     U25 AH8
 '@T6G_MB_LIB.T6G(SCH_1):PAGE31_I22@PURE_QUANTA.GENOA_SP5(CHIPS)':
 'VSS_AH8': CDS_PINID='VSS_AH8';
NODE_NAME     U25 AH10
 '@T6G_MB_LIB.T6G(SCH_1):PAGE31_I22@PURE_QUANTA.GENOA_SP5(CHIPS)':
 'VSS_AH10': CDS_PINID='VSS_AH10';
NODE_NAME     U25 AH12
 '@T6G_MB_LIB.T6G(SCH_1):PAGE31_I22@PURE_QUANTA.GENOA_SP5(CHIPS)':
 'VSS_AH12': CDS_PINID='VSS_AH12';
NODE_NAME     U25 AH15
 '@T6G_MB_LIB.T6G(SCH_1):PAGE31_I22@PURE_QUANTA.GENOA_SP5(CHIPS)':
 'VSS_AH15': CDS_PINID='VSS_AH15';
NODE_NAME     U25 AH17
 '@T6G_MB_LIB.T6G(SCH_1):PAGE31_I22@PURE_QUANTA.GENOA_SP5(CHIPS)':
 'VSS_AH17': CDS_PINID='VSS_AH17';
NODE_NAME     U25 AH19
 '@T6G_MB_LIB.T6G(SCH_1):PAGE31_I22@PURE_QUANTA.GENOA_SP5(CHIPS)':
 'VSS_AH19': CDS_PINID='VSS_AH19';
NODE_NAME     U25 AH23
 '@T6G_MB_LIB.T6G(SCH_1):PAGE31_I22@PURE_QUANTA.GENOA_SP5(CHIPS)':
 'VSS_AH23': CDS_PINID='VSS_AH23';
NODE_NAME     U25 AH24
 '@T6G_MB_LIB.T6G(SCH_1):PAGE31_I22@PURE_QUANTA.GENOA_SP5(CHIPS)':
 'VSS_AH24': CDS_PINID='VSS_AH24';
NODE_NAME     U25 AH25
 '@T6G_MB_LIB.T6G(SCH_1):PAGE31_I22@PURE_QUANTA.GENOA_SP5(CHIPS)':
 'VSS_AH25': CDS_PINID='VSS_AH25';
NODE_NAME     U25 AH26
 '@T6G_MB_LIB.T6G(SCH_1):PAGE31_I22@PURE_QUANTA.GENOA_SP5(CHIPS)':
 'VSS_AH26': CDS_PINID='VSS_AH26';
NODE_NAME     U25 AH27
 '@T6G_MB_LIB.T6G(SCH_1):PAGE31_I22@PURE_QUANTA.GENOA_SP5(CHIPS)':
 'VSS_AH27': CDS_PINID='VSS_AH27';
NODE_NAME     U25 AH28
 '@T6G_MB_LIB.T6G(SCH_1):PAGE31_I22@PURE_QUANTA.GENOA_SP5(CHIPS)':
 'VSS_AH28': CDS_PINID='VSS_AH28';
NODE_NAME     U25 AH29
 '@T6G_MB_LIB.T6G(SCH_1):PAGE31_I22@PURE_QUANTA.GENOA_SP5(CHIPS)':
 'VSS_AH29': CDS_PINID='VSS_AH29';
NODE_NAME     U25 AH30
 '@T6G_MB_LIB.T6G(SCH_1):PAGE31_I22@PURE_QUANTA.GENOA_SP5(CHIPS)':
 'VSS_AH30': CDS_PINID='VSS_AH30';
NODE_NAME     U25 AH31
 '@T6G_MB_LIB.T6G(SCH_1):PAGE31_I22@PURE_QUANTA.GENOA_SP5(CHIPS)':
 'VSS_AH31': CDS_PINID='VSS_AH31';
NODE_NAME     U25 AH32
 '@T6G_MB_LIB.T6G(SCH_1):PAGE31_I22@PURE_QUANTA.GENOA_SP5(CHIPS)':
 'VSS_AH32': CDS_PINID='VSS_AH32';
NODE_NAME     U25 AH34
 '@T6G_MB_LIB.T6G(SCH_1):PAGE31_I22@PURE_QUANTA.GENOA_SP5(CHIPS)':
 'VSS_AH34': CDS_PINID='VSS_AH34';
NODE_NAME     U25 AH37
 '@T6G_MB_LIB.T6G(SCH_1):PAGE31_I22@PURE_QUANTA.GENOA_SP5(CHIPS)':
 'VSS_AH37': CDS_PINID='VSS_AH37';
NODE_NAME     U25 AH39
 '@T6G_MB_LIB.T6G(SCH_1):PAGE31_I22@PURE_QUANTA.GENOA_SP5(CHIPS)':
 'VSS_AH39': CDS_PINID='VSS_AH39';
NODE_NAME     U25 AH42
 '@T6G_MB_LIB.T6G(SCH_1):PAGE31_I22@PURE_QUANTA.GENOA_SP5(CHIPS)':
 'VSS_AH42': CDS_PINID='VSS_AH42';
NODE_NAME     U25 AH43
 '@T6G_MB_LIB.T6G(SCH_1):PAGE31_I22@PURE_QUANTA.GENOA_SP5(CHIPS)':
 'VSS_AH43': CDS_PINID='VSS_AH43';
NODE_NAME     U25 AH44
 '@T6G_MB_LIB.T6G(SCH_1):PAGE31_I22@PURE_QUANTA.GENOA_SP5(CHIPS)':
 'VSS_AH44': CDS_PINID='VSS_AH44';
NODE_NAME     U25 AH45
 '@T6G_MB_LIB.T6G(SCH_1):PAGE31_I22@PURE_QUANTA.GENOA_SP5(CHIPS)':
 'VSS_AH45': CDS_PINID='VSS_AH45';
NODE_NAME     U25 AH46
 '@T6G_MB_LIB.T6G(SCH_1):PAGE31_I22@PURE_QUANTA.GENOA_SP5(CHIPS)':
 'VSS_AH46': CDS_PINID='VSS_AH46';
NODE_NAME     U25 AH47
 '@T6G_MB_LIB.T6G(SCH_1):PAGE31_I22@PURE_QUANTA.GENOA_SP5(CHIPS)':
 'VSS_AH47': CDS_PINID='VSS_AH47';
NODE_NAME     U25 AH48
 '@T6G_MB_LIB.T6G(SCH_1):PAGE31_I22@PURE_QUANTA.GENOA_SP5(CHIPS)':
 'VSS_AH48': CDS_PINID='VSS_AH48';
NODE_NAME     U25 AH49
 '@T6G_MB_LIB.T6G(SCH_1):PAGE31_I22@PURE_QUANTA.GENOA_SP5(CHIPS)':
 'VSS_AH49': CDS_PINID='VSS_AH49';
NODE_NAME     U25 AH50
 '@T6G_MB_LIB.T6G(SCH_1):PAGE31_I22@PURE_QUANTA.GENOA_SP5(CHIPS)':
 'VSS_AH50': CDS_PINID='VSS_AH50';
NODE_NAME     U25 AH51
 '@T6G_MB_LIB.T6G(SCH_1):PAGE31_I22@PURE_QUANTA.GENOA_SP5(CHIPS)':
 'VSS_AH51': CDS_PINID='VSS_AH51';
NODE_NAME     U25 AH52
 '@T6G_MB_LIB.T6G(SCH_1):PAGE31_I22@PURE_QUANTA.GENOA_SP5(CHIPS)':
 'VSS_AH52': CDS_PINID='VSS_AH52';
NODE_NAME     U25 AH53
 '@T6G_MB_LIB.T6G(SCH_1):PAGE31_I22@PURE_QUANTA.GENOA_SP5(CHIPS)':
 'VSS_AH53': CDS_PINID='VSS_AH53';
NODE_NAME     U25 AH57
 '@T6G_MB_LIB.T6G(SCH_1):PAGE31_I22@PURE_QUANTA.GENOA_SP5(CHIPS)':
 'VSS_AH57': CDS_PINID='VSS_AH57';
NODE_NAME     U25 AH59
 '@T6G_MB_LIB.T6G(SCH_1):PAGE31_I22@PURE_QUANTA.GENOA_SP5(CHIPS)':
 'VSS_AH59': CDS_PINID='VSS_AH59';
NODE_NAME     U25 AH61
 '@T6G_MB_LIB.T6G(SCH_1):PAGE31_I22@PURE_QUANTA.GENOA_SP5(CHIPS)':
 'VSS_AH61': CDS_PINID='VSS_AH61';
NODE_NAME     U25 AH64
 '@T6G_MB_LIB.T6G(SCH_1):PAGE31_I22@PURE_QUANTA.GENOA_SP5(CHIPS)':
 'VSS_AH64': CDS_PINID='VSS_AH64';
NODE_NAME     U25 AH66
 '@T6G_MB_LIB.T6G(SCH_1):PAGE31_I22@PURE_QUANTA.GENOA_SP5(CHIPS)':
 'VSS_AH66': CDS_PINID='VSS_AH66';
NODE_NAME     U25 AH68
 '@T6G_MB_LIB.T6G(SCH_1):PAGE31_I22@PURE_QUANTA.GENOA_SP5(CHIPS)':
 'VSS_AH68': CDS_PINID='VSS_AH68';
NODE_NAME     U25 AH71
 '@T6G_MB_LIB.T6G(SCH_1):PAGE31_I22@PURE_QUANTA.GENOA_SP5(CHIPS)':
 'VSS_AH71': CDS_PINID='VSS_AH71';
NODE_NAME     U25 AH73
 '@T6G_MB_LIB.T6G(SCH_1):PAGE31_I22@PURE_QUANTA.GENOA_SP5(CHIPS)':
 'VSS_AH73': CDS_PINID='VSS_AH73';
NODE_NAME     U25 AJ1
 '@T6G_MB_LIB.T6G(SCH_1):PAGE31_I22@PURE_QUANTA.GENOA_SP5(CHIPS)':
 'VSS_AJ1': CDS_PINID='VSS_AJ1';
NODE_NAME     U25 AJ6
 '@T6G_MB_LIB.T6G(SCH_1):PAGE31_I22@PURE_QUANTA.GENOA_SP5(CHIPS)':
 'VSS_AJ6': CDS_PINID='VSS_AJ6';
NODE_NAME     U25 AJ8
 '@T6G_MB_LIB.T6G(SCH_1):PAGE31_I22@PURE_QUANTA.GENOA_SP5(CHIPS)':
 'VSS_AJ8': CDS_PINID='VSS_AJ8';
NODE_NAME     U25 AJ15
 '@T6G_MB_LIB.T6G(SCH_1):PAGE31_I22@PURE_QUANTA.GENOA_SP5(CHIPS)':
 'VSS_AJ15': CDS_PINID='VSS_AJ15';
NODE_NAME     U25 AJ20
 '@T6G_MB_LIB.T6G(SCH_1):PAGE31_I22@PURE_QUANTA.GENOA_SP5(CHIPS)':
 'VSS_AJ20': CDS_PINID='VSS_AJ20';
NODE_NAME     U25 AJ22
 '@T6G_MB_LIB.T6G(SCH_1):PAGE31_I22@PURE_QUANTA.GENOA_SP5(CHIPS)':
 'VSS_AJ22': CDS_PINID='VSS_AJ22';
NODE_NAME     U25 AJ25
 '@T6G_MB_LIB.T6G(SCH_1):PAGE31_I22@PURE_QUANTA.GENOA_SP5(CHIPS)':
 'VSS_AJ25': CDS_PINID='VSS_AJ25';
NODE_NAME     U25 AJ28
 '@T6G_MB_LIB.T6G(SCH_1):PAGE31_I22@PURE_QUANTA.GENOA_SP5(CHIPS)':
 'VSS_AJ28': CDS_PINID='VSS_AJ28';
NODE_NAME     U25 AJ31
 '@T6G_MB_LIB.T6G(SCH_1):PAGE31_I22@PURE_QUANTA.GENOA_SP5(CHIPS)':
 'VSS_AJ31': CDS_PINID='VSS_AJ31';
NODE_NAME     U25 AJ34
 '@T6G_MB_LIB.T6G(SCH_1):PAGE31_I22@PURE_QUANTA.GENOA_SP5(CHIPS)':
 'VSS_AJ34': CDS_PINID='VSS_AJ34';
NODE_NAME     U25 AJ35
 '@T6G_MB_LIB.T6G(SCH_1):PAGE31_I22@PURE_QUANTA.GENOA_SP5(CHIPS)':
 'VSS_AJ35': CDS_PINID='VSS_AJ35';
NODE_NAME     U25 AJ36
 '@T6G_MB_LIB.T6G(SCH_1):PAGE31_I22@PURE_QUANTA.GENOA_SP5(CHIPS)':
 'VSS_AJ36': CDS_PINID='VSS_AJ36';
NODE_NAME     U25 AJ40
 '@T6G_MB_LIB.T6G(SCH_1):PAGE31_I22@PURE_QUANTA.GENOA_SP5(CHIPS)':
 'VSS_AJ40': CDS_PINID='VSS_AJ40';
NODE_NAME     U25 AJ41
 '@T6G_MB_LIB.T6G(SCH_1):PAGE31_I22@PURE_QUANTA.GENOA_SP5(CHIPS)':
 'VSS_AJ41': CDS_PINID='VSS_AJ41';
NODE_NAME     U25 AJ42
 '@T6G_MB_LIB.T6G(SCH_1):PAGE31_I22@PURE_QUANTA.GENOA_SP5(CHIPS)':
 'VSS_AJ42': CDS_PINID='VSS_AJ42';
NODE_NAME     U25 AJ45
 '@T6G_MB_LIB.T6G(SCH_1):PAGE31_I22@PURE_QUANTA.GENOA_SP5(CHIPS)':
 'VSS_AJ45': CDS_PINID='VSS_AJ45';
NODE_NAME     U25 AJ48
 '@T6G_MB_LIB.T6G(SCH_1):PAGE31_I22@PURE_QUANTA.GENOA_SP5(CHIPS)':
 'VSS_AJ48': CDS_PINID='VSS_AJ48';
NODE_NAME     U25 AJ51
 '@T6G_MB_LIB.T6G(SCH_1):PAGE31_I22@PURE_QUANTA.GENOA_SP5(CHIPS)':
 'VSS_AJ51': CDS_PINID='VSS_AJ51';
NODE_NAME     U25 AJ54
 '@T6G_MB_LIB.T6G(SCH_1):PAGE31_I22@PURE_QUANTA.GENOA_SP5(CHIPS)':
 'VSS_AJ54': CDS_PINID='VSS_AJ54';
NODE_NAME     U25 AJ56
 '@T6G_MB_LIB.T6G(SCH_1):PAGE31_I22@PURE_QUANTA.GENOA_SP5(CHIPS)':
 'VSS_AJ56': CDS_PINID='VSS_AJ56';
NODE_NAME     U25 AJ61
 '@T6G_MB_LIB.T6G(SCH_1):PAGE31_I22@PURE_QUANTA.GENOA_SP5(CHIPS)':
 'VSS_AJ61': CDS_PINID='VSS_AJ61';
NODE_NAME     U25 AJ63
 '@T6G_MB_LIB.T6G(SCH_1):PAGE31_I22@PURE_QUANTA.GENOA_SP5(CHIPS)':
 'VSS_AJ63': CDS_PINID='VSS_AJ63';
NODE_NAME     U25 AJ68
 '@T6G_MB_LIB.T6G(SCH_1):PAGE31_I22@PURE_QUANTA.GENOA_SP5(CHIPS)':
 'VSS_AJ68': CDS_PINID='VSS_AJ68';
NODE_NAME     U25 AJ70
 '@T6G_MB_LIB.T6G(SCH_1):PAGE31_I22@PURE_QUANTA.GENOA_SP5(CHIPS)':
 'VSS_AJ70': CDS_PINID='VSS_AJ70';
NODE_NAME     U25 AJ75
 '@T6G_MB_LIB.T6G(SCH_1):PAGE31_I22@PURE_QUANTA.GENOA_SP5(CHIPS)':
 'VSS_AJ75': CDS_PINID='VSS_AJ75';
NODE_NAME     U25 AK3
 '@T6G_MB_LIB.T6G(SCH_1):PAGE31_I22@PURE_QUANTA.GENOA_SP5(CHIPS)':
 'VSS_AK3': CDS_PINID='VSS_AK3';
NODE_NAME     U25 AK5
 '@T6G_MB_LIB.T6G(SCH_1):PAGE31_I22@PURE_QUANTA.GENOA_SP5(CHIPS)':
 'VSS_AK5': CDS_PINID='VSS_AK5';
NODE_NAME     U25 AK8
 '@T6G_MB_LIB.T6G(SCH_1):PAGE31_I22@PURE_QUANTA.GENOA_SP5(CHIPS)':
 'VSS_AK8': CDS_PINID='VSS_AK8';
NODE_NAME     U25 AK10
 '@T6G_MB_LIB.T6G(SCH_1):PAGE31_I22@PURE_QUANTA.GENOA_SP5(CHIPS)':
 'VSS_AK10': CDS_PINID='VSS_AK10';
NODE_NAME     U25 AK12
 '@T6G_MB_LIB.T6G(SCH_1):PAGE31_I22@PURE_QUANTA.GENOA_SP5(CHIPS)':
 'VSS_AK12': CDS_PINID='VSS_AK12';
NODE_NAME     U25 AK15
 '@T6G_MB_LIB.T6G(SCH_1):PAGE31_I22@PURE_QUANTA.GENOA_SP5(CHIPS)':
 'VSS_AK15': CDS_PINID='VSS_AK15';
NODE_NAME     U25 AK17
 '@T6G_MB_LIB.T6G(SCH_1):PAGE31_I22@PURE_QUANTA.GENOA_SP5(CHIPS)':
 'VSS_AK17': CDS_PINID='VSS_AK17';
NODE_NAME     U25 AK19
 '@T6G_MB_LIB.T6G(SCH_1):PAGE31_I22@PURE_QUANTA.GENOA_SP5(CHIPS)':
 'VSS_AK19': CDS_PINID='VSS_AK19';
NODE_NAME     U25 AK22
 '@T6G_MB_LIB.T6G(SCH_1):PAGE31_I22@PURE_QUANTA.GENOA_SP5(CHIPS)':
 'VSS_AK22': CDS_PINID='VSS_AK22';
NODE_NAME     U25 AK25
 '@T6G_MB_LIB.T6G(SCH_1):PAGE31_I22@PURE_QUANTA.GENOA_SP5(CHIPS)':
 'VSS_AK25': CDS_PINID='VSS_AK25';
NODE_NAME     U25 AK28
 '@T6G_MB_LIB.T6G(SCH_1):PAGE31_I22@PURE_QUANTA.GENOA_SP5(CHIPS)':
 'VSS_AK28': CDS_PINID='VSS_AK28';
NODE_NAME     U25 AK31
 '@T6G_MB_LIB.T6G(SCH_1):PAGE31_I22@PURE_QUANTA.GENOA_SP5(CHIPS)':
 'VSS_AK31': CDS_PINID='VSS_AK31';
NODE_NAME     U25 AK34
 '@T6G_MB_LIB.T6G(SCH_1):PAGE31_I22@PURE_QUANTA.GENOA_SP5(CHIPS)':
 'VSS_AK34': CDS_PINID='VSS_AK34';
NODE_NAME     U25 AK37
 '@T6G_MB_LIB.T6G(SCH_1):PAGE31_I22@PURE_QUANTA.GENOA_SP5(CHIPS)':
 'VSS_AK37': CDS_PINID='VSS_AK37';
NODE_NAME     U25 AK39
 '@T6G_MB_LIB.T6G(SCH_1):PAGE31_I22@PURE_QUANTA.GENOA_SP5(CHIPS)':
 'VSS_AK39': CDS_PINID='VSS_AK39';
NODE_NAME     U25 AK42
 '@T6G_MB_LIB.T6G(SCH_1):PAGE31_I22@PURE_QUANTA.GENOA_SP5(CHIPS)':
 'VSS_AK42': CDS_PINID='VSS_AK42';
NODE_NAME     U25 AK45
 '@T6G_MB_LIB.T6G(SCH_1):PAGE31_I22@PURE_QUANTA.GENOA_SP5(CHIPS)':
 'VSS_AK45': CDS_PINID='VSS_AK45';
NODE_NAME     U25 AK48
 '@T6G_MB_LIB.T6G(SCH_1):PAGE31_I22@PURE_QUANTA.GENOA_SP5(CHIPS)':
 'VSS_AK48': CDS_PINID='VSS_AK48';
NODE_NAME     U25 AK51
 '@T6G_MB_LIB.T6G(SCH_1):PAGE31_I22@PURE_QUANTA.GENOA_SP5(CHIPS)':
 'VSS_AK51': CDS_PINID='VSS_AK51';
NODE_NAME     U25 AK54
 '@T6G_MB_LIB.T6G(SCH_1):PAGE31_I22@PURE_QUANTA.GENOA_SP5(CHIPS)':
 'VSS_AK54': CDS_PINID='VSS_AK54';
NODE_NAME     U25 AK57
 '@T6G_MB_LIB.T6G(SCH_1):PAGE31_I22@PURE_QUANTA.GENOA_SP5(CHIPS)':
 'VSS_AK57': CDS_PINID='VSS_AK57';
NODE_NAME     U25 AK59
 '@T6G_MB_LIB.T6G(SCH_1):PAGE31_I22@PURE_QUANTA.GENOA_SP5(CHIPS)':
 'VSS_AK59': CDS_PINID='VSS_AK59';
NODE_NAME     U25 AK61
 '@T6G_MB_LIB.T6G(SCH_1):PAGE31_I22@PURE_QUANTA.GENOA_SP5(CHIPS)':
 'VSS_AK61': CDS_PINID='VSS_AK61';
NODE_NAME     U25 AK64
 '@T6G_MB_LIB.T6G(SCH_1):PAGE31_I22@PURE_QUANTA.GENOA_SP5(CHIPS)':
 'VSS_AK64': CDS_PINID='VSS_AK64';
NODE_NAME     U25 AK66
 '@T6G_MB_LIB.T6G(SCH_1):PAGE31_I22@PURE_QUANTA.GENOA_SP5(CHIPS)':
 'VSS_AK66': CDS_PINID='VSS_AK66';
NODE_NAME     U25 AK68
 '@T6G_MB_LIB.T6G(SCH_1):PAGE31_I22@PURE_QUANTA.GENOA_SP5(CHIPS)':
 'VSS_AK68': CDS_PINID='VSS_AK68';
NODE_NAME     U25 AK71
 '@T6G_MB_LIB.T6G(SCH_1):PAGE31_I22@PURE_QUANTA.GENOA_SP5(CHIPS)':
 'VSS_AK71': CDS_PINID='VSS_AK71';
NODE_NAME     U25 AK73
 '@T6G_MB_LIB.T6G(SCH_1):PAGE31_I22@PURE_QUANTA.GENOA_SP5(CHIPS)':
 'VSS_AK73': CDS_PINID='VSS_AK73';
NODE_NAME     U25 AL1
 '@T6G_MB_LIB.T6G(SCH_1):PAGE31_I22@PURE_QUANTA.GENOA_SP5(CHIPS)':
 'VSS_AL1': CDS_PINID='VSS_AL1';
NODE_NAME     U25 AL4
 '@T6G_MB_LIB.T6G(SCH_1):PAGE31_I22@PURE_QUANTA.GENOA_SP5(CHIPS)':
 'VSS_AL4': CDS_PINID='VSS_AL4';
NODE_NAME     U25 AL6
 '@T6G_MB_LIB.T6G(SCH_1):PAGE31_I22@PURE_QUANTA.GENOA_SP5(CHIPS)':
 'VSS_AL6': CDS_PINID='VSS_AL6';
NODE_NAME     U25 AL8
 '@T6G_MB_LIB.T6G(SCH_1):PAGE31_I22@PURE_QUANTA.GENOA_SP5(CHIPS)':
 'VSS_AL8': CDS_PINID='VSS_AL8';
NODE_NAME     U25 AL11
 '@T6G_MB_LIB.T6G(SCH_1):PAGE31_I22@PURE_QUANTA.GENOA_SP5(CHIPS)':
 'VSS_AL11': CDS_PINID='VSS_AL11';
NODE_NAME     U25 AL13
 '@T6G_MB_LIB.T6G(SCH_1):PAGE31_I22@PURE_QUANTA.GENOA_SP5(CHIPS)':
 'VSS_AL13': CDS_PINID='VSS_AL13';
NODE_NAME     U25 AL15
 '@T6G_MB_LIB.T6G(SCH_1):PAGE31_I22@PURE_QUANTA.GENOA_SP5(CHIPS)':
 'VSS_AL15': CDS_PINID='VSS_AL15';
NODE_NAME     U25 AL18
 '@T6G_MB_LIB.T6G(SCH_1):PAGE31_I22@PURE_QUANTA.GENOA_SP5(CHIPS)':
 'VSS_AL18': CDS_PINID='VSS_AL18';
NODE_NAME     U25 AL20
 '@T6G_MB_LIB.T6G(SCH_1):PAGE31_I22@PURE_QUANTA.GENOA_SP5(CHIPS)':
 'VSS_AL20': CDS_PINID='VSS_AL20';
NODE_NAME     U25 AL22
 '@T6G_MB_LIB.T6G(SCH_1):PAGE31_I22@PURE_QUANTA.GENOA_SP5(CHIPS)':
 'VSS_AL22': CDS_PINID='VSS_AL22';
NODE_NAME     U25 AL25
 '@T6G_MB_LIB.T6G(SCH_1):PAGE31_I22@PURE_QUANTA.GENOA_SP5(CHIPS)':
 'VSS_AL25': CDS_PINID='VSS_AL25';
NODE_NAME     U25 AL28
 '@T6G_MB_LIB.T6G(SCH_1):PAGE31_I22@PURE_QUANTA.GENOA_SP5(CHIPS)':
 'VSS_AL28': CDS_PINID='VSS_AL28';
NODE_NAME     U25 AL31
 '@T6G_MB_LIB.T6G(SCH_1):PAGE31_I22@PURE_QUANTA.GENOA_SP5(CHIPS)':
 'VSS_AL31': CDS_PINID='VSS_AL31';
NODE_NAME     U25 AL34
 '@T6G_MB_LIB.T6G(SCH_1):PAGE31_I22@PURE_QUANTA.GENOA_SP5(CHIPS)':
 'VSS_AL34': CDS_PINID='VSS_AL34';
NODE_NAME     U25 AL42
 '@T6G_MB_LIB.T6G(SCH_1):PAGE31_I22@PURE_QUANTA.GENOA_SP5(CHIPS)':
 'VSS_AL42': CDS_PINID='VSS_AL42';
NODE_NAME     U25 AL45
 '@T6G_MB_LIB.T6G(SCH_1):PAGE31_I22@PURE_QUANTA.GENOA_SP5(CHIPS)':
 'VSS_AL45': CDS_PINID='VSS_AL45';
NODE_NAME     U25 AL48
 '@T6G_MB_LIB.T6G(SCH_1):PAGE31_I22@PURE_QUANTA.GENOA_SP5(CHIPS)':
 'VSS_AL48': CDS_PINID='VSS_AL48';
NODE_NAME     U25 AL51
 '@T6G_MB_LIB.T6G(SCH_1):PAGE31_I22@PURE_QUANTA.GENOA_SP5(CHIPS)':
 'VSS_AL51': CDS_PINID='VSS_AL51';
NODE_NAME     U25 AL54
 '@T6G_MB_LIB.T6G(SCH_1):PAGE31_I22@PURE_QUANTA.GENOA_SP5(CHIPS)':
 'VSS_AL54': CDS_PINID='VSS_AL54';
NODE_NAME     U25 AL56
 '@T6G_MB_LIB.T6G(SCH_1):PAGE31_I22@PURE_QUANTA.GENOA_SP5(CHIPS)':
 'VSS_AL56': CDS_PINID='VSS_AL56';
NODE_NAME     U25 AL58
 '@T6G_MB_LIB.T6G(SCH_1):PAGE31_I22@PURE_QUANTA.GENOA_SP5(CHIPS)':
 'VSS_AL58': CDS_PINID='VSS_AL58';
NODE_NAME     U25 AL61
 '@T6G_MB_LIB.T6G(SCH_1):PAGE31_I22@PURE_QUANTA.GENOA_SP5(CHIPS)':
 'VSS_AL61': CDS_PINID='VSS_AL61';
NODE_NAME     U25 AL63
 '@T6G_MB_LIB.T6G(SCH_1):PAGE31_I22@PURE_QUANTA.GENOA_SP5(CHIPS)':
 'VSS_AL63': CDS_PINID='VSS_AL63';
NODE_NAME     U25 AL65
 '@T6G_MB_LIB.T6G(SCH_1):PAGE31_I22@PURE_QUANTA.GENOA_SP5(CHIPS)':
 'VSS_AL65': CDS_PINID='VSS_AL65';
NODE_NAME     U25 AL68
 '@T6G_MB_LIB.T6G(SCH_1):PAGE31_I22@PURE_QUANTA.GENOA_SP5(CHIPS)':
 'VSS_AL68': CDS_PINID='VSS_AL68';
NODE_NAME     U25 AL70
 '@T6G_MB_LIB.T6G(SCH_1):PAGE31_I22@PURE_QUANTA.GENOA_SP5(CHIPS)':
 'VSS_AL70': CDS_PINID='VSS_AL70';
NODE_NAME     U25 AL72
 '@T6G_MB_LIB.T6G(SCH_1):PAGE31_I22@PURE_QUANTA.GENOA_SP5(CHIPS)':
 'VSS_AL72': CDS_PINID='VSS_AL72';
NODE_NAME     U25 AL75
 '@T6G_MB_LIB.T6G(SCH_1):PAGE31_I22@PURE_QUANTA.GENOA_SP5(CHIPS)':
 'VSS_AL75': CDS_PINID='VSS_AL75';
NODE_NAME     U25 AM3
 '@T6G_MB_LIB.T6G(SCH_1):PAGE31_I22@PURE_QUANTA.GENOA_SP5(CHIPS)':
 'VSS_AM3': CDS_PINID='VSS_AM3';
NODE_NAME     U25 AM8
 '@T6G_MB_LIB.T6G(SCH_1):PAGE31_I22@PURE_QUANTA.GENOA_SP5(CHIPS)':
 'VSS_AM8': CDS_PINID='VSS_AM8';
NODE_NAME     U25 AM10
 '@T6G_MB_LIB.T6G(SCH_1):PAGE31_I22@PURE_QUANTA.GENOA_SP5(CHIPS)':
 'VSS_AM10': CDS_PINID='VSS_AM10';
NODE_NAME     U25 AM15
 '@T6G_MB_LIB.T6G(SCH_1):PAGE31_I22@PURE_QUANTA.GENOA_SP5(CHIPS)':
 'VSS_AM15': CDS_PINID='VSS_AM15';
NODE_NAME     U25 AM17
 '@T6G_MB_LIB.T6G(SCH_1):PAGE31_I22@PURE_QUANTA.GENOA_SP5(CHIPS)':
 'VSS_AM17': CDS_PINID='VSS_AM17';
NODE_NAME     U25 AM23
 '@T6G_MB_LIB.T6G(SCH_1):PAGE31_I22@PURE_QUANTA.GENOA_SP5(CHIPS)':
 'VSS_AM23': CDS_PINID='VSS_AM23';
NODE_NAME     U25 AM24
 '@T6G_MB_LIB.T6G(SCH_1):PAGE31_I22@PURE_QUANTA.GENOA_SP5(CHIPS)':
 'VSS_AM24': CDS_PINID='VSS_AM24';
NODE_NAME     U25 AM25
 '@T6G_MB_LIB.T6G(SCH_1):PAGE31_I22@PURE_QUANTA.GENOA_SP5(CHIPS)':
 'VSS_AM25': CDS_PINID='VSS_AM25';
NODE_NAME     U25 AM26
 '@T6G_MB_LIB.T6G(SCH_1):PAGE31_I22@PURE_QUANTA.GENOA_SP5(CHIPS)':
 'VSS_AM26': CDS_PINID='VSS_AM26';
NODE_NAME     U25 AM27
 '@T6G_MB_LIB.T6G(SCH_1):PAGE31_I22@PURE_QUANTA.GENOA_SP5(CHIPS)':
 'VSS_AM27': CDS_PINID='VSS_AM27';
NODE_NAME     U25 AM28
 '@T6G_MB_LIB.T6G(SCH_1):PAGE31_I22@PURE_QUANTA.GENOA_SP5(CHIPS)':
 'VSS_AM28': CDS_PINID='VSS_AM28';
NODE_NAME     U25 AM29
 '@T6G_MB_LIB.T6G(SCH_1):PAGE31_I22@PURE_QUANTA.GENOA_SP5(CHIPS)':
 'VSS_AM29': CDS_PINID='VSS_AM29';
NODE_NAME     U25 AM30
 '@T6G_MB_LIB.T6G(SCH_1):PAGE31_I22@PURE_QUANTA.GENOA_SP5(CHIPS)':
 'VSS_AM30': CDS_PINID='VSS_AM30';
NODE_NAME     U25 AM31
 '@T6G_MB_LIB.T6G(SCH_1):PAGE31_I22@PURE_QUANTA.GENOA_SP5(CHIPS)':
 'VSS_AM31': CDS_PINID='VSS_AM31';
NODE_NAME     U25 AM32
 '@T6G_MB_LIB.T6G(SCH_1):PAGE31_I22@PURE_QUANTA.GENOA_SP5(CHIPS)':
 'VSS_AM32': CDS_PINID='VSS_AM32';
NODE_NAME     U25 AM33
 '@T6G_MB_LIB.T6G(SCH_1):PAGE31_I22@PURE_QUANTA.GENOA_SP5(CHIPS)':
 'VSS_AM33': CDS_PINID='VSS_AM33';
NODE_NAME     U25 AM34
 '@T6G_MB_LIB.T6G(SCH_1):PAGE31_I22@PURE_QUANTA.GENOA_SP5(CHIPS)':
 'VSS_AM34': CDS_PINID='VSS_AM34';
NODE_NAME     U25 AM39
 '@T6G_MB_LIB.T6G(SCH_1):PAGE31_I22@PURE_QUANTA.GENOA_SP5(CHIPS)':
 'VSS_AM39': CDS_PINID='VSS_AM39';
NODE_NAME     U25 AM42
 '@T6G_MB_LIB.T6G(SCH_1):PAGE31_I23@PURE_QUANTA.GENOA_SP5(CHIPS)':
 'VSS_AM42': CDS_PINID='VSS_AM42';
NODE_NAME     U25 AM43
 '@T6G_MB_LIB.T6G(SCH_1):PAGE31_I23@PURE_QUANTA.GENOA_SP5(CHIPS)':
 'VSS_AM43': CDS_PINID='VSS_AM43';
NODE_NAME     U25 AM44
 '@T6G_MB_LIB.T6G(SCH_1):PAGE31_I23@PURE_QUANTA.GENOA_SP5(CHIPS)':
 'VSS_AM44': CDS_PINID='VSS_AM44';
NODE_NAME     U25 AM45
 '@T6G_MB_LIB.T6G(SCH_1):PAGE31_I23@PURE_QUANTA.GENOA_SP5(CHIPS)':
 'VSS_AM45': CDS_PINID='VSS_AM45';
NODE_NAME     U25 AM46
 '@T6G_MB_LIB.T6G(SCH_1):PAGE31_I23@PURE_QUANTA.GENOA_SP5(CHIPS)':
 'VSS_AM46': CDS_PINID='VSS_AM46';
NODE_NAME     U25 AM47
 '@T6G_MB_LIB.T6G(SCH_1):PAGE31_I23@PURE_QUANTA.GENOA_SP5(CHIPS)':
 'VSS_AM47': CDS_PINID='VSS_AM47';
NODE_NAME     U25 AM48
 '@T6G_MB_LIB.T6G(SCH_1):PAGE31_I23@PURE_QUANTA.GENOA_SP5(CHIPS)':
 'VSS_AM48': CDS_PINID='VSS_AM48';
NODE_NAME     U25 AM49
 '@T6G_MB_LIB.T6G(SCH_1):PAGE31_I23@PURE_QUANTA.GENOA_SP5(CHIPS)':
 'VSS_AM49': CDS_PINID='VSS_AM49';
NODE_NAME     U25 AM50
 '@T6G_MB_LIB.T6G(SCH_1):PAGE31_I23@PURE_QUANTA.GENOA_SP5(CHIPS)':
 'VSS_AM50': CDS_PINID='VSS_AM50';
NODE_NAME     U25 AM51
 '@T6G_MB_LIB.T6G(SCH_1):PAGE31_I23@PURE_QUANTA.GENOA_SP5(CHIPS)':
 'VSS_AM51': CDS_PINID='VSS_AM51';
NODE_NAME     U25 AM52
 '@T6G_MB_LIB.T6G(SCH_1):PAGE31_I23@PURE_QUANTA.GENOA_SP5(CHIPS)':
 'VSS_AM52': CDS_PINID='VSS_AM52';
NODE_NAME     U25 AM53
 '@T6G_MB_LIB.T6G(SCH_1):PAGE31_I23@PURE_QUANTA.GENOA_SP5(CHIPS)':
 'VSS_AM53': CDS_PINID='VSS_AM53';
NODE_NAME     U25 AM59
 '@T6G_MB_LIB.T6G(SCH_1):PAGE31_I23@PURE_QUANTA.GENOA_SP5(CHIPS)':
 'VSS_AM59': CDS_PINID='VSS_AM59';
NODE_NAME     U25 AM61
 '@T6G_MB_LIB.T6G(SCH_1):PAGE31_I23@PURE_QUANTA.GENOA_SP5(CHIPS)':
 'VSS_AM61': CDS_PINID='VSS_AM61';
NODE_NAME     U25 AM66
 '@T6G_MB_LIB.T6G(SCH_1):PAGE31_I23@PURE_QUANTA.GENOA_SP5(CHIPS)':
 'VSS_AM66': CDS_PINID='VSS_AM66';
NODE_NAME     U25 AM68
 '@T6G_MB_LIB.T6G(SCH_1):PAGE31_I23@PURE_QUANTA.GENOA_SP5(CHIPS)':
 'VSS_AM68': CDS_PINID='VSS_AM68';
NODE_NAME     U25 AM73
 '@T6G_MB_LIB.T6G(SCH_1):PAGE31_I23@PURE_QUANTA.GENOA_SP5(CHIPS)':
 'VSS_AM73': CDS_PINID='VSS_AM73';
NODE_NAME     U25 AN1
 '@T6G_MB_LIB.T6G(SCH_1):PAGE31_I23@PURE_QUANTA.GENOA_SP5(CHIPS)':
 'VSS_AN1': CDS_PINID='VSS_AN1';
NODE_NAME     U25 AN4
 '@T6G_MB_LIB.T6G(SCH_1):PAGE31_I23@PURE_QUANTA.GENOA_SP5(CHIPS)':
 'VSS_AN4': CDS_PINID='VSS_AN4';
NODE_NAME     U25 AN6
 '@T6G_MB_LIB.T6G(SCH_1):PAGE31_I23@PURE_QUANTA.GENOA_SP5(CHIPS)':
 'VSS_AN6': CDS_PINID='VSS_AN6';
NODE_NAME     U25 AN8
 '@T6G_MB_LIB.T6G(SCH_1):PAGE31_I23@PURE_QUANTA.GENOA_SP5(CHIPS)':
 'VSS_AN8': CDS_PINID='VSS_AN8';
NODE_NAME     U25 AN11
 '@T6G_MB_LIB.T6G(SCH_1):PAGE31_I23@PURE_QUANTA.GENOA_SP5(CHIPS)':
 'VSS_AN11': CDS_PINID='VSS_AN11';
NODE_NAME     U25 AN13
 '@T6G_MB_LIB.T6G(SCH_1):PAGE31_I23@PURE_QUANTA.GENOA_SP5(CHIPS)':
 'VSS_AN13': CDS_PINID='VSS_AN13';
NODE_NAME     U25 AN15
 '@T6G_MB_LIB.T6G(SCH_1):PAGE31_I23@PURE_QUANTA.GENOA_SP5(CHIPS)':
 'VSS_AN15': CDS_PINID='VSS_AN15';
NODE_NAME     U25 AN18
 '@T6G_MB_LIB.T6G(SCH_1):PAGE31_I23@PURE_QUANTA.GENOA_SP5(CHIPS)':
 'VSS_AN18': CDS_PINID='VSS_AN18';
NODE_NAME     U25 AN22
 '@T6G_MB_LIB.T6G(SCH_1):PAGE31_I23@PURE_QUANTA.GENOA_SP5(CHIPS)':
 'VSS_AN22': CDS_PINID='VSS_AN22';
NODE_NAME     U25 AN25
 '@T6G_MB_LIB.T6G(SCH_1):PAGE31_I23@PURE_QUANTA.GENOA_SP5(CHIPS)':
 'VSS_AN25': CDS_PINID='VSS_AN25';
NODE_NAME     U25 AN28
 '@T6G_MB_LIB.T6G(SCH_1):PAGE31_I23@PURE_QUANTA.GENOA_SP5(CHIPS)':
 'VSS_AN28': CDS_PINID='VSS_AN28';
NODE_NAME     U25 AN31
 '@T6G_MB_LIB.T6G(SCH_1):PAGE31_I23@PURE_QUANTA.GENOA_SP5(CHIPS)':
 'VSS_AN31': CDS_PINID='VSS_AN31';
NODE_NAME     U25 AN34
 '@T6G_MB_LIB.T6G(SCH_1):PAGE31_I23@PURE_QUANTA.GENOA_SP5(CHIPS)':
 'VSS_AN34': CDS_PINID='VSS_AN34';
NODE_NAME     U25 AN35
 '@T6G_MB_LIB.T6G(SCH_1):PAGE31_I23@PURE_QUANTA.GENOA_SP5(CHIPS)':
 'VSS_AN35': CDS_PINID='VSS_AN35';
NODE_NAME     U25 AN36
 '@T6G_MB_LIB.T6G(SCH_1):PAGE31_I23@PURE_QUANTA.GENOA_SP5(CHIPS)':
 'VSS_AN36': CDS_PINID='VSS_AN36';
NODE_NAME     U25 AN40
 '@T6G_MB_LIB.T6G(SCH_1):PAGE31_I23@PURE_QUANTA.GENOA_SP5(CHIPS)':
 'VSS_AN40': CDS_PINID='VSS_AN40';
NODE_NAME     U25 AN41
 '@T6G_MB_LIB.T6G(SCH_1):PAGE31_I23@PURE_QUANTA.GENOA_SP5(CHIPS)':
 'VSS_AN41': CDS_PINID='VSS_AN41';
NODE_NAME     U25 AN42
 '@T6G_MB_LIB.T6G(SCH_1):PAGE31_I23@PURE_QUANTA.GENOA_SP5(CHIPS)':
 'VSS_AN42': CDS_PINID='VSS_AN42';
NODE_NAME     U25 AN45
 '@T6G_MB_LIB.T6G(SCH_1):PAGE31_I23@PURE_QUANTA.GENOA_SP5(CHIPS)':
 'VSS_AN45': CDS_PINID='VSS_AN45';
NODE_NAME     U25 AN48
 '@T6G_MB_LIB.T6G(SCH_1):PAGE31_I23@PURE_QUANTA.GENOA_SP5(CHIPS)':
 'VSS_AN48': CDS_PINID='VSS_AN48';
NODE_NAME     U25 AN51
 '@T6G_MB_LIB.T6G(SCH_1):PAGE31_I23@PURE_QUANTA.GENOA_SP5(CHIPS)':
 'VSS_AN51': CDS_PINID='VSS_AN51';
NODE_NAME     U25 AN54
 '@T6G_MB_LIB.T6G(SCH_1):PAGE31_I23@PURE_QUANTA.GENOA_SP5(CHIPS)':
 'VSS_AN54': CDS_PINID='VSS_AN54';
NODE_NAME     U25 AN56
 '@T6G_MB_LIB.T6G(SCH_1):PAGE31_I23@PURE_QUANTA.GENOA_SP5(CHIPS)':
 'VSS_AN56': CDS_PINID='VSS_AN56';
NODE_NAME     U25 AN58
 '@T6G_MB_LIB.T6G(SCH_1):PAGE31_I23@PURE_QUANTA.GENOA_SP5(CHIPS)':
 'VSS_AN58': CDS_PINID='VSS_AN58';
NODE_NAME     U25 AN61
 '@T6G_MB_LIB.T6G(SCH_1):PAGE31_I23@PURE_QUANTA.GENOA_SP5(CHIPS)':
 'VSS_AN61': CDS_PINID='VSS_AN61';
NODE_NAME     U25 AN63
 '@T6G_MB_LIB.T6G(SCH_1):PAGE31_I23@PURE_QUANTA.GENOA_SP5(CHIPS)':
 'VSS_AN63': CDS_PINID='VSS_AN63';
NODE_NAME     U25 AN65
 '@T6G_MB_LIB.T6G(SCH_1):PAGE31_I23@PURE_QUANTA.GENOA_SP5(CHIPS)':
 'VSS_AN65': CDS_PINID='VSS_AN65';
NODE_NAME     U25 AN68
 '@T6G_MB_LIB.T6G(SCH_1):PAGE31_I23@PURE_QUANTA.GENOA_SP5(CHIPS)':
 'VSS_AN68': CDS_PINID='VSS_AN68';
NODE_NAME     U25 AN70
 '@T6G_MB_LIB.T6G(SCH_1):PAGE31_I23@PURE_QUANTA.GENOA_SP5(CHIPS)':
 'VSS_AN70': CDS_PINID='VSS_AN70';
NODE_NAME     U25 AN72
 '@T6G_MB_LIB.T6G(SCH_1):PAGE31_I23@PURE_QUANTA.GENOA_SP5(CHIPS)':
 'VSS_AN72': CDS_PINID='VSS_AN72';
NODE_NAME     U25 AN75
 '@T6G_MB_LIB.T6G(SCH_1):PAGE31_I23@PURE_QUANTA.GENOA_SP5(CHIPS)':
 'VSS_AN75': CDS_PINID='VSS_AN75';
NODE_NAME     U25 AP3
 '@T6G_MB_LIB.T6G(SCH_1):PAGE31_I23@PURE_QUANTA.GENOA_SP5(CHIPS)':
 'VSS_AP3': CDS_PINID='VSS_AP3';
NODE_NAME     U25 AP5
 '@T6G_MB_LIB.T6G(SCH_1):PAGE31_I23@PURE_QUANTA.GENOA_SP5(CHIPS)':
 'VSS_AP5': CDS_PINID='VSS_AP5';
NODE_NAME     U25 AP8
 '@T6G_MB_LIB.T6G(SCH_1):PAGE31_I23@PURE_QUANTA.GENOA_SP5(CHIPS)':
 'VSS_AP8': CDS_PINID='VSS_AP8';
NODE_NAME     U25 AP10
 '@T6G_MB_LIB.T6G(SCH_1):PAGE31_I23@PURE_QUANTA.GENOA_SP5(CHIPS)':
 'VSS_AP10': CDS_PINID='VSS_AP10';
NODE_NAME     U25 AP12
 '@T6G_MB_LIB.T6G(SCH_1):PAGE31_I23@PURE_QUANTA.GENOA_SP5(CHIPS)':
 'VSS_AP12': CDS_PINID='VSS_AP12';
NODE_NAME     U25 AP15
 '@T6G_MB_LIB.T6G(SCH_1):PAGE31_I23@PURE_QUANTA.GENOA_SP5(CHIPS)':
 'VSS_AP15': CDS_PINID='VSS_AP15';
NODE_NAME     U25 AP17
 '@T6G_MB_LIB.T6G(SCH_1):PAGE31_I23@PURE_QUANTA.GENOA_SP5(CHIPS)':
 'VSS_AP17': CDS_PINID='VSS_AP17';
NODE_NAME     U25 AP19
 '@T6G_MB_LIB.T6G(SCH_1):PAGE31_I23@PURE_QUANTA.GENOA_SP5(CHIPS)':
 'VSS_AP19': CDS_PINID='VSS_AP19';
NODE_NAME     U25 AP22
 '@T6G_MB_LIB.T6G(SCH_1):PAGE31_I23@PURE_QUANTA.GENOA_SP5(CHIPS)':
 'VSS_AP22': CDS_PINID='VSS_AP22';
NODE_NAME     U25 AP25
 '@T6G_MB_LIB.T6G(SCH_1):PAGE31_I23@PURE_QUANTA.GENOA_SP5(CHIPS)':
 'VSS_AP25': CDS_PINID='VSS_AP25';
NODE_NAME     U25 AP28
 '@T6G_MB_LIB.T6G(SCH_1):PAGE31_I23@PURE_QUANTA.GENOA_SP5(CHIPS)':
 'VSS_AP28': CDS_PINID='VSS_AP28';
NODE_NAME     U25 AP31
 '@T6G_MB_LIB.T6G(SCH_1):PAGE31_I23@PURE_QUANTA.GENOA_SP5(CHIPS)':
 'VSS_AP31': CDS_PINID='VSS_AP31';
NODE_NAME     U25 AP34
 '@T6G_MB_LIB.T6G(SCH_1):PAGE31_I23@PURE_QUANTA.GENOA_SP5(CHIPS)':
 'VSS_AP34': CDS_PINID='VSS_AP34';
NODE_NAME     U25 AP37
 '@T6G_MB_LIB.T6G(SCH_1):PAGE31_I23@PURE_QUANTA.GENOA_SP5(CHIPS)':
 'VSS_AP37': CDS_PINID='VSS_AP37';
NODE_NAME     U25 AP39
 '@T6G_MB_LIB.T6G(SCH_1):PAGE31_I23@PURE_QUANTA.GENOA_SP5(CHIPS)':
 'VSS_AP39': CDS_PINID='VSS_AP39';
NODE_NAME     U25 AP42
 '@T6G_MB_LIB.T6G(SCH_1):PAGE31_I23@PURE_QUANTA.GENOA_SP5(CHIPS)':
 'VSS_AP42': CDS_PINID='VSS_AP42';
NODE_NAME     U25 AP45
 '@T6G_MB_LIB.T6G(SCH_1):PAGE31_I23@PURE_QUANTA.GENOA_SP5(CHIPS)':
 'VSS_AP45': CDS_PINID='VSS_AP45';
NODE_NAME     U25 AP48
 '@T6G_MB_LIB.T6G(SCH_1):PAGE31_I23@PURE_QUANTA.GENOA_SP5(CHIPS)':
 'VSS_AP48': CDS_PINID='VSS_AP48';
NODE_NAME     U25 AP51
 '@T6G_MB_LIB.T6G(SCH_1):PAGE31_I23@PURE_QUANTA.GENOA_SP5(CHIPS)':
 'VSS_AP51': CDS_PINID='VSS_AP51';
NODE_NAME     U25 AP54
 '@T6G_MB_LIB.T6G(SCH_1):PAGE31_I23@PURE_QUANTA.GENOA_SP5(CHIPS)':
 'VSS_AP54': CDS_PINID='VSS_AP54';
NODE_NAME     U25 AP57
 '@T6G_MB_LIB.T6G(SCH_1):PAGE31_I23@PURE_QUANTA.GENOA_SP5(CHIPS)':
 'VSS_AP57': CDS_PINID='VSS_AP57';
NODE_NAME     U25 AP59
 '@T6G_MB_LIB.T6G(SCH_1):PAGE31_I23@PURE_QUANTA.GENOA_SP5(CHIPS)':
 'VSS_AP59': CDS_PINID='VSS_AP59';
NODE_NAME     U25 AP61
 '@T6G_MB_LIB.T6G(SCH_1):PAGE31_I23@PURE_QUANTA.GENOA_SP5(CHIPS)':
 'VSS_AP61': CDS_PINID='VSS_AP61';
NODE_NAME     U25 AP64
 '@T6G_MB_LIB.T6G(SCH_1):PAGE31_I23@PURE_QUANTA.GENOA_SP5(CHIPS)':
 'VSS_AP64': CDS_PINID='VSS_AP64';
NODE_NAME     U25 AP66
 '@T6G_MB_LIB.T6G(SCH_1):PAGE31_I23@PURE_QUANTA.GENOA_SP5(CHIPS)':
 'VSS_AP66': CDS_PINID='VSS_AP66';
NODE_NAME     U25 AP68
 '@T6G_MB_LIB.T6G(SCH_1):PAGE31_I23@PURE_QUANTA.GENOA_SP5(CHIPS)':
 'VSS_AP68': CDS_PINID='VSS_AP68';
NODE_NAME     U25 AP71
 '@T6G_MB_LIB.T6G(SCH_1):PAGE31_I23@PURE_QUANTA.GENOA_SP5(CHIPS)':
 'VSS_AP71': CDS_PINID='VSS_AP71';
NODE_NAME     U25 AP73
 '@T6G_MB_LIB.T6G(SCH_1):PAGE31_I23@PURE_QUANTA.GENOA_SP5(CHIPS)':
 'VSS_AP73': CDS_PINID='VSS_AP73';
NODE_NAME     U25 AR1
 '@T6G_MB_LIB.T6G(SCH_1):PAGE31_I23@PURE_QUANTA.GENOA_SP5(CHIPS)':
 'VSS_AR1': CDS_PINID='VSS_AR1';
NODE_NAME     U25 AR5
 '@T6G_MB_LIB.T6G(SCH_1):PAGE31_I23@PURE_QUANTA.GENOA_SP5(CHIPS)':
 'VSS_AR5': CDS_PINID='VSS_AR5';
NODE_NAME     U25 AR6
 '@T6G_MB_LIB.T6G(SCH_1):PAGE31_I23@PURE_QUANTA.GENOA_SP5(CHIPS)':
 'VSS_AR6': CDS_PINID='VSS_AR6';
NODE_NAME     U25 AR8
 '@T6G_MB_LIB.T6G(SCH_1):PAGE31_I23@PURE_QUANTA.GENOA_SP5(CHIPS)':
 'VSS_AR8': CDS_PINID='VSS_AR8';
NODE_NAME     U25 AR9
 '@T6G_MB_LIB.T6G(SCH_1):PAGE31_I23@PURE_QUANTA.GENOA_SP5(CHIPS)':
 'VSS_AR9': CDS_PINID='VSS_AR9';
NODE_NAME     U25 AR12
 '@T6G_MB_LIB.T6G(SCH_1):PAGE31_I23@PURE_QUANTA.GENOA_SP5(CHIPS)':
 'VSS_AR12': CDS_PINID='VSS_AR12';
NODE_NAME     U25 AR13
 '@T6G_MB_LIB.T6G(SCH_1):PAGE31_I23@PURE_QUANTA.GENOA_SP5(CHIPS)':
 'VSS_AR13': CDS_PINID='VSS_AR13';
NODE_NAME     U25 AR15
 '@T6G_MB_LIB.T6G(SCH_1):PAGE31_I23@PURE_QUANTA.GENOA_SP5(CHIPS)':
 'VSS_AR15': CDS_PINID='VSS_AR15';
NODE_NAME     U25 AR16
 '@T6G_MB_LIB.T6G(SCH_1):PAGE31_I23@PURE_QUANTA.GENOA_SP5(CHIPS)':
 'VSS_AR16': CDS_PINID='VSS_AR16';
NODE_NAME     U25 AR19
 '@T6G_MB_LIB.T6G(SCH_1):PAGE31_I23@PURE_QUANTA.GENOA_SP5(CHIPS)':
 'VSS_AR19': CDS_PINID='VSS_AR19';
NODE_NAME     U25 AR20
 '@T6G_MB_LIB.T6G(SCH_1):PAGE31_I23@PURE_QUANTA.GENOA_SP5(CHIPS)':
 'VSS_AR20': CDS_PINID='VSS_AR20';
NODE_NAME     U25 AR22
 '@T6G_MB_LIB.T6G(SCH_1):PAGE31_I23@PURE_QUANTA.GENOA_SP5(CHIPS)':
 'VSS_AR22': CDS_PINID='VSS_AR22';
NODE_NAME     U25 AR24
 '@T6G_MB_LIB.T6G(SCH_1):PAGE31_I23@PURE_QUANTA.GENOA_SP5(CHIPS)':
 'VSS_AR24': CDS_PINID='VSS_AR24';
NODE_NAME     U25 AR26
 '@T6G_MB_LIB.T6G(SCH_1):PAGE31_I23@PURE_QUANTA.GENOA_SP5(CHIPS)':
 'VSS_AR26': CDS_PINID='VSS_AR26';
NODE_NAME     U25 AR28
 '@T6G_MB_LIB.T6G(SCH_1):PAGE31_I23@PURE_QUANTA.GENOA_SP5(CHIPS)':
 'VSS_AR28': CDS_PINID='VSS_AR28';
NODE_NAME     U25 AR30
 '@T6G_MB_LIB.T6G(SCH_1):PAGE31_I23@PURE_QUANTA.GENOA_SP5(CHIPS)':
 'VSS_AR30': CDS_PINID='VSS_AR30';
NODE_NAME     U25 AR32
 '@T6G_MB_LIB.T6G(SCH_1):PAGE31_I23@PURE_QUANTA.GENOA_SP5(CHIPS)':
 'VSS_AR32': CDS_PINID='VSS_AR32';
NODE_NAME     U25 AR34
 '@T6G_MB_LIB.T6G(SCH_1):PAGE31_I23@PURE_QUANTA.GENOA_SP5(CHIPS)':
 'VSS_AR34': CDS_PINID='VSS_AR34';
NODE_NAME     U25 AR36
 '@T6G_MB_LIB.T6G(SCH_1):PAGE31_I23@PURE_QUANTA.GENOA_SP5(CHIPS)':
 'VSS_AR36': CDS_PINID='VSS_AR36';
NODE_NAME     U25 AR41
 '@T6G_MB_LIB.T6G(SCH_1):PAGE31_I23@PURE_QUANTA.GENOA_SP5(CHIPS)':
 'VSS_AR41': CDS_PINID='VSS_AR41';
NODE_NAME     U25 AR43
 '@T6G_MB_LIB.T6G(SCH_1):PAGE31_I23@PURE_QUANTA.GENOA_SP5(CHIPS)':
 'VSS_AR43': CDS_PINID='VSS_AR43';
NODE_NAME     U25 AR45
 '@T6G_MB_LIB.T6G(SCH_1):PAGE31_I23@PURE_QUANTA.GENOA_SP5(CHIPS)':
 'VSS_AR45': CDS_PINID='VSS_AR45';
NODE_NAME     U25 AR47
 '@T6G_MB_LIB.T6G(SCH_1):PAGE31_I23@PURE_QUANTA.GENOA_SP5(CHIPS)':
 'VSS_AR47': CDS_PINID='VSS_AR47';
NODE_NAME     U25 AR49
 '@T6G_MB_LIB.T6G(SCH_1):PAGE31_I23@PURE_QUANTA.GENOA_SP5(CHIPS)':
 'VSS_AR49': CDS_PINID='VSS_AR49';
NODE_NAME     U25 AR51
 '@T6G_MB_LIB.T6G(SCH_1):PAGE31_I23@PURE_QUANTA.GENOA_SP5(CHIPS)':
 'VSS_AR51': CDS_PINID='VSS_AR51';
NODE_NAME     U25 AR53
 '@T6G_MB_LIB.T6G(SCH_1):PAGE31_I23@PURE_QUANTA.GENOA_SP5(CHIPS)':
 'VSS_AR53': CDS_PINID='VSS_AR53';
NODE_NAME     U25 AR56
 '@T6G_MB_LIB.T6G(SCH_1):PAGE31_I23@PURE_QUANTA.GENOA_SP5(CHIPS)':
 'VSS_AR56': CDS_PINID='VSS_AR56';
NODE_NAME     U25 AR57
 '@T6G_MB_LIB.T6G(SCH_1):PAGE31_I23@PURE_QUANTA.GENOA_SP5(CHIPS)':
 'VSS_AR57': CDS_PINID='VSS_AR57';
NODE_NAME     U25 AR60
 '@T6G_MB_LIB.T6G(SCH_1):PAGE31_I23@PURE_QUANTA.GENOA_SP5(CHIPS)':
 'VSS_AR60': CDS_PINID='VSS_AR60';
NODE_NAME     U25 AR61
 '@T6G_MB_LIB.T6G(SCH_1):PAGE31_I23@PURE_QUANTA.GENOA_SP5(CHIPS)':
 'VSS_AR61': CDS_PINID='VSS_AR61';
NODE_NAME     U25 AR63
 '@T6G_MB_LIB.T6G(SCH_1):PAGE31_I23@PURE_QUANTA.GENOA_SP5(CHIPS)':
 'VSS_AR63': CDS_PINID='VSS_AR63';
NODE_NAME     U25 AR64
 '@T6G_MB_LIB.T6G(SCH_1):PAGE31_I23@PURE_QUANTA.GENOA_SP5(CHIPS)':
 'VSS_AR64': CDS_PINID='VSS_AR64';
NODE_NAME     U25 AR67
 '@T6G_MB_LIB.T6G(SCH_1):PAGE31_I23@PURE_QUANTA.GENOA_SP5(CHIPS)':
 'VSS_AR67': CDS_PINID='VSS_AR67';
NODE_NAME     U25 AR68
 '@T6G_MB_LIB.T6G(SCH_1):PAGE31_I23@PURE_QUANTA.GENOA_SP5(CHIPS)':
 'VSS_AR68': CDS_PINID='VSS_AR68';
NODE_NAME     U25 AR70
 '@T6G_MB_LIB.T6G(SCH_1):PAGE31_I23@PURE_QUANTA.GENOA_SP5(CHIPS)':
 'VSS_AR70': CDS_PINID='VSS_AR70';
NODE_NAME     U25 AR71
 '@T6G_MB_LIB.T6G(SCH_1):PAGE31_I23@PURE_QUANTA.GENOA_SP5(CHIPS)':
 'VSS_AR71': CDS_PINID='VSS_AR71';
NODE_NAME     U25 AR75
 '@T6G_MB_LIB.T6G(SCH_1):PAGE31_I23@PURE_QUANTA.GENOA_SP5(CHIPS)':
 'VSS_AR75': CDS_PINID='VSS_AR75';
NODE_NAME     U25 AT3
 '@T6G_MB_LIB.T6G(SCH_1):PAGE31_I23@PURE_QUANTA.GENOA_SP5(CHIPS)':
 'VSS_AT3': CDS_PINID='VSS_AT3';
NODE_NAME     U25 AT4
 '@T6G_MB_LIB.T6G(SCH_1):PAGE31_I23@PURE_QUANTA.GENOA_SP5(CHIPS)':
 'VSS_AT4': CDS_PINID='VSS_AT4';
NODE_NAME     U25 AT5
 '@T6G_MB_LIB.T6G(SCH_1):PAGE31_I23@PURE_QUANTA.GENOA_SP5(CHIPS)':
 'VSS_AT5': CDS_PINID='VSS_AT5';
NODE_NAME     U25 AT6
 '@T6G_MB_LIB.T6G(SCH_1):PAGE31_I23@PURE_QUANTA.GENOA_SP5(CHIPS)':
 'VSS_AT6': CDS_PINID='VSS_AT6';
NODE_NAME     U25 AT8
 '@T6G_MB_LIB.T6G(SCH_1):PAGE31_I23@PURE_QUANTA.GENOA_SP5(CHIPS)':
 'VSS_AT8': CDS_PINID='VSS_AT8';
NODE_NAME     U25 AT9
 '@T6G_MB_LIB.T6G(SCH_1):PAGE31_I23@PURE_QUANTA.GENOA_SP5(CHIPS)':
 'VSS_AT9': CDS_PINID='VSS_AT9';
NODE_NAME     U25 AT10
 '@T6G_MB_LIB.T6G(SCH_1):PAGE31_I23@PURE_QUANTA.GENOA_SP5(CHIPS)':
 'VSS_AT10': CDS_PINID='VSS_AT10';
NODE_NAME     U25 AT12
 '@T6G_MB_LIB.T6G(SCH_1):PAGE31_I23@PURE_QUANTA.GENOA_SP5(CHIPS)':
 'VSS_AT12': CDS_PINID='VSS_AT12';
NODE_NAME     U25 AT13
 '@T6G_MB_LIB.T6G(SCH_1):PAGE31_I23@PURE_QUANTA.GENOA_SP5(CHIPS)':
 'VSS_AT13': CDS_PINID='VSS_AT13';
NODE_NAME     U25 AT15
 '@T6G_MB_LIB.T6G(SCH_1):PAGE31_I23@PURE_QUANTA.GENOA_SP5(CHIPS)':
 'VSS_AT15': CDS_PINID='VSS_AT15';
NODE_NAME     U25 AT16
 '@T6G_MB_LIB.T6G(SCH_1):PAGE31_I23@PURE_QUANTA.GENOA_SP5(CHIPS)':
 'VSS_AT16': CDS_PINID='VSS_AT16';
NODE_NAME     U25 AT17
 '@T6G_MB_LIB.T6G(SCH_1):PAGE31_I23@PURE_QUANTA.GENOA_SP5(CHIPS)':
 'VSS_AT17': CDS_PINID='VSS_AT17';
NODE_NAME     U25 AT19
 '@T6G_MB_LIB.T6G(SCH_1):PAGE31_I23@PURE_QUANTA.GENOA_SP5(CHIPS)':
 'VSS_AT19': CDS_PINID='VSS_AT19';
NODE_NAME     U25 AT20
 '@T6G_MB_LIB.T6G(SCH_1):PAGE31_I23@PURE_QUANTA.GENOA_SP5(CHIPS)':
 'VSS_AT20': CDS_PINID='VSS_AT20';
NODE_NAME     U25 AT23
 '@T6G_MB_LIB.T6G(SCH_1):PAGE31_I23@PURE_QUANTA.GENOA_SP5(CHIPS)':
 'VSS_AT23': CDS_PINID='VSS_AT23';
NODE_NAME     U25 AT25
 '@T6G_MB_LIB.T6G(SCH_1):PAGE31_I23@PURE_QUANTA.GENOA_SP5(CHIPS)':
 'VSS_AT25': CDS_PINID='VSS_AT25';
NODE_NAME     U25 AT27
 '@T6G_MB_LIB.T6G(SCH_1):PAGE31_I23@PURE_QUANTA.GENOA_SP5(CHIPS)':
 'VSS_AT27': CDS_PINID='VSS_AT27';
NODE_NAME     U25 AT29
 '@T6G_MB_LIB.T6G(SCH_1):PAGE31_I23@PURE_QUANTA.GENOA_SP5(CHIPS)':
 'VSS_AT29': CDS_PINID='VSS_AT29';
NODE_NAME     U25 AT31
 '@T6G_MB_LIB.T6G(SCH_1):PAGE31_I23@PURE_QUANTA.GENOA_SP5(CHIPS)':
 'VSS_AT31': CDS_PINID='VSS_AT31';
NODE_NAME     U25 AT33
 '@T6G_MB_LIB.T6G(SCH_1):PAGE31_I23@PURE_QUANTA.GENOA_SP5(CHIPS)':
 'VSS_AT33': CDS_PINID='VSS_AT33';
NODE_NAME     U25 AT35
 '@T6G_MB_LIB.T6G(SCH_1):PAGE31_I23@PURE_QUANTA.GENOA_SP5(CHIPS)':
 'VSS_AT35': CDS_PINID='VSS_AT35';
NODE_NAME     U25 AT37
 '@T6G_MB_LIB.T6G(SCH_1):PAGE31_I23@PURE_QUANTA.GENOA_SP5(CHIPS)':
 'VSS_AT37': CDS_PINID='VSS_AT37';
NODE_NAME     U25 AT40
 '@T6G_MB_LIB.T6G(SCH_1):PAGE31_I23@PURE_QUANTA.GENOA_SP5(CHIPS)':
 'VSS_AT40': CDS_PINID='VSS_AT40';
NODE_NAME     U25 AT42
 '@T6G_MB_LIB.T6G(SCH_1):PAGE31_I23@PURE_QUANTA.GENOA_SP5(CHIPS)':
 'VSS_AT42': CDS_PINID='VSS_AT42';
NODE_NAME     U25 AT44
 '@T6G_MB_LIB.T6G(SCH_1):PAGE31_I23@PURE_QUANTA.GENOA_SP5(CHIPS)':
 'VSS_AT44': CDS_PINID='VSS_AT44';
NODE_NAME     U25 AT46
 '@T6G_MB_LIB.T6G(SCH_1):PAGE31_I23@PURE_QUANTA.GENOA_SP5(CHIPS)':
 'VSS_AT46': CDS_PINID='VSS_AT46';
NODE_NAME     U25 AT48
 '@T6G_MB_LIB.T6G(SCH_1):PAGE31_I23@PURE_QUANTA.GENOA_SP5(CHIPS)':
 'VSS_AT48': CDS_PINID='VSS_AT48';
NODE_NAME     U25 AT50
 '@T6G_MB_LIB.T6G(SCH_1):PAGE31_I23@PURE_QUANTA.GENOA_SP5(CHIPS)':
 'VSS_AT50': CDS_PINID='VSS_AT50';
NODE_NAME     U25 AT52
 '@T6G_MB_LIB.T6G(SCH_1):PAGE31_I23@PURE_QUANTA.GENOA_SP5(CHIPS)':
 'VSS_AT52': CDS_PINID='VSS_AT52';
NODE_NAME     U25 AT54
 '@T6G_MB_LIB.T6G(SCH_1):PAGE31_I23@PURE_QUANTA.GENOA_SP5(CHIPS)':
 'VSS_AT54': CDS_PINID='VSS_AT54';
NODE_NAME     U25 AT56
 '@T6G_MB_LIB.T6G(SCH_1):PAGE31_I23@PURE_QUANTA.GENOA_SP5(CHIPS)':
 'VSS_AT56': CDS_PINID='VSS_AT56';
NODE_NAME     U25 AT57
 '@T6G_MB_LIB.T6G(SCH_1):PAGE31_I23@PURE_QUANTA.GENOA_SP5(CHIPS)':
 'VSS_AT57': CDS_PINID='VSS_AT57';
NODE_NAME     U25 AT59
 '@T6G_MB_LIB.T6G(SCH_1):PAGE31_I23@PURE_QUANTA.GENOA_SP5(CHIPS)':
 'VSS_AT59': CDS_PINID='VSS_AT59';
NODE_NAME     U25 AT60
 '@T6G_MB_LIB.T6G(SCH_1):PAGE31_I23@PURE_QUANTA.GENOA_SP5(CHIPS)':
 'VSS_AT60': CDS_PINID='VSS_AT60';
NODE_NAME     U25 AT61
 '@T6G_MB_LIB.T6G(SCH_1):PAGE31_I23@PURE_QUANTA.GENOA_SP5(CHIPS)':
 'VSS_AT61': CDS_PINID='VSS_AT61';
NODE_NAME     U25 AT63
 '@T6G_MB_LIB.T6G(SCH_1):PAGE31_I23@PURE_QUANTA.GENOA_SP5(CHIPS)':
 'VSS_AT63': CDS_PINID='VSS_AT63';
NODE_NAME     U25 AT64
 '@T6G_MB_LIB.T6G(SCH_1):PAGE31_I23@PURE_QUANTA.GENOA_SP5(CHIPS)':
 'VSS_AT64': CDS_PINID='VSS_AT64';
NODE_NAME     U25 AT66
 '@T6G_MB_LIB.T6G(SCH_1):PAGE31_I23@PURE_QUANTA.GENOA_SP5(CHIPS)':
 'VSS_AT66': CDS_PINID='VSS_AT66';
NODE_NAME     U25 AT67
 '@T6G_MB_LIB.T6G(SCH_1):PAGE31_I23@PURE_QUANTA.GENOA_SP5(CHIPS)':
 'VSS_AT67': CDS_PINID='VSS_AT67';
NODE_NAME     U25 AT68
 '@T6G_MB_LIB.T6G(SCH_1):PAGE31_I23@PURE_QUANTA.GENOA_SP5(CHIPS)':
 'VSS_AT68': CDS_PINID='VSS_AT68';
NODE_NAME     U25 AT70
 '@T6G_MB_LIB.T6G(SCH_1):PAGE31_I23@PURE_QUANTA.GENOA_SP5(CHIPS)':
 'VSS_AT70': CDS_PINID='VSS_AT70';
NODE_NAME     U25 AT71
 '@T6G_MB_LIB.T6G(SCH_1):PAGE31_I23@PURE_QUANTA.GENOA_SP5(CHIPS)':
 'VSS_AT71': CDS_PINID='VSS_AT71';
NODE_NAME     U25 AT72
 '@T6G_MB_LIB.T6G(SCH_1):PAGE31_I23@PURE_QUANTA.GENOA_SP5(CHIPS)':
 'VSS_AT72': CDS_PINID='VSS_AT72';
NODE_NAME     U25 AT73
 '@T6G_MB_LIB.T6G(SCH_1):PAGE31_I23@PURE_QUANTA.GENOA_SP5(CHIPS)':
 'VSS_AT73': CDS_PINID='VSS_AT73';
NODE_NAME     U25 AU1
 '@T6G_MB_LIB.T6G(SCH_1):PAGE31_I23@PURE_QUANTA.GENOA_SP5(CHIPS)':
 'VSS_AU1': CDS_PINID='VSS_AU1';
NODE_NAME     U25 AU3
 '@T6G_MB_LIB.T6G(SCH_1):PAGE31_I23@PURE_QUANTA.GENOA_SP5(CHIPS)':
 'VSS_AU3': CDS_PINID='VSS_AU3';
NODE_NAME     U25 AU4
 '@T6G_MB_LIB.T6G(SCH_1):PAGE31_I23@PURE_QUANTA.GENOA_SP5(CHIPS)':
 'VSS_AU4': CDS_PINID='VSS_AU4';
NODE_NAME     U25 AU6
 '@T6G_MB_LIB.T6G(SCH_1):PAGE31_I23@PURE_QUANTA.GENOA_SP5(CHIPS)':
 'VSS_AU6': CDS_PINID='VSS_AU6';
NODE_NAME     U25 AU8
 '@T6G_MB_LIB.T6G(SCH_1):PAGE31_I23@PURE_QUANTA.GENOA_SP5(CHIPS)':
 'VSS_AU8': CDS_PINID='VSS_AU8';
NODE_NAME     U25 AU11
 '@T6G_MB_LIB.T6G(SCH_1):PAGE31_I23@PURE_QUANTA.GENOA_SP5(CHIPS)':
 'VSS_AU11': CDS_PINID='VSS_AU11';
NODE_NAME     U25 AU13
 '@T6G_MB_LIB.T6G(SCH_1):PAGE31_I23@PURE_QUANTA.GENOA_SP5(CHIPS)':
 'VSS_AU13': CDS_PINID='VSS_AU13';
NODE_NAME     U25 AU15
 '@T6G_MB_LIB.T6G(SCH_1):PAGE31_I23@PURE_QUANTA.GENOA_SP5(CHIPS)':
 'VSS_AU15': CDS_PINID='VSS_AU15';
NODE_NAME     U25 AU18
 '@T6G_MB_LIB.T6G(SCH_1):PAGE31_I23@PURE_QUANTA.GENOA_SP5(CHIPS)':
 'VSS_AU18': CDS_PINID='VSS_AU18';
NODE_NAME     U25 AU20
 '@T6G_MB_LIB.T6G(SCH_1):PAGE31_I23@PURE_QUANTA.GENOA_SP5(CHIPS)':
 'VSS_AU20': CDS_PINID='VSS_AU20';
NODE_NAME     U25 AU22
 '@T6G_MB_LIB.T6G(SCH_1):PAGE31_I23@PURE_QUANTA.GENOA_SP5(CHIPS)':
 'VSS_AU22': CDS_PINID='VSS_AU22';
NODE_NAME     U25 AU24
 '@T6G_MB_LIB.T6G(SCH_1):PAGE31_I23@PURE_QUANTA.GENOA_SP5(CHIPS)':
 'VSS_AU24': CDS_PINID='VSS_AU24';
NODE_NAME     U25 AU26
 '@T6G_MB_LIB.T6G(SCH_1):PAGE31_I23@PURE_QUANTA.GENOA_SP5(CHIPS)':
 'VSS_AU26': CDS_PINID='VSS_AU26';
NODE_NAME     U25 AU28
 '@T6G_MB_LIB.T6G(SCH_1):PAGE31_I23@PURE_QUANTA.GENOA_SP5(CHIPS)':
 'VSS_AU28': CDS_PINID='VSS_AU28';
NODE_NAME     U25 AU30
 '@T6G_MB_LIB.T6G(SCH_1):PAGE31_I23@PURE_QUANTA.GENOA_SP5(CHIPS)':
 'VSS_AU30': CDS_PINID='VSS_AU30';
NODE_NAME     U25 AU32
 '@T6G_MB_LIB.T6G(SCH_1):PAGE31_I23@PURE_QUANTA.GENOA_SP5(CHIPS)':
 'VSS_AU32': CDS_PINID='VSS_AU32';
NODE_NAME     U25 AU34
 '@T6G_MB_LIB.T6G(SCH_1):PAGE31_I23@PURE_QUANTA.GENOA_SP5(CHIPS)':
 'VSS_AU34': CDS_PINID='VSS_AU34';
NODE_NAME     U25 AU36
 '@T6G_MB_LIB.T6G(SCH_1):PAGE31_I23@PURE_QUANTA.GENOA_SP5(CHIPS)':
 'VSS_AU36': CDS_PINID='VSS_AU36';
NODE_NAME     U25 AU41
 '@T6G_MB_LIB.T6G(SCH_1):PAGE31_I23@PURE_QUANTA.GENOA_SP5(CHIPS)':
 'VSS_AU41': CDS_PINID='VSS_AU41';
NODE_NAME     U25 AU43
 '@T6G_MB_LIB.T6G(SCH_1):PAGE31_I23@PURE_QUANTA.GENOA_SP5(CHIPS)':
 'VSS_AU43': CDS_PINID='VSS_AU43';
NODE_NAME     U25 AU45
 '@T6G_MB_LIB.T6G(SCH_1):PAGE31_I23@PURE_QUANTA.GENOA_SP5(CHIPS)':
 'VSS_AU45': CDS_PINID='VSS_AU45';
NODE_NAME     U25 AU47
 '@T6G_MB_LIB.T6G(SCH_1):PAGE31_I23@PURE_QUANTA.GENOA_SP5(CHIPS)':
 'VSS_AU47': CDS_PINID='VSS_AU47';
NODE_NAME     U25 AU49
 '@T6G_MB_LIB.T6G(SCH_1):PAGE31_I23@PURE_QUANTA.GENOA_SP5(CHIPS)':
 'VSS_AU49': CDS_PINID='VSS_AU49';
NODE_NAME     U25 AU51
 '@T6G_MB_LIB.T6G(SCH_1):PAGE31_I23@PURE_QUANTA.GENOA_SP5(CHIPS)':
 'VSS_AU51': CDS_PINID='VSS_AU51';
NODE_NAME     U25 AU53
 '@T6G_MB_LIB.T6G(SCH_1):PAGE31_I23@PURE_QUANTA.GENOA_SP5(CHIPS)':
 'VSS_AU53': CDS_PINID='VSS_AU53';
NODE_NAME     U25 AU56
 '@T6G_MB_LIB.T6G(SCH_1):PAGE31_I23@PURE_QUANTA.GENOA_SP5(CHIPS)':
 'VSS_AU56': CDS_PINID='VSS_AU56';
NODE_NAME     U25 AU58
 '@T6G_MB_LIB.T6G(SCH_1):PAGE31_I23@PURE_QUANTA.GENOA_SP5(CHIPS)':
 'VSS_AU58': CDS_PINID='VSS_AU58';
NODE_NAME     U25 AU61
 '@T6G_MB_LIB.T6G(SCH_1):PAGE31_I23@PURE_QUANTA.GENOA_SP5(CHIPS)':
 'VSS_AU61': CDS_PINID='VSS_AU61';
NODE_NAME     U25 AU63
 '@T6G_MB_LIB.T6G(SCH_1):PAGE31_I23@PURE_QUANTA.GENOA_SP5(CHIPS)':
 'VSS_AU63': CDS_PINID='VSS_AU63';
NODE_NAME     U25 AU65
 '@T6G_MB_LIB.T6G(SCH_1):PAGE31_I23@PURE_QUANTA.GENOA_SP5(CHIPS)':
 'VSS_AU65': CDS_PINID='VSS_AU65';
NODE_NAME     U25 AU68
 '@T6G_MB_LIB.T6G(SCH_1):PAGE31_I23@PURE_QUANTA.GENOA_SP5(CHIPS)':
 'VSS_AU68': CDS_PINID='VSS_AU68';
NODE_NAME     U25 AU70
 '@T6G_MB_LIB.T6G(SCH_1):PAGE31_I23@PURE_QUANTA.GENOA_SP5(CHIPS)':
 'VSS_AU70': CDS_PINID='VSS_AU70';
NODE_NAME     U25 AU72
 '@T6G_MB_LIB.T6G(SCH_1):PAGE31_I23@PURE_QUANTA.GENOA_SP5(CHIPS)':
 'VSS_AU72': CDS_PINID='VSS_AU72';
NODE_NAME     U25 AU73
 '@T6G_MB_LIB.T6G(SCH_1):PAGE31_I23@PURE_QUANTA.GENOA_SP5(CHIPS)':
 'VSS_AU73': CDS_PINID='VSS_AU73';
NODE_NAME     U25 AU75
 '@T6G_MB_LIB.T6G(SCH_1):PAGE31_I23@PURE_QUANTA.GENOA_SP5(CHIPS)':
 'VSS_AU75': CDS_PINID='VSS_AU75';
NODE_NAME     U25 AV3
 '@T6G_MB_LIB.T6G(SCH_1):PAGE31_I23@PURE_QUANTA.GENOA_SP5(CHIPS)':
 'VSS_AV3': CDS_PINID='VSS_AV3';
NODE_NAME     U25 AV8
 '@T6G_MB_LIB.T6G(SCH_1):PAGE31_I23@PURE_QUANTA.GENOA_SP5(CHIPS)':
 'VSS_AV8': CDS_PINID='VSS_AV8';
NODE_NAME     U25 AV10
 '@T6G_MB_LIB.T6G(SCH_1):PAGE31_I23@PURE_QUANTA.GENOA_SP5(CHIPS)':
 'VSS_AV10': CDS_PINID='VSS_AV10';
NODE_NAME     U25 AV15
 '@T6G_MB_LIB.T6G(SCH_1):PAGE31_I23@PURE_QUANTA.GENOA_SP5(CHIPS)':
 'VSS_AV15': CDS_PINID='VSS_AV15';
NODE_NAME     U25 AV17
 '@T6G_MB_LIB.T6G(SCH_1):PAGE31_I23@PURE_QUANTA.GENOA_SP5(CHIPS)':
 'VSS_AV17': CDS_PINID='VSS_AV17';
NODE_NAME     U25 AV23
 '@T6G_MB_LIB.T6G(SCH_1):PAGE31_I23@PURE_QUANTA.GENOA_SP5(CHIPS)':
 'VSS_AV23': CDS_PINID='VSS_AV23';
NODE_NAME     U25 AV25
 '@T6G_MB_LIB.T6G(SCH_1):PAGE31_I23@PURE_QUANTA.GENOA_SP5(CHIPS)':
 'VSS_AV25': CDS_PINID='VSS_AV25';
NODE_NAME     U25 AV27
 '@T6G_MB_LIB.T6G(SCH_1):PAGE31_I23@PURE_QUANTA.GENOA_SP5(CHIPS)':
 'VSS_AV27': CDS_PINID='VSS_AV27';
NODE_NAME     U25 AV29
 '@T6G_MB_LIB.T6G(SCH_1):PAGE31_I23@PURE_QUANTA.GENOA_SP5(CHIPS)':
 'VSS_AV29': CDS_PINID='VSS_AV29';
NODE_NAME     U25 AV31
 '@T6G_MB_LIB.T6G(SCH_1):PAGE31_I23@PURE_QUANTA.GENOA_SP5(CHIPS)':
 'VSS_AV31': CDS_PINID='VSS_AV31';
NODE_NAME     U25 AV33
 '@T6G_MB_LIB.T6G(SCH_1):PAGE31_I23@PURE_QUANTA.GENOA_SP5(CHIPS)':
 'VSS_AV33': CDS_PINID='VSS_AV33';
NODE_NAME     U25 AV35
 '@T6G_MB_LIB.T6G(SCH_1):PAGE31_I23@PURE_QUANTA.GENOA_SP5(CHIPS)':
 'VSS_AV35': CDS_PINID='VSS_AV35';
NODE_NAME     U25 AV37
 '@T6G_MB_LIB.T6G(SCH_1):PAGE31_I23@PURE_QUANTA.GENOA_SP5(CHIPS)':
 'VSS_AV37': CDS_PINID='VSS_AV37';
NODE_NAME     U25 AV40
 '@T6G_MB_LIB.T6G(SCH_1):PAGE31_I23@PURE_QUANTA.GENOA_SP5(CHIPS)':
 'VSS_AV40': CDS_PINID='VSS_AV40';
NODE_NAME     U25 AV42
 '@T6G_MB_LIB.T6G(SCH_1):PAGE31_I23@PURE_QUANTA.GENOA_SP5(CHIPS)':
 'VSS_AV42': CDS_PINID='VSS_AV42';
NODE_NAME     U25 AV44
 '@T6G_MB_LIB.T6G(SCH_1):PAGE31_I23@PURE_QUANTA.GENOA_SP5(CHIPS)':
 'VSS_AV44': CDS_PINID='VSS_AV44';
NODE_NAME     U25 AV46
 '@T6G_MB_LIB.T6G(SCH_1):PAGE31_I23@PURE_QUANTA.GENOA_SP5(CHIPS)':
 'VSS_AV46': CDS_PINID='VSS_AV46';
NODE_NAME     U25 AV48
 '@T6G_MB_LIB.T6G(SCH_1):PAGE31_I23@PURE_QUANTA.GENOA_SP5(CHIPS)':
 'VSS_AV48': CDS_PINID='VSS_AV48';
NODE_NAME     U25 AV50
 '@T6G_MB_LIB.T6G(SCH_1):PAGE31_I23@PURE_QUANTA.GENOA_SP5(CHIPS)':
 'VSS_AV50': CDS_PINID='VSS_AV50';
NODE_NAME     U25 AV52
 '@T6G_MB_LIB.T6G(SCH_1):PAGE31_I23@PURE_QUANTA.GENOA_SP5(CHIPS)':
 'VSS_AV52': CDS_PINID='VSS_AV52';
NODE_NAME     U25 AV54
 '@T6G_MB_LIB.T6G(SCH_1):PAGE31_I23@PURE_QUANTA.GENOA_SP5(CHIPS)':
 'VSS_AV54': CDS_PINID='VSS_AV54';
NODE_NAME     U25 AV59
 '@T6G_MB_LIB.T6G(SCH_1):PAGE31_I23@PURE_QUANTA.GENOA_SP5(CHIPS)':
 'VSS_AV59': CDS_PINID='VSS_AV59';
NODE_NAME     U25 AV61
 '@T6G_MB_LIB.T6G(SCH_1):PAGE31_I23@PURE_QUANTA.GENOA_SP5(CHIPS)':
 'VSS_AV61': CDS_PINID='VSS_AV61';
NODE_NAME     U25 AV66
 '@T6G_MB_LIB.T6G(SCH_1):PAGE31_I23@PURE_QUANTA.GENOA_SP5(CHIPS)':
 'VSS_AV66': CDS_PINID='VSS_AV66';
NODE_NAME     U25 AV68
 '@T6G_MB_LIB.T6G(SCH_1):PAGE31_I23@PURE_QUANTA.GENOA_SP5(CHIPS)':
 'VSS_AV68': CDS_PINID='VSS_AV68';
NODE_NAME     U25 AV73
 '@T6G_MB_LIB.T6G(SCH_1):PAGE31_I23@PURE_QUANTA.GENOA_SP5(CHIPS)':
 'VSS_AV73': CDS_PINID='VSS_AV73';
NODE_NAME     U25 AW1
 '@T6G_MB_LIB.T6G(SCH_1):PAGE31_I23@PURE_QUANTA.GENOA_SP5(CHIPS)':
 'VSS_AW1': CDS_PINID='VSS_AW1';
NODE_NAME     U25 AW4
 '@T6G_MB_LIB.T6G(SCH_1):PAGE31_I23@PURE_QUANTA.GENOA_SP5(CHIPS)':
 'VSS_AW4': CDS_PINID='VSS_AW4';
NODE_NAME     U25 AW6
 '@T6G_MB_LIB.T6G(SCH_1):PAGE31_I23@PURE_QUANTA.GENOA_SP5(CHIPS)':
 'VSS_AW6': CDS_PINID='VSS_AW6';
NODE_NAME     U25 AW8
 '@T6G_MB_LIB.T6G(SCH_1):PAGE31_I23@PURE_QUANTA.GENOA_SP5(CHIPS)':
 'VSS_AW8': CDS_PINID='VSS_AW8';
NODE_NAME     U25 AW11
 '@T6G_MB_LIB.T6G(SCH_1):PAGE31_I23@PURE_QUANTA.GENOA_SP5(CHIPS)':
 'VSS_AW11': CDS_PINID='VSS_AW11';
NODE_NAME     U25 AW13
 '@T6G_MB_LIB.T6G(SCH_1):PAGE31_I23@PURE_QUANTA.GENOA_SP5(CHIPS)':
 'VSS_AW13': CDS_PINID='VSS_AW13';
NODE_NAME     U25 AW15
 '@T6G_MB_LIB.T6G(SCH_1):PAGE31_I23@PURE_QUANTA.GENOA_SP5(CHIPS)':
 'VSS_AW15': CDS_PINID='VSS_AW15';
NODE_NAME     U25 AW18
 '@T6G_MB_LIB.T6G(SCH_1):PAGE31_I23@PURE_QUANTA.GENOA_SP5(CHIPS)':
 'VSS_AW18': CDS_PINID='VSS_AW18';
NODE_NAME     U25 AW20
 '@T6G_MB_LIB.T6G(SCH_1):PAGE31_I23@PURE_QUANTA.GENOA_SP5(CHIPS)':
 'VSS_AW20': CDS_PINID='VSS_AW20';
NODE_NAME     U25 AW22
 '@T6G_MB_LIB.T6G(SCH_1):PAGE31_I23@PURE_QUANTA.GENOA_SP5(CHIPS)':
 'VSS_AW22': CDS_PINID='VSS_AW22';
NODE_NAME     U25 AW24
 '@T6G_MB_LIB.T6G(SCH_1):PAGE31_I23@PURE_QUANTA.GENOA_SP5(CHIPS)':
 'VSS_AW24': CDS_PINID='VSS_AW24';
NODE_NAME     U25 AW26
 '@T6G_MB_LIB.T6G(SCH_1):PAGE31_I23@PURE_QUANTA.GENOA_SP5(CHIPS)':
 'VSS_AW26': CDS_PINID='VSS_AW26';
NODE_NAME     U25 AW28
 '@T6G_MB_LIB.T6G(SCH_1):PAGE31_I23@PURE_QUANTA.GENOA_SP5(CHIPS)':
 'VSS_AW28': CDS_PINID='VSS_AW28';
NODE_NAME     U25 AW49
 '@T6G_MB_LIB.T6G(SCH_1):PAGE31_I23@PURE_QUANTA.GENOA_SP5(CHIPS)':
 'VSS_AW49': CDS_PINID='VSS_AW49';
NODE_NAME     U25 AW51
 '@T6G_MB_LIB.T6G(SCH_1):PAGE31_I23@PURE_QUANTA.GENOA_SP5(CHIPS)':
 'VSS_AW51': CDS_PINID='VSS_AW51';
NODE_NAME     U25 AW53
 '@T6G_MB_LIB.T6G(SCH_1):PAGE31_I23@PURE_QUANTA.GENOA_SP5(CHIPS)':
 'VSS_AW53': CDS_PINID='VSS_AW53';
NODE_NAME     U25 AW56
 '@T6G_MB_LIB.T6G(SCH_1):PAGE31_I23@PURE_QUANTA.GENOA_SP5(CHIPS)':
 'VSS_AW56': CDS_PINID='VSS_AW56';
NODE_NAME     U25 AW58
 '@T6G_MB_LIB.T6G(SCH_1):PAGE31_I23@PURE_QUANTA.GENOA_SP5(CHIPS)':
 'VSS_AW58': CDS_PINID='VSS_AW58';
NODE_NAME     U25 AW61
 '@T6G_MB_LIB.T6G(SCH_1):PAGE31_I23@PURE_QUANTA.GENOA_SP5(CHIPS)':
 'VSS_AW61': CDS_PINID='VSS_AW61';
NODE_NAME     U25 AW63
 '@T6G_MB_LIB.T6G(SCH_1):PAGE31_I24@PURE_QUANTA.GENOA_SP5(CHIPS)':
 'VSS_AW63': CDS_PINID='VSS_AW63';
NODE_NAME     U25 AW65
 '@T6G_MB_LIB.T6G(SCH_1):PAGE31_I24@PURE_QUANTA.GENOA_SP5(CHIPS)':
 'VSS_AW65': CDS_PINID='VSS_AW65';
NODE_NAME     U25 AW68
 '@T6G_MB_LIB.T6G(SCH_1):PAGE31_I24@PURE_QUANTA.GENOA_SP5(CHIPS)':
 'VSS_AW68': CDS_PINID='VSS_AW68';
NODE_NAME     U25 AW70
 '@T6G_MB_LIB.T6G(SCH_1):PAGE31_I24@PURE_QUANTA.GENOA_SP5(CHIPS)':
 'VSS_AW70': CDS_PINID='VSS_AW70';
NODE_NAME     U25 AW72
 '@T6G_MB_LIB.T6G(SCH_1):PAGE31_I24@PURE_QUANTA.GENOA_SP5(CHIPS)':
 'VSS_AW72': CDS_PINID='VSS_AW72';
NODE_NAME     U25 AW75
 '@T6G_MB_LIB.T6G(SCH_1):PAGE31_I24@PURE_QUANTA.GENOA_SP5(CHIPS)':
 'VSS_AW75': CDS_PINID='VSS_AW75';
NODE_NAME     U25 AY3
 '@T6G_MB_LIB.T6G(SCH_1):PAGE31_I24@PURE_QUANTA.GENOA_SP5(CHIPS)':
 'VSS_AY3': CDS_PINID='VSS_AY3';
NODE_NAME     U25 AY5
 '@T6G_MB_LIB.T6G(SCH_1):PAGE31_I24@PURE_QUANTA.GENOA_SP5(CHIPS)':
 'VSS_AY5': CDS_PINID='VSS_AY5';
NODE_NAME     U25 AY8
 '@T6G_MB_LIB.T6G(SCH_1):PAGE31_I24@PURE_QUANTA.GENOA_SP5(CHIPS)':
 'VSS_AY8': CDS_PINID='VSS_AY8';
NODE_NAME     U25 AY10
 '@T6G_MB_LIB.T6G(SCH_1):PAGE31_I24@PURE_QUANTA.GENOA_SP5(CHIPS)':
 'VSS_AY10': CDS_PINID='VSS_AY10';
NODE_NAME     U25 AY12
 '@T6G_MB_LIB.T6G(SCH_1):PAGE31_I24@PURE_QUANTA.GENOA_SP5(CHIPS)':
 'VSS_AY12': CDS_PINID='VSS_AY12';
NODE_NAME     U25 AY15
 '@T6G_MB_LIB.T6G(SCH_1):PAGE31_I24@PURE_QUANTA.GENOA_SP5(CHIPS)':
 'VSS_AY15': CDS_PINID='VSS_AY15';
NODE_NAME     U25 AY17
 '@T6G_MB_LIB.T6G(SCH_1):PAGE31_I24@PURE_QUANTA.GENOA_SP5(CHIPS)':
 'VSS_AY17': CDS_PINID='VSS_AY17';
NODE_NAME     U25 AY19
 '@T6G_MB_LIB.T6G(SCH_1):PAGE31_I24@PURE_QUANTA.GENOA_SP5(CHIPS)':
 'VSS_AY19': CDS_PINID='VSS_AY19';
NODE_NAME     U25 AY23
 '@T6G_MB_LIB.T6G(SCH_1):PAGE31_I24@PURE_QUANTA.GENOA_SP5(CHIPS)':
 'VSS_AY23': CDS_PINID='VSS_AY23';
NODE_NAME     U25 AY25
 '@T6G_MB_LIB.T6G(SCH_1):PAGE31_I24@PURE_QUANTA.GENOA_SP5(CHIPS)':
 'VSS_AY25': CDS_PINID='VSS_AY25';
NODE_NAME     U25 AY27
 '@T6G_MB_LIB.T6G(SCH_1):PAGE31_I24@PURE_QUANTA.GENOA_SP5(CHIPS)':
 'VSS_AY27': CDS_PINID='VSS_AY27';
NODE_NAME     U25 AY48
 '@T6G_MB_LIB.T6G(SCH_1):PAGE31_I24@PURE_QUANTA.GENOA_SP5(CHIPS)':
 'VSS_AY48': CDS_PINID='VSS_AY48';
NODE_NAME     U25 AY50
 '@T6G_MB_LIB.T6G(SCH_1):PAGE31_I24@PURE_QUANTA.GENOA_SP5(CHIPS)':
 'VSS_AY50': CDS_PINID='VSS_AY50';
NODE_NAME     U25 AY52
 '@T6G_MB_LIB.T6G(SCH_1):PAGE31_I24@PURE_QUANTA.GENOA_SP5(CHIPS)':
 'VSS_AY52': CDS_PINID='VSS_AY52';
NODE_NAME     U25 AY54
 '@T6G_MB_LIB.T6G(SCH_1):PAGE31_I24@PURE_QUANTA.GENOA_SP5(CHIPS)':
 'VSS_AY54': CDS_PINID='VSS_AY54';
NODE_NAME     U25 AY57
 '@T6G_MB_LIB.T6G(SCH_1):PAGE31_I24@PURE_QUANTA.GENOA_SP5(CHIPS)':
 'VSS_AY57': CDS_PINID='VSS_AY57';
NODE_NAME     U25 AY59
 '@T6G_MB_LIB.T6G(SCH_1):PAGE31_I24@PURE_QUANTA.GENOA_SP5(CHIPS)':
 'VSS_AY59': CDS_PINID='VSS_AY59';
NODE_NAME     U25 AY61
 '@T6G_MB_LIB.T6G(SCH_1):PAGE31_I24@PURE_QUANTA.GENOA_SP5(CHIPS)':
 'VSS_AY61': CDS_PINID='VSS_AY61';
NODE_NAME     U25 AY64
 '@T6G_MB_LIB.T6G(SCH_1):PAGE31_I24@PURE_QUANTA.GENOA_SP5(CHIPS)':
 'VSS_AY64': CDS_PINID='VSS_AY64';
NODE_NAME     U25 AY66
 '@T6G_MB_LIB.T6G(SCH_1):PAGE31_I24@PURE_QUANTA.GENOA_SP5(CHIPS)':
 'VSS_AY66': CDS_PINID='VSS_AY66';
NODE_NAME     U25 AY68
 '@T6G_MB_LIB.T6G(SCH_1):PAGE31_I24@PURE_QUANTA.GENOA_SP5(CHIPS)':
 'VSS_AY68': CDS_PINID='VSS_AY68';
NODE_NAME     U25 AY71
 '@T6G_MB_LIB.T6G(SCH_1):PAGE31_I24@PURE_QUANTA.GENOA_SP5(CHIPS)':
 'VSS_AY71': CDS_PINID='VSS_AY71';
NODE_NAME     U25 AY73
 '@T6G_MB_LIB.T6G(SCH_1):PAGE31_I24@PURE_QUANTA.GENOA_SP5(CHIPS)':
 'VSS_AY73': CDS_PINID='VSS_AY73';
NODE_NAME     U25 BA1
 '@T6G_MB_LIB.T6G(SCH_1):PAGE31_I24@PURE_QUANTA.GENOA_SP5(CHIPS)':
 'VSS_BA1': CDS_PINID='VSS_BA1';
NODE_NAME     U25 BA6
 '@T6G_MB_LIB.T6G(SCH_1):PAGE31_I24@PURE_QUANTA.GENOA_SP5(CHIPS)':
 'VSS_BA6': CDS_PINID='VSS_BA6';
NODE_NAME     U25 BA8
 '@T6G_MB_LIB.T6G(SCH_1):PAGE31_I24@PURE_QUANTA.GENOA_SP5(CHIPS)':
 'VSS_BA8': CDS_PINID='VSS_BA8';
NODE_NAME     U25 BA13
 '@T6G_MB_LIB.T6G(SCH_1):PAGE31_I24@PURE_QUANTA.GENOA_SP5(CHIPS)':
 'VSS_BA13': CDS_PINID='VSS_BA13';
NODE_NAME     U25 BA15
 '@T6G_MB_LIB.T6G(SCH_1):PAGE31_I24@PURE_QUANTA.GENOA_SP5(CHIPS)':
 'VSS_BA15': CDS_PINID='VSS_BA15';
NODE_NAME     U25 BA20
 '@T6G_MB_LIB.T6G(SCH_1):PAGE31_I24@PURE_QUANTA.GENOA_SP5(CHIPS)':
 'VSS_BA20': CDS_PINID='VSS_BA20';
NODE_NAME     U25 BA22
 '@T6G_MB_LIB.T6G(SCH_1):PAGE31_I24@PURE_QUANTA.GENOA_SP5(CHIPS)':
 'VSS_BA22': CDS_PINID='VSS_BA22';
NODE_NAME     U25 BA24
 '@T6G_MB_LIB.T6G(SCH_1):PAGE31_I24@PURE_QUANTA.GENOA_SP5(CHIPS)':
 'VSS_BA24': CDS_PINID='VSS_BA24';
NODE_NAME     U25 BA26
 '@T6G_MB_LIB.T6G(SCH_1):PAGE31_I24@PURE_QUANTA.GENOA_SP5(CHIPS)':
 'VSS_BA26': CDS_PINID='VSS_BA26';
NODE_NAME     U25 BA28
 '@T6G_MB_LIB.T6G(SCH_1):PAGE31_I24@PURE_QUANTA.GENOA_SP5(CHIPS)':
 'VSS_BA28': CDS_PINID='VSS_BA28';
NODE_NAME     U25 BA49
 '@T6G_MB_LIB.T6G(SCH_1):PAGE31_I24@PURE_QUANTA.GENOA_SP5(CHIPS)':
 'VSS_BA49': CDS_PINID='VSS_BA49';
NODE_NAME     U25 BA51
 '@T6G_MB_LIB.T6G(SCH_1):PAGE31_I24@PURE_QUANTA.GENOA_SP5(CHIPS)':
 'VSS_BA51': CDS_PINID='VSS_BA51';
NODE_NAME     U25 BA53
 '@T6G_MB_LIB.T6G(SCH_1):PAGE31_I24@PURE_QUANTA.GENOA_SP5(CHIPS)':
 'VSS_BA53': CDS_PINID='VSS_BA53';
NODE_NAME     U25 BA56
 '@T6G_MB_LIB.T6G(SCH_1):PAGE31_I24@PURE_QUANTA.GENOA_SP5(CHIPS)':
 'VSS_BA56': CDS_PINID='VSS_BA56';
NODE_NAME     U25 BA61
 '@T6G_MB_LIB.T6G(SCH_1):PAGE31_I24@PURE_QUANTA.GENOA_SP5(CHIPS)':
 'VSS_BA61': CDS_PINID='VSS_BA61';
NODE_NAME     U25 BA63
 '@T6G_MB_LIB.T6G(SCH_1):PAGE31_I24@PURE_QUANTA.GENOA_SP5(CHIPS)':
 'VSS_BA63': CDS_PINID='VSS_BA63';
NODE_NAME     U25 BA68
 '@T6G_MB_LIB.T6G(SCH_1):PAGE31_I24@PURE_QUANTA.GENOA_SP5(CHIPS)':
 'VSS_BA68': CDS_PINID='VSS_BA68';
NODE_NAME     U25 BA70
 '@T6G_MB_LIB.T6G(SCH_1):PAGE31_I24@PURE_QUANTA.GENOA_SP5(CHIPS)':
 'VSS_BA70': CDS_PINID='VSS_BA70';
NODE_NAME     U25 BA75
 '@T6G_MB_LIB.T6G(SCH_1):PAGE31_I24@PURE_QUANTA.GENOA_SP5(CHIPS)':
 'VSS_BA75': CDS_PINID='VSS_BA75';
NODE_NAME     U25 BB3
 '@T6G_MB_LIB.T6G(SCH_1):PAGE31_I24@PURE_QUANTA.GENOA_SP5(CHIPS)':
 'VSS_BB3': CDS_PINID='VSS_BB3';
NODE_NAME     U25 BB5
 '@T6G_MB_LIB.T6G(SCH_1):PAGE31_I24@PURE_QUANTA.GENOA_SP5(CHIPS)':
 'VSS_BB5': CDS_PINID='VSS_BB5';
NODE_NAME     U25 BB8
 '@T6G_MB_LIB.T6G(SCH_1):PAGE31_I24@PURE_QUANTA.GENOA_SP5(CHIPS)':
 'VSS_BB8': CDS_PINID='VSS_BB8';
NODE_NAME     U25 BB10
 '@T6G_MB_LIB.T6G(SCH_1):PAGE31_I24@PURE_QUANTA.GENOA_SP5(CHIPS)':
 'VSS_BB10': CDS_PINID='VSS_BB10';
NODE_NAME     U25 BB12
 '@T6G_MB_LIB.T6G(SCH_1):PAGE31_I24@PURE_QUANTA.GENOA_SP5(CHIPS)':
 'VSS_BB12': CDS_PINID='VSS_BB12';
NODE_NAME     U25 BB15
 '@T6G_MB_LIB.T6G(SCH_1):PAGE31_I24@PURE_QUANTA.GENOA_SP5(CHIPS)':
 'VSS_BB15': CDS_PINID='VSS_BB15';
NODE_NAME     U25 BB17
 '@T6G_MB_LIB.T6G(SCH_1):PAGE31_I24@PURE_QUANTA.GENOA_SP5(CHIPS)':
 'VSS_BB17': CDS_PINID='VSS_BB17';
NODE_NAME     U25 BB19
 '@T6G_MB_LIB.T6G(SCH_1):PAGE31_I24@PURE_QUANTA.GENOA_SP5(CHIPS)':
 'VSS_BB19': CDS_PINID='VSS_BB19';
NODE_NAME     U25 BB23
 '@T6G_MB_LIB.T6G(SCH_1):PAGE31_I24@PURE_QUANTA.GENOA_SP5(CHIPS)':
 'VSS_BB23': CDS_PINID='VSS_BB23';
NODE_NAME     U25 BB25
 '@T6G_MB_LIB.T6G(SCH_1):PAGE31_I24@PURE_QUANTA.GENOA_SP5(CHIPS)':
 'VSS_BB25': CDS_PINID='VSS_BB25';
NODE_NAME     U25 BB27
 '@T6G_MB_LIB.T6G(SCH_1):PAGE31_I24@PURE_QUANTA.GENOA_SP5(CHIPS)':
 'VSS_BB27': CDS_PINID='VSS_BB27';
NODE_NAME     U25 BB48
 '@T6G_MB_LIB.T6G(SCH_1):PAGE31_I24@PURE_QUANTA.GENOA_SP5(CHIPS)':
 'VSS_BB48': CDS_PINID='VSS_BB48';
NODE_NAME     U25 BB50
 '@T6G_MB_LIB.T6G(SCH_1):PAGE31_I24@PURE_QUANTA.GENOA_SP5(CHIPS)':
 'VSS_BB50': CDS_PINID='VSS_BB50';
NODE_NAME     U25 BB52
 '@T6G_MB_LIB.T6G(SCH_1):PAGE31_I24@PURE_QUANTA.GENOA_SP5(CHIPS)':
 'VSS_BB52': CDS_PINID='VSS_BB52';
NODE_NAME     U25 BB54
 '@T6G_MB_LIB.T6G(SCH_1):PAGE31_I24@PURE_QUANTA.GENOA_SP5(CHIPS)':
 'VSS_BB54': CDS_PINID='VSS_BB54';
NODE_NAME     U25 BB57
 '@T6G_MB_LIB.T6G(SCH_1):PAGE31_I24@PURE_QUANTA.GENOA_SP5(CHIPS)':
 'VSS_BB57': CDS_PINID='VSS_BB57';
NODE_NAME     U25 BB59
 '@T6G_MB_LIB.T6G(SCH_1):PAGE31_I24@PURE_QUANTA.GENOA_SP5(CHIPS)':
 'VSS_BB59': CDS_PINID='VSS_BB59';
NODE_NAME     U25 BB61
 '@T6G_MB_LIB.T6G(SCH_1):PAGE31_I24@PURE_QUANTA.GENOA_SP5(CHIPS)':
 'VSS_BB61': CDS_PINID='VSS_BB61';
NODE_NAME     U25 BB64
 '@T6G_MB_LIB.T6G(SCH_1):PAGE31_I24@PURE_QUANTA.GENOA_SP5(CHIPS)':
 'VSS_BB64': CDS_PINID='VSS_BB64';
NODE_NAME     U25 BB66
 '@T6G_MB_LIB.T6G(SCH_1):PAGE31_I24@PURE_QUANTA.GENOA_SP5(CHIPS)':
 'VSS_BB66': CDS_PINID='VSS_BB66';
NODE_NAME     U25 BB68
 '@T6G_MB_LIB.T6G(SCH_1):PAGE31_I24@PURE_QUANTA.GENOA_SP5(CHIPS)':
 'VSS_BB68': CDS_PINID='VSS_BB68';
NODE_NAME     U25 BB71
 '@T6G_MB_LIB.T6G(SCH_1):PAGE31_I24@PURE_QUANTA.GENOA_SP5(CHIPS)':
 'VSS_BB71': CDS_PINID='VSS_BB71';
NODE_NAME     U25 BB73
 '@T6G_MB_LIB.T6G(SCH_1):PAGE31_I24@PURE_QUANTA.GENOA_SP5(CHIPS)':
 'VSS_BB73': CDS_PINID='VSS_BB73';
NODE_NAME     U25 BC1
 '@T6G_MB_LIB.T6G(SCH_1):PAGE31_I24@PURE_QUANTA.GENOA_SP5(CHIPS)':
 'VSS_BC1': CDS_PINID='VSS_BC1';
NODE_NAME     U25 BC4
 '@T6G_MB_LIB.T6G(SCH_1):PAGE31_I24@PURE_QUANTA.GENOA_SP5(CHIPS)':
 'VSS_BC4': CDS_PINID='VSS_BC4';
NODE_NAME     U25 BC6
 '@T6G_MB_LIB.T6G(SCH_1):PAGE31_I24@PURE_QUANTA.GENOA_SP5(CHIPS)':
 'VSS_BC6': CDS_PINID='VSS_BC6';
NODE_NAME     U25 BC8
 '@T6G_MB_LIB.T6G(SCH_1):PAGE31_I24@PURE_QUANTA.GENOA_SP5(CHIPS)':
 'VSS_BC8': CDS_PINID='VSS_BC8';
NODE_NAME     U25 BC11
 '@T6G_MB_LIB.T6G(SCH_1):PAGE31_I24@PURE_QUANTA.GENOA_SP5(CHIPS)':
 'VSS_BC11': CDS_PINID='VSS_BC11';
NODE_NAME     U25 BC13
 '@T6G_MB_LIB.T6G(SCH_1):PAGE31_I24@PURE_QUANTA.GENOA_SP5(CHIPS)':
 'VSS_BC13': CDS_PINID='VSS_BC13';
NODE_NAME     U25 BC15
 '@T6G_MB_LIB.T6G(SCH_1):PAGE31_I24@PURE_QUANTA.GENOA_SP5(CHIPS)':
 'VSS_BC15': CDS_PINID='VSS_BC15';
NODE_NAME     U25 BC18
 '@T6G_MB_LIB.T6G(SCH_1):PAGE31_I24@PURE_QUANTA.GENOA_SP5(CHIPS)':
 'VSS_BC18': CDS_PINID='VSS_BC18';
NODE_NAME     U25 BC20
 '@T6G_MB_LIB.T6G(SCH_1):PAGE31_I24@PURE_QUANTA.GENOA_SP5(CHIPS)':
 'VSS_BC20': CDS_PINID='VSS_BC20';
NODE_NAME     U25 BC22
 '@T6G_MB_LIB.T6G(SCH_1):PAGE31_I24@PURE_QUANTA.GENOA_SP5(CHIPS)':
 'VSS_BC22': CDS_PINID='VSS_BC22';
NODE_NAME     U25 BC24
 '@T6G_MB_LIB.T6G(SCH_1):PAGE31_I24@PURE_QUANTA.GENOA_SP5(CHIPS)':
 'VSS_BC24': CDS_PINID='VSS_BC24';
NODE_NAME     U25 BC26
 '@T6G_MB_LIB.T6G(SCH_1):PAGE31_I24@PURE_QUANTA.GENOA_SP5(CHIPS)':
 'VSS_BC26': CDS_PINID='VSS_BC26';
NODE_NAME     U25 BC28
 '@T6G_MB_LIB.T6G(SCH_1):PAGE31_I24@PURE_QUANTA.GENOA_SP5(CHIPS)':
 'VSS_BC28': CDS_PINID='VSS_BC28';
NODE_NAME     U25 BC49
 '@T6G_MB_LIB.T6G(SCH_1):PAGE31_I24@PURE_QUANTA.GENOA_SP5(CHIPS)':
 'VSS_BC49': CDS_PINID='VSS_BC49';
NODE_NAME     U25 BC50
 '@T6G_MB_LIB.T6G(SCH_1):PAGE31_I24@PURE_QUANTA.GENOA_SP5(CHIPS)':
 'VSS_BC50': CDS_PINID='VSS_BC50';
NODE_NAME     U25 BC51
 '@T6G_MB_LIB.T6G(SCH_1):PAGE31_I24@PURE_QUANTA.GENOA_SP5(CHIPS)':
 'VSS_BC51': CDS_PINID='VSS_BC51';
NODE_NAME     U25 BC53
 '@T6G_MB_LIB.T6G(SCH_1):PAGE31_I24@PURE_QUANTA.GENOA_SP5(CHIPS)':
 'VSS_BC53': CDS_PINID='VSS_BC53';
NODE_NAME     U25 BC56
 '@T6G_MB_LIB.T6G(SCH_1):PAGE31_I24@PURE_QUANTA.GENOA_SP5(CHIPS)':
 'VSS_BC56': CDS_PINID='VSS_BC56';
NODE_NAME     U25 BC58
 '@T6G_MB_LIB.T6G(SCH_1):PAGE31_I24@PURE_QUANTA.GENOA_SP5(CHIPS)':
 'VSS_BC58': CDS_PINID='VSS_BC58';
NODE_NAME     U25 BC61
 '@T6G_MB_LIB.T6G(SCH_1):PAGE31_I24@PURE_QUANTA.GENOA_SP5(CHIPS)':
 'VSS_BC61': CDS_PINID='VSS_BC61';
NODE_NAME     U25 BC63
 '@T6G_MB_LIB.T6G(SCH_1):PAGE31_I24@PURE_QUANTA.GENOA_SP5(CHIPS)':
 'VSS_BC63': CDS_PINID='VSS_BC63';
NODE_NAME     U25 BC65
 '@T6G_MB_LIB.T6G(SCH_1):PAGE31_I24@PURE_QUANTA.GENOA_SP5(CHIPS)':
 'VSS_BC65': CDS_PINID='VSS_BC65';
NODE_NAME     U25 BC68
 '@T6G_MB_LIB.T6G(SCH_1):PAGE31_I24@PURE_QUANTA.GENOA_SP5(CHIPS)':
 'VSS_BC68': CDS_PINID='VSS_BC68';
NODE_NAME     U25 BC70
 '@T6G_MB_LIB.T6G(SCH_1):PAGE31_I24@PURE_QUANTA.GENOA_SP5(CHIPS)':
 'VSS_BC70': CDS_PINID='VSS_BC70';
NODE_NAME     U25 BC72
 '@T6G_MB_LIB.T6G(SCH_1):PAGE31_I24@PURE_QUANTA.GENOA_SP5(CHIPS)':
 'VSS_BC72': CDS_PINID='VSS_BC72';
NODE_NAME     U25 BC75
 '@T6G_MB_LIB.T6G(SCH_1):PAGE31_I24@PURE_QUANTA.GENOA_SP5(CHIPS)':
 'VSS_BC75': CDS_PINID='VSS_BC75';
NODE_NAME     U25 BD3
 '@T6G_MB_LIB.T6G(SCH_1):PAGE31_I24@PURE_QUANTA.GENOA_SP5(CHIPS)':
 'VSS_BD3': CDS_PINID='VSS_BD3';
NODE_NAME     U25 BD8
 '@T6G_MB_LIB.T6G(SCH_1):PAGE31_I24@PURE_QUANTA.GENOA_SP5(CHIPS)':
 'VSS_BD8': CDS_PINID='VSS_BD8';
NODE_NAME     U25 BD10
 '@T6G_MB_LIB.T6G(SCH_1):PAGE31_I24@PURE_QUANTA.GENOA_SP5(CHIPS)':
 'VSS_BD10': CDS_PINID='VSS_BD10';
NODE_NAME     U25 BD15
 '@T6G_MB_LIB.T6G(SCH_1):PAGE31_I24@PURE_QUANTA.GENOA_SP5(CHIPS)':
 'VSS_BD15': CDS_PINID='VSS_BD15';
NODE_NAME     U25 BD17
 '@T6G_MB_LIB.T6G(SCH_1):PAGE31_I24@PURE_QUANTA.GENOA_SP5(CHIPS)':
 'VSS_BD17': CDS_PINID='VSS_BD17';
NODE_NAME     U25 BD23
 '@T6G_MB_LIB.T6G(SCH_1):PAGE31_I24@PURE_QUANTA.GENOA_SP5(CHIPS)':
 'VSS_BD23': CDS_PINID='VSS_BD23';
NODE_NAME     U25 BD25
 '@T6G_MB_LIB.T6G(SCH_1):PAGE31_I24@PURE_QUANTA.GENOA_SP5(CHIPS)':
 'VSS_BD25': CDS_PINID='VSS_BD25';
NODE_NAME     U25 BD27
 '@T6G_MB_LIB.T6G(SCH_1):PAGE31_I24@PURE_QUANTA.GENOA_SP5(CHIPS)':
 'VSS_BD27': CDS_PINID='VSS_BD27';
NODE_NAME     U25 BD49
 '@T6G_MB_LIB.T6G(SCH_1):PAGE31_I24@PURE_QUANTA.GENOA_SP5(CHIPS)':
 'VSS_BD49': CDS_PINID='VSS_BD49';
NODE_NAME     U25 BD51
 '@T6G_MB_LIB.T6G(SCH_1):PAGE31_I24@PURE_QUANTA.GENOA_SP5(CHIPS)':
 'VSS_BD51': CDS_PINID='VSS_BD51';
NODE_NAME     U25 BD53
 '@T6G_MB_LIB.T6G(SCH_1):PAGE31_I24@PURE_QUANTA.GENOA_SP5(CHIPS)':
 'VSS_BD53': CDS_PINID='VSS_BD53';
NODE_NAME     U25 BD57
 '@T6G_MB_LIB.T6G(SCH_1):PAGE31_I24@PURE_QUANTA.GENOA_SP5(CHIPS)':
 'VSS_BD57': CDS_PINID='VSS_BD57';
NODE_NAME     U25 BD59
 '@T6G_MB_LIB.T6G(SCH_1):PAGE31_I24@PURE_QUANTA.GENOA_SP5(CHIPS)':
 'VSS_BD59': CDS_PINID='VSS_BD59';
NODE_NAME     U25 BD61
 '@T6G_MB_LIB.T6G(SCH_1):PAGE31_I24@PURE_QUANTA.GENOA_SP5(CHIPS)':
 'VSS_BD61': CDS_PINID='VSS_BD61';
NODE_NAME     U25 BD64
 '@T6G_MB_LIB.T6G(SCH_1):PAGE31_I24@PURE_QUANTA.GENOA_SP5(CHIPS)':
 'VSS_BD64': CDS_PINID='VSS_BD64';
NODE_NAME     U25 BD66
 '@T6G_MB_LIB.T6G(SCH_1):PAGE31_I24@PURE_QUANTA.GENOA_SP5(CHIPS)':
 'VSS_BD66': CDS_PINID='VSS_BD66';
NODE_NAME     U25 BD68
 '@T6G_MB_LIB.T6G(SCH_1):PAGE31_I24@PURE_QUANTA.GENOA_SP5(CHIPS)':
 'VSS_BD68': CDS_PINID='VSS_BD68';
NODE_NAME     U25 BD71
 '@T6G_MB_LIB.T6G(SCH_1):PAGE31_I24@PURE_QUANTA.GENOA_SP5(CHIPS)':
 'VSS_BD71': CDS_PINID='VSS_BD71';
NODE_NAME     U25 BD73
 '@T6G_MB_LIB.T6G(SCH_1):PAGE31_I24@PURE_QUANTA.GENOA_SP5(CHIPS)':
 'VSS_BD73': CDS_PINID='VSS_BD73';
NODE_NAME     U25 BF3
 '@T6G_MB_LIB.T6G(SCH_1):PAGE31_I24@PURE_QUANTA.GENOA_SP5(CHIPS)':
 'VSS_BF3': CDS_PINID='VSS_BF3';
NODE_NAME     U25 BF5
 '@T6G_MB_LIB.T6G(SCH_1):PAGE31_I24@PURE_QUANTA.GENOA_SP5(CHIPS)':
 'VSS_BF5': CDS_PINID='VSS_BF5';
NODE_NAME     U25 BF8
 '@T6G_MB_LIB.T6G(SCH_1):PAGE31_I24@PURE_QUANTA.GENOA_SP5(CHIPS)':
 'VSS_BF8': CDS_PINID='VSS_BF8';
NODE_NAME     U25 BF10
 '@T6G_MB_LIB.T6G(SCH_1):PAGE31_I24@PURE_QUANTA.GENOA_SP5(CHIPS)':
 'VSS_BF10': CDS_PINID='VSS_BF10';
NODE_NAME     U25 BF12
 '@T6G_MB_LIB.T6G(SCH_1):PAGE31_I24@PURE_QUANTA.GENOA_SP5(CHIPS)':
 'VSS_BF12': CDS_PINID='VSS_BF12';
NODE_NAME     U25 BF15
 '@T6G_MB_LIB.T6G(SCH_1):PAGE31_I24@PURE_QUANTA.GENOA_SP5(CHIPS)':
 'VSS_BF15': CDS_PINID='VSS_BF15';
NODE_NAME     U25 BF17
 '@T6G_MB_LIB.T6G(SCH_1):PAGE31_I24@PURE_QUANTA.GENOA_SP5(CHIPS)':
 'VSS_BF17': CDS_PINID='VSS_BF17';
NODE_NAME     U25 BF19
 '@T6G_MB_LIB.T6G(SCH_1):PAGE31_I24@PURE_QUANTA.GENOA_SP5(CHIPS)':
 'VSS_BF19': CDS_PINID='VSS_BF19';
NODE_NAME     U25 BF22
 '@T6G_MB_LIB.T6G(SCH_1):PAGE31_I24@PURE_QUANTA.GENOA_SP5(CHIPS)':
 'VSS_BF22': CDS_PINID='VSS_BF22';
NODE_NAME     U25 BF24
 '@T6G_MB_LIB.T6G(SCH_1):PAGE31_I24@PURE_QUANTA.GENOA_SP5(CHIPS)':
 'VSS_BF24': CDS_PINID='VSS_BF24';
NODE_NAME     U25 BF26
 '@T6G_MB_LIB.T6G(SCH_1):PAGE31_I24@PURE_QUANTA.GENOA_SP5(CHIPS)':
 'VSS_BF26': CDS_PINID='VSS_BF26';
NODE_NAME     U25 BF28
 '@T6G_MB_LIB.T6G(SCH_1):PAGE31_I24@PURE_QUANTA.GENOA_SP5(CHIPS)':
 'VSS_BF28': CDS_PINID='VSS_BF28';
NODE_NAME     U25 BF49
 '@T6G_MB_LIB.T6G(SCH_1):PAGE31_I24@PURE_QUANTA.GENOA_SP5(CHIPS)':
 'VSS_BF49': CDS_PINID='VSS_BF49';
NODE_NAME     U25 BF50
 '@T6G_MB_LIB.T6G(SCH_1):PAGE31_I24@PURE_QUANTA.GENOA_SP5(CHIPS)':
 'VSS_BF50': CDS_PINID='VSS_BF50';
NODE_NAME     U25 BF52
 '@T6G_MB_LIB.T6G(SCH_1):PAGE31_I24@PURE_QUANTA.GENOA_SP5(CHIPS)':
 'VSS_BF52': CDS_PINID='VSS_BF52';
NODE_NAME     U25 BF54
 '@T6G_MB_LIB.T6G(SCH_1):PAGE31_I24@PURE_QUANTA.GENOA_SP5(CHIPS)':
 'VSS_BF54': CDS_PINID='VSS_BF54';
NODE_NAME     U25 BF59
 '@T6G_MB_LIB.T6G(SCH_1):PAGE31_I24@PURE_QUANTA.GENOA_SP5(CHIPS)':
 'VSS_BF59': CDS_PINID='VSS_BF59';
NODE_NAME     U25 BF61
 '@T6G_MB_LIB.T6G(SCH_1):PAGE31_I24@PURE_QUANTA.GENOA_SP5(CHIPS)':
 'VSS_BF61': CDS_PINID='VSS_BF61';
NODE_NAME     U25 BF66
 '@T6G_MB_LIB.T6G(SCH_1):PAGE31_I24@PURE_QUANTA.GENOA_SP5(CHIPS)':
 'VSS_BF66': CDS_PINID='VSS_BF66';
NODE_NAME     U25 BF68
 '@T6G_MB_LIB.T6G(SCH_1):PAGE31_I24@PURE_QUANTA.GENOA_SP5(CHIPS)':
 'VSS_BF68': CDS_PINID='VSS_BF68';
NODE_NAME     U25 BF73
 '@T6G_MB_LIB.T6G(SCH_1):PAGE31_I24@PURE_QUANTA.GENOA_SP5(CHIPS)':
 'VSS_BF73': CDS_PINID='VSS_BF73';
NODE_NAME     U25 BG1
 '@T6G_MB_LIB.T6G(SCH_1):PAGE31_I24@PURE_QUANTA.GENOA_SP5(CHIPS)':
 'VSS_BG1': CDS_PINID='VSS_BG1';
NODE_NAME     U25 BG4
 '@T6G_MB_LIB.T6G(SCH_1):PAGE31_I24@PURE_QUANTA.GENOA_SP5(CHIPS)':
 'VSS_BG4': CDS_PINID='VSS_BG4';
NODE_NAME     U25 BG6
 '@T6G_MB_LIB.T6G(SCH_1):PAGE31_I24@PURE_QUANTA.GENOA_SP5(CHIPS)':
 'VSS_BG6': CDS_PINID='VSS_BG6';
NODE_NAME     U25 BG8
 '@T6G_MB_LIB.T6G(SCH_1):PAGE31_I24@PURE_QUANTA.GENOA_SP5(CHIPS)':
 'VSS_BG8': CDS_PINID='VSS_BG8';
NODE_NAME     U25 BG11
 '@T6G_MB_LIB.T6G(SCH_1):PAGE31_I24@PURE_QUANTA.GENOA_SP5(CHIPS)':
 'VSS_BG11': CDS_PINID='VSS_BG11';
NODE_NAME     U25 BG13
 '@T6G_MB_LIB.T6G(SCH_1):PAGE31_I24@PURE_QUANTA.GENOA_SP5(CHIPS)':
 'VSS_BG13': CDS_PINID='VSS_BG13';
NODE_NAME     U25 BG15
 '@T6G_MB_LIB.T6G(SCH_1):PAGE31_I24@PURE_QUANTA.GENOA_SP5(CHIPS)':
 'VSS_BG15': CDS_PINID='VSS_BG15';
NODE_NAME     U25 BG18
 '@T6G_MB_LIB.T6G(SCH_1):PAGE31_I24@PURE_QUANTA.GENOA_SP5(CHIPS)':
 'VSS_BG18': CDS_PINID='VSS_BG18';
NODE_NAME     U25 BG20
 '@T6G_MB_LIB.T6G(SCH_1):PAGE31_I24@PURE_QUANTA.GENOA_SP5(CHIPS)':
 'VSS_BG20': CDS_PINID='VSS_BG20';
NODE_NAME     U25 BG23
 '@T6G_MB_LIB.T6G(SCH_1):PAGE31_I24@PURE_QUANTA.GENOA_SP5(CHIPS)':
 'VSS_BG23': CDS_PINID='VSS_BG23';
NODE_NAME     U25 BG25
 '@T6G_MB_LIB.T6G(SCH_1):PAGE31_I24@PURE_QUANTA.GENOA_SP5(CHIPS)':
 'VSS_BG25': CDS_PINID='VSS_BG25';
NODE_NAME     U25 BG27
 '@T6G_MB_LIB.T6G(SCH_1):PAGE31_I24@PURE_QUANTA.GENOA_SP5(CHIPS)':
 'VSS_BG27': CDS_PINID='VSS_BG27';
NODE_NAME     U25 BG49
 '@T6G_MB_LIB.T6G(SCH_1):PAGE31_I24@PURE_QUANTA.GENOA_SP5(CHIPS)':
 'VSS_BG49': CDS_PINID='VSS_BG49';
NODE_NAME     U25 BG51
 '@T6G_MB_LIB.T6G(SCH_1):PAGE31_I24@PURE_QUANTA.GENOA_SP5(CHIPS)':
 'VSS_BG51': CDS_PINID='VSS_BG51';
NODE_NAME     U25 BG53
 '@T6G_MB_LIB.T6G(SCH_1):PAGE31_I24@PURE_QUANTA.GENOA_SP5(CHIPS)':
 'VSS_BG53': CDS_PINID='VSS_BG53';
NODE_NAME     U25 BG56
 '@T6G_MB_LIB.T6G(SCH_1):PAGE31_I24@PURE_QUANTA.GENOA_SP5(CHIPS)':
 'VSS_BG56': CDS_PINID='VSS_BG56';
NODE_NAME     U25 BG58
 '@T6G_MB_LIB.T6G(SCH_1):PAGE31_I24@PURE_QUANTA.GENOA_SP5(CHIPS)':
 'VSS_BG58': CDS_PINID='VSS_BG58';
NODE_NAME     U25 BG61
 '@T6G_MB_LIB.T6G(SCH_1):PAGE31_I24@PURE_QUANTA.GENOA_SP5(CHIPS)':
 'VSS_BG61': CDS_PINID='VSS_BG61';
NODE_NAME     U25 BG63
 '@T6G_MB_LIB.T6G(SCH_1):PAGE31_I24@PURE_QUANTA.GENOA_SP5(CHIPS)':
 'VSS_BG63': CDS_PINID='VSS_BG63';
NODE_NAME     U25 BG65
 '@T6G_MB_LIB.T6G(SCH_1):PAGE31_I24@PURE_QUANTA.GENOA_SP5(CHIPS)':
 'VSS_BG65': CDS_PINID='VSS_BG65';
NODE_NAME     U25 BG68
 '@T6G_MB_LIB.T6G(SCH_1):PAGE31_I24@PURE_QUANTA.GENOA_SP5(CHIPS)':
 'VSS_BG68': CDS_PINID='VSS_BG68';
NODE_NAME     U25 BG70
 '@T6G_MB_LIB.T6G(SCH_1):PAGE31_I24@PURE_QUANTA.GENOA_SP5(CHIPS)':
 'VSS_BG70': CDS_PINID='VSS_BG70';
NODE_NAME     U25 BG72
 '@T6G_MB_LIB.T6G(SCH_1):PAGE31_I24@PURE_QUANTA.GENOA_SP5(CHIPS)':
 'VSS_BG72': CDS_PINID='VSS_BG72';
NODE_NAME     U25 BG75
 '@T6G_MB_LIB.T6G(SCH_1):PAGE31_I24@PURE_QUANTA.GENOA_SP5(CHIPS)':
 'VSS_BG75': CDS_PINID='VSS_BG75';
NODE_NAME     U25 BH3
 '@T6G_MB_LIB.T6G(SCH_1):PAGE31_I24@PURE_QUANTA.GENOA_SP5(CHIPS)':
 'VSS_BH3': CDS_PINID='VSS_BH3';
NODE_NAME     U25 BH5
 '@T6G_MB_LIB.T6G(SCH_1):PAGE31_I24@PURE_QUANTA.GENOA_SP5(CHIPS)':
 'VSS_BH5': CDS_PINID='VSS_BH5';
NODE_NAME     U25 BH8
 '@T6G_MB_LIB.T6G(SCH_1):PAGE31_I24@PURE_QUANTA.GENOA_SP5(CHIPS)':
 'VSS_BH8': CDS_PINID='VSS_BH8';
NODE_NAME     U25 BH10
 '@T6G_MB_LIB.T6G(SCH_1):PAGE31_I24@PURE_QUANTA.GENOA_SP5(CHIPS)':
 'VSS_BH10': CDS_PINID='VSS_BH10';
NODE_NAME     U25 BH12
 '@T6G_MB_LIB.T6G(SCH_1):PAGE31_I24@PURE_QUANTA.GENOA_SP5(CHIPS)':
 'VSS_BH12': CDS_PINID='VSS_BH12';
NODE_NAME     U25 BH15
 '@T6G_MB_LIB.T6G(SCH_1):PAGE31_I24@PURE_QUANTA.GENOA_SP5(CHIPS)':
 'VSS_BH15': CDS_PINID='VSS_BH15';
NODE_NAME     U25 BH17
 '@T6G_MB_LIB.T6G(SCH_1):PAGE31_I24@PURE_QUANTA.GENOA_SP5(CHIPS)':
 'VSS_BH17': CDS_PINID='VSS_BH17';
NODE_NAME     U25 BH19
 '@T6G_MB_LIB.T6G(SCH_1):PAGE31_I24@PURE_QUANTA.GENOA_SP5(CHIPS)':
 'VSS_BH19': CDS_PINID='VSS_BH19';
NODE_NAME     U25 BH22
 '@T6G_MB_LIB.T6G(SCH_1):PAGE31_I24@PURE_QUANTA.GENOA_SP5(CHIPS)':
 'VSS_BH22': CDS_PINID='VSS_BH22';
NODE_NAME     U25 BH24
 '@T6G_MB_LIB.T6G(SCH_1):PAGE31_I24@PURE_QUANTA.GENOA_SP5(CHIPS)':
 'VSS_BH24': CDS_PINID='VSS_BH24';
NODE_NAME     U25 BH26
 '@T6G_MB_LIB.T6G(SCH_1):PAGE31_I24@PURE_QUANTA.GENOA_SP5(CHIPS)':
 'VSS_BH26': CDS_PINID='VSS_BH26';
NODE_NAME     U25 BH28
 '@T6G_MB_LIB.T6G(SCH_1):PAGE31_I24@PURE_QUANTA.GENOA_SP5(CHIPS)':
 'VSS_BH28': CDS_PINID='VSS_BH28';
NODE_NAME     U25 BH49
 '@T6G_MB_LIB.T6G(SCH_1):PAGE31_I24@PURE_QUANTA.GENOA_SP5(CHIPS)':
 'VSS_BH49': CDS_PINID='VSS_BH49';
NODE_NAME     U25 BH50
 '@T6G_MB_LIB.T6G(SCH_1):PAGE31_I24@PURE_QUANTA.GENOA_SP5(CHIPS)':
 'VSS_BH50': CDS_PINID='VSS_BH50';
NODE_NAME     U25 BH52
 '@T6G_MB_LIB.T6G(SCH_1):PAGE31_I24@PURE_QUANTA.GENOA_SP5(CHIPS)':
 'VSS_BH52': CDS_PINID='VSS_BH52';
NODE_NAME     U25 BH54
 '@T6G_MB_LIB.T6G(SCH_1):PAGE31_I24@PURE_QUANTA.GENOA_SP5(CHIPS)':
 'VSS_BH54': CDS_PINID='VSS_BH54';
NODE_NAME     U25 BH57
 '@T6G_MB_LIB.T6G(SCH_1):PAGE31_I24@PURE_QUANTA.GENOA_SP5(CHIPS)':
 'VSS_BH57': CDS_PINID='VSS_BH57';
NODE_NAME     U25 BH59
 '@T6G_MB_LIB.T6G(SCH_1):PAGE31_I24@PURE_QUANTA.GENOA_SP5(CHIPS)':
 'VSS_BH59': CDS_PINID='VSS_BH59';
NODE_NAME     U25 BH61
 '@T6G_MB_LIB.T6G(SCH_1):PAGE31_I24@PURE_QUANTA.GENOA_SP5(CHIPS)':
 'VSS_BH61': CDS_PINID='VSS_BH61';
NODE_NAME     U25 BH64
 '@T6G_MB_LIB.T6G(SCH_1):PAGE31_I24@PURE_QUANTA.GENOA_SP5(CHIPS)':
 'VSS_BH64': CDS_PINID='VSS_BH64';
NODE_NAME     U25 BH66
 '@T6G_MB_LIB.T6G(SCH_1):PAGE31_I24@PURE_QUANTA.GENOA_SP5(CHIPS)':
 'VSS_BH66': CDS_PINID='VSS_BH66';
NODE_NAME     U25 BH68
 '@T6G_MB_LIB.T6G(SCH_1):PAGE31_I24@PURE_QUANTA.GENOA_SP5(CHIPS)':
 'VSS_BH68': CDS_PINID='VSS_BH68';
NODE_NAME     U25 BH71
 '@T6G_MB_LIB.T6G(SCH_1):PAGE31_I24@PURE_QUANTA.GENOA_SP5(CHIPS)':
 'VSS_BH71': CDS_PINID='VSS_BH71';
NODE_NAME     U25 BH73
 '@T6G_MB_LIB.T6G(SCH_1):PAGE31_I24@PURE_QUANTA.GENOA_SP5(CHIPS)':
 'VSS_BH73': CDS_PINID='VSS_BH73';
NODE_NAME     U25 BJ1
 '@T6G_MB_LIB.T6G(SCH_1):PAGE31_I24@PURE_QUANTA.GENOA_SP5(CHIPS)':
 'VSS_BJ1': CDS_PINID='VSS_BJ1';
NODE_NAME     U25 BJ6
 '@T6G_MB_LIB.T6G(SCH_1):PAGE31_I24@PURE_QUANTA.GENOA_SP5(CHIPS)':
 'VSS_BJ6': CDS_PINID='VSS_BJ6';
NODE_NAME     U25 BJ8
 '@T6G_MB_LIB.T6G(SCH_1):PAGE31_I24@PURE_QUANTA.GENOA_SP5(CHIPS)':
 'VSS_BJ8': CDS_PINID='VSS_BJ8';
NODE_NAME     U25 BJ13
 '@T6G_MB_LIB.T6G(SCH_1):PAGE31_I24@PURE_QUANTA.GENOA_SP5(CHIPS)':
 'VSS_BJ13': CDS_PINID='VSS_BJ13';
NODE_NAME     U25 BJ15
 '@T6G_MB_LIB.T6G(SCH_1):PAGE31_I24@PURE_QUANTA.GENOA_SP5(CHIPS)':
 'VSS_BJ15': CDS_PINID='VSS_BJ15';
NODE_NAME     U25 BJ20
 '@T6G_MB_LIB.T6G(SCH_1):PAGE31_I24@PURE_QUANTA.GENOA_SP5(CHIPS)':
 'VSS_BJ20': CDS_PINID='VSS_BJ20';
NODE_NAME     U25 BJ22
 '@T6G_MB_LIB.T6G(SCH_1):PAGE31_I24@PURE_QUANTA.GENOA_SP5(CHIPS)':
 'VSS_BJ22': CDS_PINID='VSS_BJ22';
NODE_NAME     U25 BJ24
 '@T6G_MB_LIB.T6G(SCH_1):PAGE31_I24@PURE_QUANTA.GENOA_SP5(CHIPS)':
 'VSS_BJ24': CDS_PINID='VSS_BJ24';
NODE_NAME     U25 BJ26
 '@T6G_MB_LIB.T6G(SCH_1):PAGE31_I24@PURE_QUANTA.GENOA_SP5(CHIPS)':
 'VSS_BJ26': CDS_PINID='VSS_BJ26';
NODE_NAME     U25 BJ28
 '@T6G_MB_LIB.T6G(SCH_1):PAGE31_I24@PURE_QUANTA.GENOA_SP5(CHIPS)':
 'VSS_BJ28': CDS_PINID='VSS_BJ28';
NODE_NAME     U25 BJ49
 '@T6G_MB_LIB.T6G(SCH_1):PAGE31_I24@PURE_QUANTA.GENOA_SP5(CHIPS)':
 'VSS_BJ49': CDS_PINID='VSS_BJ49';
NODE_NAME     U25 BJ51
 '@T6G_MB_LIB.T6G(SCH_1):PAGE31_I24@PURE_QUANTA.GENOA_SP5(CHIPS)':
 'VSS_BJ51': CDS_PINID='VSS_BJ51';
NODE_NAME     U25 BJ53
 '@T6G_MB_LIB.T6G(SCH_1):PAGE31_I24@PURE_QUANTA.GENOA_SP5(CHIPS)':
 'VSS_BJ53': CDS_PINID='VSS_BJ53';
NODE_NAME     U25 BJ56
 '@T6G_MB_LIB.T6G(SCH_1):PAGE31_I24@PURE_QUANTA.GENOA_SP5(CHIPS)':
 'VSS_BJ56': CDS_PINID='VSS_BJ56';
NODE_NAME     U25 BJ61
 '@T6G_MB_LIB.T6G(SCH_1):PAGE31_I24@PURE_QUANTA.GENOA_SP5(CHIPS)':
 'VSS_BJ61': CDS_PINID='VSS_BJ61';
NODE_NAME     U25 BJ63
 '@T6G_MB_LIB.T6G(SCH_1):PAGE31_I24@PURE_QUANTA.GENOA_SP5(CHIPS)':
 'VSS_BJ63': CDS_PINID='VSS_BJ63';
NODE_NAME     U25 BJ68
 '@T6G_MB_LIB.T6G(SCH_1):PAGE31_I24@PURE_QUANTA.GENOA_SP5(CHIPS)':
 'VSS_BJ68': CDS_PINID='VSS_BJ68';
NODE_NAME     U25 BJ70
 '@T6G_MB_LIB.T6G(SCH_1):PAGE31_I24@PURE_QUANTA.GENOA_SP5(CHIPS)':
 'VSS_BJ70': CDS_PINID='VSS_BJ70';
NODE_NAME     U25 BJ75
 '@T6G_MB_LIB.T6G(SCH_1):PAGE31_I24@PURE_QUANTA.GENOA_SP5(CHIPS)':
 'VSS_BJ75': CDS_PINID='VSS_BJ75';
NODE_NAME     U25 BK3
 '@T6G_MB_LIB.T6G(SCH_1):PAGE31_I24@PURE_QUANTA.GENOA_SP5(CHIPS)':
 'VSS_BK3': CDS_PINID='VSS_BK3';
NODE_NAME     U25 BK5
 '@T6G_MB_LIB.T6G(SCH_1):PAGE31_I24@PURE_QUANTA.GENOA_SP5(CHIPS)':
 'VSS_BK5': CDS_PINID='VSS_BK5';
NODE_NAME     U25 BK8
 '@T6G_MB_LIB.T6G(SCH_1):PAGE31_I24@PURE_QUANTA.GENOA_SP5(CHIPS)':
 'VSS_BK8': CDS_PINID='VSS_BK8';
NODE_NAME     U25 BK10
 '@T6G_MB_LIB.T6G(SCH_1):PAGE31_I24@PURE_QUANTA.GENOA_SP5(CHIPS)':
 'VSS_BK10': CDS_PINID='VSS_BK10';
NODE_NAME     U25 BK12
 '@T6G_MB_LIB.T6G(SCH_1):PAGE31_I24@PURE_QUANTA.GENOA_SP5(CHIPS)':
 'VSS_BK12': CDS_PINID='VSS_BK12';
NODE_NAME     U25 BK15
 '@T6G_MB_LIB.T6G(SCH_1):PAGE31_I24@PURE_QUANTA.GENOA_SP5(CHIPS)':
 'VSS_BK15': CDS_PINID='VSS_BK15';
NODE_NAME     U25 BK17
 '@T6G_MB_LIB.T6G(SCH_1):PAGE31_I24@PURE_QUANTA.GENOA_SP5(CHIPS)':
 'VSS_BK17': CDS_PINID='VSS_BK17';
NODE_NAME     U25 BK19
 '@T6G_MB_LIB.T6G(SCH_1):PAGE31_I24@PURE_QUANTA.GENOA_SP5(CHIPS)':
 'VSS_BK19': CDS_PINID='VSS_BK19';
NODE_NAME     U25 BK23
 '@T6G_MB_LIB.T6G(SCH_1):PAGE31_I24@PURE_QUANTA.GENOA_SP5(CHIPS)':
 'VSS_BK23': CDS_PINID='VSS_BK23';
NODE_NAME     U25 BK25
 '@T6G_MB_LIB.T6G(SCH_1):PAGE31_I24@PURE_QUANTA.GENOA_SP5(CHIPS)':
 'VSS_BK25': CDS_PINID='VSS_BK25';
NODE_NAME     U25 BK27
 '@T6G_MB_LIB.T6G(SCH_1):PAGE31_I24@PURE_QUANTA.GENOA_SP5(CHIPS)':
 'VSS_BK27': CDS_PINID='VSS_BK27';
NODE_NAME     U25 BK48
 '@T6G_MB_LIB.T6G(SCH_1):PAGE31_I24@PURE_QUANTA.GENOA_SP5(CHIPS)':
 'VSS_BK48': CDS_PINID='VSS_BK48';
NODE_NAME     U25 BK50
 '@T6G_MB_LIB.T6G(SCH_1):PAGE31_I24@PURE_QUANTA.GENOA_SP5(CHIPS)':
 'VSS_BK50': CDS_PINID='VSS_BK50';
NODE_NAME     U25 BK52
 '@T6G_MB_LIB.T6G(SCH_1):PAGE31_I24@PURE_QUANTA.GENOA_SP5(CHIPS)':
 'VSS_BK52': CDS_PINID='VSS_BK52';
NODE_NAME     U25 BK54
 '@T6G_MB_LIB.T6G(SCH_1):PAGE31_I24@PURE_QUANTA.GENOA_SP5(CHIPS)':
 'VSS_BK54': CDS_PINID='VSS_BK54';
NODE_NAME     U25 BK57
 '@T6G_MB_LIB.T6G(SCH_1):PAGE31_I24@PURE_QUANTA.GENOA_SP5(CHIPS)':
 'VSS_BK57': CDS_PINID='VSS_BK57';
NODE_NAME     U25 BK59
 '@T6G_MB_LIB.T6G(SCH_1):PAGE31_I24@PURE_QUANTA.GENOA_SP5(CHIPS)':
 'VSS_BK59': CDS_PINID='VSS_BK59';
NODE_NAME     U25 BK61
 '@T6G_MB_LIB.T6G(SCH_1):PAGE31_I24@PURE_QUANTA.GENOA_SP5(CHIPS)':
 'VSS_BK61': CDS_PINID='VSS_BK61';
NODE_NAME     U25 BK64
 '@T6G_MB_LIB.T6G(SCH_1):PAGE31_I24@PURE_QUANTA.GENOA_SP5(CHIPS)':
 'VSS_BK64': CDS_PINID='VSS_BK64';
NODE_NAME     U25 BK66
 '@T6G_MB_LIB.T6G(SCH_1):PAGE31_I24@PURE_QUANTA.GENOA_SP5(CHIPS)':
 'VSS_BK66': CDS_PINID='VSS_BK66';
NODE_NAME     U25 BK68
 '@T6G_MB_LIB.T6G(SCH_1):PAGE31_I24@PURE_QUANTA.GENOA_SP5(CHIPS)':
 'VSS_BK68': CDS_PINID='VSS_BK68';
NODE_NAME     U25 BK71
 '@T6G_MB_LIB.T6G(SCH_1):PAGE31_I24@PURE_QUANTA.GENOA_SP5(CHIPS)':
 'VSS_BK71': CDS_PINID='VSS_BK71';
NODE_NAME     U25 BK73
 '@T6G_MB_LIB.T6G(SCH_1):PAGE31_I24@PURE_QUANTA.GENOA_SP5(CHIPS)':
 'VSS_BK73': CDS_PINID='VSS_BK73';
NODE_NAME     U25 BL1
 '@T6G_MB_LIB.T6G(SCH_1):PAGE31_I24@PURE_QUANTA.GENOA_SP5(CHIPS)':
 'VSS_BL1': CDS_PINID='VSS_BL1';
NODE_NAME     U25 BL4
 '@T6G_MB_LIB.T6G(SCH_1):PAGE31_I24@PURE_QUANTA.GENOA_SP5(CHIPS)':
 'VSS_BL4': CDS_PINID='VSS_BL4';
NODE_NAME     U25 BL6
 '@T6G_MB_LIB.T6G(SCH_1):PAGE31_I24@PURE_QUANTA.GENOA_SP5(CHIPS)':
 'VSS_BL6': CDS_PINID='VSS_BL6';
NODE_NAME     U25 BL8
 '@T6G_MB_LIB.T6G(SCH_1):PAGE31_I24@PURE_QUANTA.GENOA_SP5(CHIPS)':
 'VSS_BL8': CDS_PINID='VSS_BL8';
NODE_NAME     U25 BL11
 '@T6G_MB_LIB.T6G(SCH_1):PAGE31_I24@PURE_QUANTA.GENOA_SP5(CHIPS)':
 'VSS_BL11': CDS_PINID='VSS_BL11';
NODE_NAME     U25 BL13
 '@T6G_MB_LIB.T6G(SCH_1):PAGE31_I24@PURE_QUANTA.GENOA_SP5(CHIPS)':
 'VSS_BL13': CDS_PINID='VSS_BL13';
NODE_NAME     U25 BL15
 '@T6G_MB_LIB.T6G(SCH_1):PAGE31_I24@PURE_QUANTA.GENOA_SP5(CHIPS)':
 'VSS_BL15': CDS_PINID='VSS_BL15';
NODE_NAME     U25 BL18
 '@T6G_MB_LIB.T6G(SCH_1):PAGE31_I24@PURE_QUANTA.GENOA_SP5(CHIPS)':
 'VSS_BL18': CDS_PINID='VSS_BL18';
NODE_NAME     U25 BL20
 '@T6G_MB_LIB.T6G(SCH_1):PAGE31_I24@PURE_QUANTA.GENOA_SP5(CHIPS)':
 'VSS_BL20': CDS_PINID='VSS_BL20';
NODE_NAME     U25 BL22
 '@T6G_MB_LIB.T6G(SCH_1):PAGE31_I24@PURE_QUANTA.GENOA_SP5(CHIPS)':
 'VSS_BL22': CDS_PINID='VSS_BL22';
NODE_NAME     U25 BL24
 '@T6G_MB_LIB.T6G(SCH_1):PAGE31_I24@PURE_QUANTA.GENOA_SP5(CHIPS)':
 'VSS_BL24': CDS_PINID='VSS_BL24';
NODE_NAME     U25 BL26
 '@T6G_MB_LIB.T6G(SCH_1):PAGE32_I13@PURE_QUANTA.GENOA_SP5(CHIPS)':
 'VSS_BL26': CDS_PINID='VSS_BL26';
NODE_NAME     U25 BL28
 '@T6G_MB_LIB.T6G(SCH_1):PAGE32_I13@PURE_QUANTA.GENOA_SP5(CHIPS)':
 'VSS_BL28': CDS_PINID='VSS_BL28';
NODE_NAME     U25 BL49
 '@T6G_MB_LIB.T6G(SCH_1):PAGE32_I13@PURE_QUANTA.GENOA_SP5(CHIPS)':
 'VSS_BL49': CDS_PINID='VSS_BL49';
NODE_NAME     U25 BL51
 '@T6G_MB_LIB.T6G(SCH_1):PAGE32_I13@PURE_QUANTA.GENOA_SP5(CHIPS)':
 'VSS_BL51': CDS_PINID='VSS_BL51';
NODE_NAME     U25 BL53
 '@T6G_MB_LIB.T6G(SCH_1):PAGE32_I13@PURE_QUANTA.GENOA_SP5(CHIPS)':
 'VSS_BL53': CDS_PINID='VSS_BL53';
NODE_NAME     U25 BL56
 '@T6G_MB_LIB.T6G(SCH_1):PAGE32_I13@PURE_QUANTA.GENOA_SP5(CHIPS)':
 'VSS_BL56': CDS_PINID='VSS_BL56';
NODE_NAME     U25 BL58
 '@T6G_MB_LIB.T6G(SCH_1):PAGE32_I13@PURE_QUANTA.GENOA_SP5(CHIPS)':
 'VSS_BL58': CDS_PINID='VSS_BL58';
NODE_NAME     U25 BL61
 '@T6G_MB_LIB.T6G(SCH_1):PAGE32_I13@PURE_QUANTA.GENOA_SP5(CHIPS)':
 'VSS_BL61': CDS_PINID='VSS_BL61';
NODE_NAME     U25 BL63
 '@T6G_MB_LIB.T6G(SCH_1):PAGE32_I13@PURE_QUANTA.GENOA_SP5(CHIPS)':
 'VSS_BL63': CDS_PINID='VSS_BL63';
NODE_NAME     U25 BL65
 '@T6G_MB_LIB.T6G(SCH_1):PAGE32_I13@PURE_QUANTA.GENOA_SP5(CHIPS)':
 'VSS_BL65': CDS_PINID='VSS_BL65';
NODE_NAME     U25 BL68
 '@T6G_MB_LIB.T6G(SCH_1):PAGE32_I13@PURE_QUANTA.GENOA_SP5(CHIPS)':
 'VSS_BL68': CDS_PINID='VSS_BL68';
NODE_NAME     U25 BL70
 '@T6G_MB_LIB.T6G(SCH_1):PAGE32_I13@PURE_QUANTA.GENOA_SP5(CHIPS)':
 'VSS_BL70': CDS_PINID='VSS_BL70';
NODE_NAME     U25 BL72
 '@T6G_MB_LIB.T6G(SCH_1):PAGE32_I13@PURE_QUANTA.GENOA_SP5(CHIPS)':
 'VSS_BL72': CDS_PINID='VSS_BL72';
NODE_NAME     U25 BL75
 '@T6G_MB_LIB.T6G(SCH_1):PAGE32_I13@PURE_QUANTA.GENOA_SP5(CHIPS)':
 'VSS_BL75': CDS_PINID='VSS_BL75';
NODE_NAME     U25 BM3
 '@T6G_MB_LIB.T6G(SCH_1):PAGE32_I13@PURE_QUANTA.GENOA_SP5(CHIPS)':
 'VSS_BM3': CDS_PINID='VSS_BM3';
NODE_NAME     U25 BM8
 '@T6G_MB_LIB.T6G(SCH_1):PAGE32_I13@PURE_QUANTA.GENOA_SP5(CHIPS)':
 'VSS_BM8': CDS_PINID='VSS_BM8';
NODE_NAME     U25 BM10
 '@T6G_MB_LIB.T6G(SCH_1):PAGE32_I13@PURE_QUANTA.GENOA_SP5(CHIPS)':
 'VSS_BM10': CDS_PINID='VSS_BM10';
NODE_NAME     U25 BM15
 '@T6G_MB_LIB.T6G(SCH_1):PAGE32_I13@PURE_QUANTA.GENOA_SP5(CHIPS)':
 'VSS_BM15': CDS_PINID='VSS_BM15';
NODE_NAME     U25 BM17
 '@T6G_MB_LIB.T6G(SCH_1):PAGE32_I13@PURE_QUANTA.GENOA_SP5(CHIPS)':
 'VSS_BM17': CDS_PINID='VSS_BM17';
NODE_NAME     U25 BM23
 '@T6G_MB_LIB.T6G(SCH_1):PAGE32_I13@PURE_QUANTA.GENOA_SP5(CHIPS)':
 'VSS_BM23': CDS_PINID='VSS_BM23';
NODE_NAME     U25 BM25
 '@T6G_MB_LIB.T6G(SCH_1):PAGE32_I13@PURE_QUANTA.GENOA_SP5(CHIPS)':
 'VSS_BM25': CDS_PINID='VSS_BM25';
NODE_NAME     U25 BM27
 '@T6G_MB_LIB.T6G(SCH_1):PAGE32_I13@PURE_QUANTA.GENOA_SP5(CHIPS)':
 'VSS_BM27': CDS_PINID='VSS_BM27';
NODE_NAME     U25 BM29
 '@T6G_MB_LIB.T6G(SCH_1):PAGE32_I13@PURE_QUANTA.GENOA_SP5(CHIPS)':
 'VSS_BM29': CDS_PINID='VSS_BM29';
NODE_NAME     U25 BM31
 '@T6G_MB_LIB.T6G(SCH_1):PAGE32_I13@PURE_QUANTA.GENOA_SP5(CHIPS)':
 'VSS_BM31': CDS_PINID='VSS_BM31';
NODE_NAME     U25 BM33
 '@T6G_MB_LIB.T6G(SCH_1):PAGE32_I13@PURE_QUANTA.GENOA_SP5(CHIPS)':
 'VSS_BM33': CDS_PINID='VSS_BM33';
NODE_NAME     U25 BM35
 '@T6G_MB_LIB.T6G(SCH_1):PAGE32_I13@PURE_QUANTA.GENOA_SP5(CHIPS)':
 'VSS_BM35': CDS_PINID='VSS_BM35';
NODE_NAME     U25 BM37
 '@T6G_MB_LIB.T6G(SCH_1):PAGE32_I13@PURE_QUANTA.GENOA_SP5(CHIPS)':
 'VSS_BM37': CDS_PINID='VSS_BM37';
NODE_NAME     U25 BM40
 '@T6G_MB_LIB.T6G(SCH_1):PAGE32_I13@PURE_QUANTA.GENOA_SP5(CHIPS)':
 'VSS_BM40': CDS_PINID='VSS_BM40';
NODE_NAME     U25 BM42
 '@T6G_MB_LIB.T6G(SCH_1):PAGE32_I13@PURE_QUANTA.GENOA_SP5(CHIPS)':
 'VSS_BM42': CDS_PINID='VSS_BM42';
NODE_NAME     U25 BM44
 '@T6G_MB_LIB.T6G(SCH_1):PAGE32_I13@PURE_QUANTA.GENOA_SP5(CHIPS)':
 'VSS_BM44': CDS_PINID='VSS_BM44';
NODE_NAME     U25 BM46
 '@T6G_MB_LIB.T6G(SCH_1):PAGE32_I13@PURE_QUANTA.GENOA_SP5(CHIPS)':
 'VSS_BM46': CDS_PINID='VSS_BM46';
NODE_NAME     U25 BM48
 '@T6G_MB_LIB.T6G(SCH_1):PAGE32_I13@PURE_QUANTA.GENOA_SP5(CHIPS)':
 'VSS_BM48': CDS_PINID='VSS_BM48';
NODE_NAME     U25 BM50
 '@T6G_MB_LIB.T6G(SCH_1):PAGE32_I13@PURE_QUANTA.GENOA_SP5(CHIPS)':
 'VSS_BM50': CDS_PINID='VSS_BM50';
NODE_NAME     U25 BM52
 '@T6G_MB_LIB.T6G(SCH_1):PAGE32_I13@PURE_QUANTA.GENOA_SP5(CHIPS)':
 'VSS_BM52': CDS_PINID='VSS_BM52';
NODE_NAME     U25 BM54
 '@T6G_MB_LIB.T6G(SCH_1):PAGE32_I13@PURE_QUANTA.GENOA_SP5(CHIPS)':
 'VSS_BM54': CDS_PINID='VSS_BM54';
NODE_NAME     U25 BM59
 '@T6G_MB_LIB.T6G(SCH_1):PAGE32_I13@PURE_QUANTA.GENOA_SP5(CHIPS)':
 'VSS_BM59': CDS_PINID='VSS_BM59';
NODE_NAME     U25 BM61
 '@T6G_MB_LIB.T6G(SCH_1):PAGE32_I13@PURE_QUANTA.GENOA_SP5(CHIPS)':
 'VSS_BM61': CDS_PINID='VSS_BM61';
NODE_NAME     U25 BM66
 '@T6G_MB_LIB.T6G(SCH_1):PAGE32_I13@PURE_QUANTA.GENOA_SP5(CHIPS)':
 'VSS_BM66': CDS_PINID='VSS_BM66';
NODE_NAME     U25 BM68
 '@T6G_MB_LIB.T6G(SCH_1):PAGE32_I13@PURE_QUANTA.GENOA_SP5(CHIPS)':
 'VSS_BM68': CDS_PINID='VSS_BM68';
NODE_NAME     U25 BM73
 '@T6G_MB_LIB.T6G(SCH_1):PAGE32_I13@PURE_QUANTA.GENOA_SP5(CHIPS)':
 'VSS_BM73': CDS_PINID='VSS_BM73';
NODE_NAME     U25 BN1
 '@T6G_MB_LIB.T6G(SCH_1):PAGE32_I13@PURE_QUANTA.GENOA_SP5(CHIPS)':
 'VSS_BN1': CDS_PINID='VSS_BN1';
NODE_NAME     U25 BN4
 '@T6G_MB_LIB.T6G(SCH_1):PAGE32_I13@PURE_QUANTA.GENOA_SP5(CHIPS)':
 'VSS_BN4': CDS_PINID='VSS_BN4';
NODE_NAME     U25 BN6
 '@T6G_MB_LIB.T6G(SCH_1):PAGE32_I13@PURE_QUANTA.GENOA_SP5(CHIPS)':
 'VSS_BN6': CDS_PINID='VSS_BN6';
NODE_NAME     U25 BN8
 '@T6G_MB_LIB.T6G(SCH_1):PAGE32_I13@PURE_QUANTA.GENOA_SP5(CHIPS)':
 'VSS_BN8': CDS_PINID='VSS_BN8';
NODE_NAME     U25 BN11
 '@T6G_MB_LIB.T6G(SCH_1):PAGE32_I13@PURE_QUANTA.GENOA_SP5(CHIPS)':
 'VSS_BN11': CDS_PINID='VSS_BN11';
NODE_NAME     U25 BN13
 '@T6G_MB_LIB.T6G(SCH_1):PAGE32_I13@PURE_QUANTA.GENOA_SP5(CHIPS)':
 'VSS_BN13': CDS_PINID='VSS_BN13';
NODE_NAME     U25 BN15
 '@T6G_MB_LIB.T6G(SCH_1):PAGE32_I13@PURE_QUANTA.GENOA_SP5(CHIPS)':
 'VSS_BN15': CDS_PINID='VSS_BN15';
NODE_NAME     U25 BN18
 '@T6G_MB_LIB.T6G(SCH_1):PAGE32_I13@PURE_QUANTA.GENOA_SP5(CHIPS)':
 'VSS_BN18': CDS_PINID='VSS_BN18';
NODE_NAME     U25 BN20
 '@T6G_MB_LIB.T6G(SCH_1):PAGE32_I13@PURE_QUANTA.GENOA_SP5(CHIPS)':
 'VSS_BN20': CDS_PINID='VSS_BN20';
NODE_NAME     U25 BN22
 '@T6G_MB_LIB.T6G(SCH_1):PAGE32_I13@PURE_QUANTA.GENOA_SP5(CHIPS)':
 'VSS_BN22': CDS_PINID='VSS_BN22';
NODE_NAME     U25 BN24
 '@T6G_MB_LIB.T6G(SCH_1):PAGE32_I13@PURE_QUANTA.GENOA_SP5(CHIPS)':
 'VSS_BN24': CDS_PINID='VSS_BN24';
NODE_NAME     U25 BN26
 '@T6G_MB_LIB.T6G(SCH_1):PAGE32_I13@PURE_QUANTA.GENOA_SP5(CHIPS)':
 'VSS_BN26': CDS_PINID='VSS_BN26';
NODE_NAME     U25 BN28
 '@T6G_MB_LIB.T6G(SCH_1):PAGE32_I13@PURE_QUANTA.GENOA_SP5(CHIPS)':
 'VSS_BN28': CDS_PINID='VSS_BN28';
NODE_NAME     U25 BN30
 '@T6G_MB_LIB.T6G(SCH_1):PAGE32_I13@PURE_QUANTA.GENOA_SP5(CHIPS)':
 'VSS_BN30': CDS_PINID='VSS_BN30';
NODE_NAME     U25 BN32
 '@T6G_MB_LIB.T6G(SCH_1):PAGE32_I13@PURE_QUANTA.GENOA_SP5(CHIPS)':
 'VSS_BN32': CDS_PINID='VSS_BN32';
NODE_NAME     U25 BN34
 '@T6G_MB_LIB.T6G(SCH_1):PAGE32_I13@PURE_QUANTA.GENOA_SP5(CHIPS)':
 'VSS_BN34': CDS_PINID='VSS_BN34';
NODE_NAME     U25 BN36
 '@T6G_MB_LIB.T6G(SCH_1):PAGE32_I13@PURE_QUANTA.GENOA_SP5(CHIPS)':
 'VSS_BN36': CDS_PINID='VSS_BN36';
NODE_NAME     U25 BN41
 '@T6G_MB_LIB.T6G(SCH_1):PAGE32_I13@PURE_QUANTA.GENOA_SP5(CHIPS)':
 'VSS_BN41': CDS_PINID='VSS_BN41';
NODE_NAME     U25 BN43
 '@T6G_MB_LIB.T6G(SCH_1):PAGE32_I13@PURE_QUANTA.GENOA_SP5(CHIPS)':
 'VSS_BN43': CDS_PINID='VSS_BN43';
NODE_NAME     U25 BN45
 '@T6G_MB_LIB.T6G(SCH_1):PAGE32_I13@PURE_QUANTA.GENOA_SP5(CHIPS)':
 'VSS_BN45': CDS_PINID='VSS_BN45';
NODE_NAME     U25 BN47
 '@T6G_MB_LIB.T6G(SCH_1):PAGE32_I13@PURE_QUANTA.GENOA_SP5(CHIPS)':
 'VSS_BN47': CDS_PINID='VSS_BN47';
NODE_NAME     U25 BN49
 '@T6G_MB_LIB.T6G(SCH_1):PAGE32_I13@PURE_QUANTA.GENOA_SP5(CHIPS)':
 'VSS_BN49': CDS_PINID='VSS_BN49';
NODE_NAME     U25 BN51
 '@T6G_MB_LIB.T6G(SCH_1):PAGE32_I13@PURE_QUANTA.GENOA_SP5(CHIPS)':
 'VSS_BN51': CDS_PINID='VSS_BN51';
NODE_NAME     U25 BN53
 '@T6G_MB_LIB.T6G(SCH_1):PAGE32_I13@PURE_QUANTA.GENOA_SP5(CHIPS)':
 'VSS_BN53': CDS_PINID='VSS_BN53';
NODE_NAME     U25 BN56
 '@T6G_MB_LIB.T6G(SCH_1):PAGE32_I13@PURE_QUANTA.GENOA_SP5(CHIPS)':
 'VSS_BN56': CDS_PINID='VSS_BN56';
NODE_NAME     U25 BN58
 '@T6G_MB_LIB.T6G(SCH_1):PAGE32_I13@PURE_QUANTA.GENOA_SP5(CHIPS)':
 'VSS_BN58': CDS_PINID='VSS_BN58';
NODE_NAME     U25 BN61
 '@T6G_MB_LIB.T6G(SCH_1):PAGE32_I13@PURE_QUANTA.GENOA_SP5(CHIPS)':
 'VSS_BN61': CDS_PINID='VSS_BN61';
NODE_NAME     U25 BN63
 '@T6G_MB_LIB.T6G(SCH_1):PAGE32_I13@PURE_QUANTA.GENOA_SP5(CHIPS)':
 'VSS_BN63': CDS_PINID='VSS_BN63';
NODE_NAME     U25 BN65
 '@T6G_MB_LIB.T6G(SCH_1):PAGE32_I13@PURE_QUANTA.GENOA_SP5(CHIPS)':
 'VSS_BN65': CDS_PINID='VSS_BN65';
NODE_NAME     U25 BN68
 '@T6G_MB_LIB.T6G(SCH_1):PAGE32_I13@PURE_QUANTA.GENOA_SP5(CHIPS)':
 'VSS_BN68': CDS_PINID='VSS_BN68';
NODE_NAME     U25 BN70
 '@T6G_MB_LIB.T6G(SCH_1):PAGE32_I13@PURE_QUANTA.GENOA_SP5(CHIPS)':
 'VSS_BN70': CDS_PINID='VSS_BN70';
NODE_NAME     U25 BN72
 '@T6G_MB_LIB.T6G(SCH_1):PAGE32_I13@PURE_QUANTA.GENOA_SP5(CHIPS)':
 'VSS_BN72': CDS_PINID='VSS_BN72';
NODE_NAME     U25 BN75
 '@T6G_MB_LIB.T6G(SCH_1):PAGE32_I13@PURE_QUANTA.GENOA_SP5(CHIPS)':
 'VSS_BN75': CDS_PINID='VSS_BN75';
NODE_NAME     U25 BP3
 '@T6G_MB_LIB.T6G(SCH_1):PAGE32_I13@PURE_QUANTA.GENOA_SP5(CHIPS)':
 'VSS_BP3': CDS_PINID='VSS_BP3';
NODE_NAME     U25 BP5
 '@T6G_MB_LIB.T6G(SCH_1):PAGE32_I13@PURE_QUANTA.GENOA_SP5(CHIPS)':
 'VSS_BP5': CDS_PINID='VSS_BP5';
NODE_NAME     U25 BP8
 '@T6G_MB_LIB.T6G(SCH_1):PAGE32_I13@PURE_QUANTA.GENOA_SP5(CHIPS)':
 'VSS_BP8': CDS_PINID='VSS_BP8';
NODE_NAME     U25 BP10
 '@T6G_MB_LIB.T6G(SCH_1):PAGE32_I13@PURE_QUANTA.GENOA_SP5(CHIPS)':
 'VSS_BP10': CDS_PINID='VSS_BP10';
NODE_NAME     U25 BP12
 '@T6G_MB_LIB.T6G(SCH_1):PAGE32_I13@PURE_QUANTA.GENOA_SP5(CHIPS)':
 'VSS_BP12': CDS_PINID='VSS_BP12';
NODE_NAME     U25 BP15
 '@T6G_MB_LIB.T6G(SCH_1):PAGE32_I13@PURE_QUANTA.GENOA_SP5(CHIPS)':
 'VSS_BP15': CDS_PINID='VSS_BP15';
NODE_NAME     U25 BP17
 '@T6G_MB_LIB.T6G(SCH_1):PAGE32_I13@PURE_QUANTA.GENOA_SP5(CHIPS)':
 'VSS_BP17': CDS_PINID='VSS_BP17';
NODE_NAME     U25 BP19
 '@T6G_MB_LIB.T6G(SCH_1):PAGE32_I13@PURE_QUANTA.GENOA_SP5(CHIPS)':
 'VSS_BP19': CDS_PINID='VSS_BP19';
NODE_NAME     U25 BP23
 '@T6G_MB_LIB.T6G(SCH_1):PAGE32_I13@PURE_QUANTA.GENOA_SP5(CHIPS)':
 'VSS_BP23': CDS_PINID='VSS_BP23';
NODE_NAME     U25 BP25
 '@T6G_MB_LIB.T6G(SCH_1):PAGE32_I13@PURE_QUANTA.GENOA_SP5(CHIPS)':
 'VSS_BP25': CDS_PINID='VSS_BP25';
NODE_NAME     U25 BP27
 '@T6G_MB_LIB.T6G(SCH_1):PAGE32_I13@PURE_QUANTA.GENOA_SP5(CHIPS)':
 'VSS_BP27': CDS_PINID='VSS_BP27';
NODE_NAME     U25 BP29
 '@T6G_MB_LIB.T6G(SCH_1):PAGE32_I13@PURE_QUANTA.GENOA_SP5(CHIPS)':
 'VSS_BP29': CDS_PINID='VSS_BP29';
NODE_NAME     U25 BP31
 '@T6G_MB_LIB.T6G(SCH_1):PAGE32_I13@PURE_QUANTA.GENOA_SP5(CHIPS)':
 'VSS_BP31': CDS_PINID='VSS_BP31';
NODE_NAME     U25 BP33
 '@T6G_MB_LIB.T6G(SCH_1):PAGE32_I13@PURE_QUANTA.GENOA_SP5(CHIPS)':
 'VSS_BP33': CDS_PINID='VSS_BP33';
NODE_NAME     U25 BP35
 '@T6G_MB_LIB.T6G(SCH_1):PAGE32_I13@PURE_QUANTA.GENOA_SP5(CHIPS)':
 'VSS_BP35': CDS_PINID='VSS_BP35';
NODE_NAME     U25 BP37
 '@T6G_MB_LIB.T6G(SCH_1):PAGE32_I13@PURE_QUANTA.GENOA_SP5(CHIPS)':
 'VSS_BP37': CDS_PINID='VSS_BP37';
NODE_NAME     U25 BP40
 '@T6G_MB_LIB.T6G(SCH_1):PAGE32_I13@PURE_QUANTA.GENOA_SP5(CHIPS)':
 'VSS_BP40': CDS_PINID='VSS_BP40';
NODE_NAME     U25 BP42
 '@T6G_MB_LIB.T6G(SCH_1):PAGE32_I13@PURE_QUANTA.GENOA_SP5(CHIPS)':
 'VSS_BP42': CDS_PINID='VSS_BP42';
NODE_NAME     U25 BP44
 '@T6G_MB_LIB.T6G(SCH_1):PAGE32_I13@PURE_QUANTA.GENOA_SP5(CHIPS)':
 'VSS_BP44': CDS_PINID='VSS_BP44';
NODE_NAME     U25 BP46
 '@T6G_MB_LIB.T6G(SCH_1):PAGE32_I13@PURE_QUANTA.GENOA_SP5(CHIPS)':
 'VSS_BP46': CDS_PINID='VSS_BP46';
NODE_NAME     U25 BP48
 '@T6G_MB_LIB.T6G(SCH_1):PAGE32_I13@PURE_QUANTA.GENOA_SP5(CHIPS)':
 'VSS_BP48': CDS_PINID='VSS_BP48';
NODE_NAME     U25 BP50
 '@T6G_MB_LIB.T6G(SCH_1):PAGE32_I13@PURE_QUANTA.GENOA_SP5(CHIPS)':
 'VSS_BP50': CDS_PINID='VSS_BP50';
NODE_NAME     U25 BP52
 '@T6G_MB_LIB.T6G(SCH_1):PAGE32_I13@PURE_QUANTA.GENOA_SP5(CHIPS)':
 'VSS_BP52': CDS_PINID='VSS_BP52';
NODE_NAME     U25 BP54
 '@T6G_MB_LIB.T6G(SCH_1):PAGE32_I13@PURE_QUANTA.GENOA_SP5(CHIPS)':
 'VSS_BP54': CDS_PINID='VSS_BP54';
NODE_NAME     U25 BP57
 '@T6G_MB_LIB.T6G(SCH_1):PAGE32_I13@PURE_QUANTA.GENOA_SP5(CHIPS)':
 'VSS_BP57': CDS_PINID='VSS_BP57';
NODE_NAME     U25 BP59
 '@T6G_MB_LIB.T6G(SCH_1):PAGE32_I13@PURE_QUANTA.GENOA_SP5(CHIPS)':
 'VSS_BP59': CDS_PINID='VSS_BP59';
NODE_NAME     U25 BP61
 '@T6G_MB_LIB.T6G(SCH_1):PAGE32_I13@PURE_QUANTA.GENOA_SP5(CHIPS)':
 'VSS_BP61': CDS_PINID='VSS_BP61';
NODE_NAME     U25 BP64
 '@T6G_MB_LIB.T6G(SCH_1):PAGE32_I13@PURE_QUANTA.GENOA_SP5(CHIPS)':
 'VSS_BP64': CDS_PINID='VSS_BP64';
NODE_NAME     U25 BP66
 '@T6G_MB_LIB.T6G(SCH_1):PAGE32_I13@PURE_QUANTA.GENOA_SP5(CHIPS)':
 'VSS_BP66': CDS_PINID='VSS_BP66';
NODE_NAME     U25 BP68
 '@T6G_MB_LIB.T6G(SCH_1):PAGE32_I13@PURE_QUANTA.GENOA_SP5(CHIPS)':
 'VSS_BP68': CDS_PINID='VSS_BP68';
NODE_NAME     U25 BP71
 '@T6G_MB_LIB.T6G(SCH_1):PAGE32_I13@PURE_QUANTA.GENOA_SP5(CHIPS)':
 'VSS_BP71': CDS_PINID='VSS_BP71';
NODE_NAME     U25 BP73
 '@T6G_MB_LIB.T6G(SCH_1):PAGE32_I13@PURE_QUANTA.GENOA_SP5(CHIPS)':
 'VSS_BP73': CDS_PINID='VSS_BP73';
NODE_NAME     U25 BR1
 '@T6G_MB_LIB.T6G(SCH_1):PAGE32_I13@PURE_QUANTA.GENOA_SP5(CHIPS)':
 'VSS_BR1': CDS_PINID='VSS_BR1';
NODE_NAME     U25 BR3
 '@T6G_MB_LIB.T6G(SCH_1):PAGE32_I13@PURE_QUANTA.GENOA_SP5(CHIPS)':
 'VSS_BR3': CDS_PINID='VSS_BR3';
NODE_NAME     U25 BR6
 '@T6G_MB_LIB.T6G(SCH_1):PAGE32_I13@PURE_QUANTA.GENOA_SP5(CHIPS)':
 'VSS_BR6': CDS_PINID='VSS_BR6';
NODE_NAME     U25 BR7
 '@T6G_MB_LIB.T6G(SCH_1):PAGE32_I13@PURE_QUANTA.GENOA_SP5(CHIPS)':
 'VSS_BR7': CDS_PINID='VSS_BR7';
NODE_NAME     U25 BR8
 '@T6G_MB_LIB.T6G(SCH_1):PAGE32_I13@PURE_QUANTA.GENOA_SP5(CHIPS)':
 'VSS_BR8': CDS_PINID='VSS_BR8';
NODE_NAME     U25 BR10
 '@T6G_MB_LIB.T6G(SCH_1):PAGE32_I13@PURE_QUANTA.GENOA_SP5(CHIPS)':
 'VSS_BR10': CDS_PINID='VSS_BR10';
NODE_NAME     U25 BR13
 '@T6G_MB_LIB.T6G(SCH_1):PAGE32_I13@PURE_QUANTA.GENOA_SP5(CHIPS)':
 'VSS_BR13': CDS_PINID='VSS_BR13';
NODE_NAME     U25 BR14
 '@T6G_MB_LIB.T6G(SCH_1):PAGE32_I13@PURE_QUANTA.GENOA_SP5(CHIPS)':
 'VSS_BR14': CDS_PINID='VSS_BR14';
NODE_NAME     U25 BR15
 '@T6G_MB_LIB.T6G(SCH_1):PAGE32_I13@PURE_QUANTA.GENOA_SP5(CHIPS)':
 'VSS_BR15': CDS_PINID='VSS_BR15';
NODE_NAME     U25 BR17
 '@T6G_MB_LIB.T6G(SCH_1):PAGE32_I13@PURE_QUANTA.GENOA_SP5(CHIPS)':
 'VSS_BR17': CDS_PINID='VSS_BR17';
NODE_NAME     U25 BR20
 '@T6G_MB_LIB.T6G(SCH_1):PAGE32_I13@PURE_QUANTA.GENOA_SP5(CHIPS)':
 'VSS_BR20': CDS_PINID='VSS_BR20';
NODE_NAME     U25 BR21
 '@T6G_MB_LIB.T6G(SCH_1):PAGE32_I13@PURE_QUANTA.GENOA_SP5(CHIPS)':
 'VSS_BR21': CDS_PINID='VSS_BR21';
NODE_NAME     U25 BR22
 '@T6G_MB_LIB.T6G(SCH_1):PAGE32_I13@PURE_QUANTA.GENOA_SP5(CHIPS)':
 'VSS_BR22': CDS_PINID='VSS_BR22';
NODE_NAME     U25 BR24
 '@T6G_MB_LIB.T6G(SCH_1):PAGE32_I13@PURE_QUANTA.GENOA_SP5(CHIPS)':
 'VSS_BR24': CDS_PINID='VSS_BR24';
NODE_NAME     U25 BR26
 '@T6G_MB_LIB.T6G(SCH_1):PAGE32_I13@PURE_QUANTA.GENOA_SP5(CHIPS)':
 'VSS_BR26': CDS_PINID='VSS_BR26';
NODE_NAME     U25 BR28
 '@T6G_MB_LIB.T6G(SCH_1):PAGE32_I13@PURE_QUANTA.GENOA_SP5(CHIPS)':
 'VSS_BR28': CDS_PINID='VSS_BR28';
NODE_NAME     U25 BR30
 '@T6G_MB_LIB.T6G(SCH_1):PAGE32_I13@PURE_QUANTA.GENOA_SP5(CHIPS)':
 'VSS_BR30': CDS_PINID='VSS_BR30';
NODE_NAME     U25 BR32
 '@T6G_MB_LIB.T6G(SCH_1):PAGE32_I13@PURE_QUANTA.GENOA_SP5(CHIPS)':
 'VSS_BR32': CDS_PINID='VSS_BR32';
NODE_NAME     U25 BR34
 '@T6G_MB_LIB.T6G(SCH_1):PAGE32_I13@PURE_QUANTA.GENOA_SP5(CHIPS)':
 'VSS_BR34': CDS_PINID='VSS_BR34';
NODE_NAME     U25 BR36
 '@T6G_MB_LIB.T6G(SCH_1):PAGE32_I13@PURE_QUANTA.GENOA_SP5(CHIPS)':
 'VSS_BR36': CDS_PINID='VSS_BR36';
NODE_NAME     U25 BR41
 '@T6G_MB_LIB.T6G(SCH_1):PAGE32_I13@PURE_QUANTA.GENOA_SP5(CHIPS)':
 'VSS_BR41': CDS_PINID='VSS_BR41';
NODE_NAME     U25 BR43
 '@T6G_MB_LIB.T6G(SCH_1):PAGE32_I13@PURE_QUANTA.GENOA_SP5(CHIPS)':
 'VSS_BR43': CDS_PINID='VSS_BR43';
NODE_NAME     U25 BR45
 '@T6G_MB_LIB.T6G(SCH_1):PAGE32_I13@PURE_QUANTA.GENOA_SP5(CHIPS)':
 'VSS_BR45': CDS_PINID='VSS_BR45';
NODE_NAME     U25 BR47
 '@T6G_MB_LIB.T6G(SCH_1):PAGE32_I13@PURE_QUANTA.GENOA_SP5(CHIPS)':
 'VSS_BR47': CDS_PINID='VSS_BR47';
NODE_NAME     U25 BR49
 '@T6G_MB_LIB.T6G(SCH_1):PAGE32_I13@PURE_QUANTA.GENOA_SP5(CHIPS)':
 'VSS_BR49': CDS_PINID='VSS_BR49';
NODE_NAME     U25 BR51
 '@T6G_MB_LIB.T6G(SCH_1):PAGE32_I13@PURE_QUANTA.GENOA_SP5(CHIPS)':
 'VSS_BR51': CDS_PINID='VSS_BR51';
NODE_NAME     U25 BR55
 '@T6G_MB_LIB.T6G(SCH_1):PAGE32_I13@PURE_QUANTA.GENOA_SP5(CHIPS)':
 'VSS_BR55': CDS_PINID='VSS_BR55';
NODE_NAME     U25 BR56
 '@T6G_MB_LIB.T6G(SCH_1):PAGE32_I13@PURE_QUANTA.GENOA_SP5(CHIPS)':
 'VSS_BR56': CDS_PINID='VSS_BR56';
NODE_NAME     U25 BR59
 '@T6G_MB_LIB.T6G(SCH_1):PAGE32_I13@PURE_QUANTA.GENOA_SP5(CHIPS)':
 'VSS_BR59': CDS_PINID='VSS_BR59';
NODE_NAME     U25 BR61
 '@T6G_MB_LIB.T6G(SCH_1):PAGE32_I13@PURE_QUANTA.GENOA_SP5(CHIPS)':
 'VSS_BR61': CDS_PINID='VSS_BR61';
NODE_NAME     U25 BR62
 '@T6G_MB_LIB.T6G(SCH_1):PAGE32_I13@PURE_QUANTA.GENOA_SP5(CHIPS)':
 'VSS_BR62': CDS_PINID='VSS_BR62';
NODE_NAME     U25 BR63
 '@T6G_MB_LIB.T6G(SCH_1):PAGE32_I13@PURE_QUANTA.GENOA_SP5(CHIPS)':
 'VSS_BR63': CDS_PINID='VSS_BR63';
NODE_NAME     U25 BR66
 '@T6G_MB_LIB.T6G(SCH_1):PAGE32_I13@PURE_QUANTA.GENOA_SP5(CHIPS)':
 'VSS_BR66': CDS_PINID='VSS_BR66';
NODE_NAME     U25 BR68
 '@T6G_MB_LIB.T6G(SCH_1):PAGE32_I13@PURE_QUANTA.GENOA_SP5(CHIPS)':
 'VSS_BR68': CDS_PINID='VSS_BR68';
NODE_NAME     U25 BR69
 '@T6G_MB_LIB.T6G(SCH_1):PAGE32_I13@PURE_QUANTA.GENOA_SP5(CHIPS)':
 'VSS_BR69': CDS_PINID='VSS_BR69';
NODE_NAME     U25 BR70
 '@T6G_MB_LIB.T6G(SCH_1):PAGE32_I13@PURE_QUANTA.GENOA_SP5(CHIPS)':
 'VSS_BR70': CDS_PINID='VSS_BR70';
NODE_NAME     U25 BR73
 '@T6G_MB_LIB.T6G(SCH_1):PAGE32_I13@PURE_QUANTA.GENOA_SP5(CHIPS)':
 'VSS_BR73': CDS_PINID='VSS_BR73';
NODE_NAME     U25 BR75
 '@T6G_MB_LIB.T6G(SCH_1):PAGE32_I13@PURE_QUANTA.GENOA_SP5(CHIPS)':
 'VSS_BR75': CDS_PINID='VSS_BR75';
NODE_NAME     U25 BT3
 '@T6G_MB_LIB.T6G(SCH_1):PAGE32_I13@PURE_QUANTA.GENOA_SP5(CHIPS)':
 'VSS_BT3': CDS_PINID='VSS_BT3';
NODE_NAME     U25 BT4
 '@T6G_MB_LIB.T6G(SCH_1):PAGE32_I13@PURE_QUANTA.GENOA_SP5(CHIPS)':
 'VSS_BT4': CDS_PINID='VSS_BT4';
NODE_NAME     U25 BT5
 '@T6G_MB_LIB.T6G(SCH_1):PAGE32_I13@PURE_QUANTA.GENOA_SP5(CHIPS)':
 'VSS_BT5': CDS_PINID='VSS_BT5';
NODE_NAME     U25 BT7
 '@T6G_MB_LIB.T6G(SCH_1):PAGE32_I13@PURE_QUANTA.GENOA_SP5(CHIPS)':
 'VSS_BT7': CDS_PINID='VSS_BT7';
NODE_NAME     U25 BT8
 '@T6G_MB_LIB.T6G(SCH_1):PAGE32_I13@PURE_QUANTA.GENOA_SP5(CHIPS)':
 'VSS_BT8': CDS_PINID='VSS_BT8';
NODE_NAME     U25 BT10
 '@T6G_MB_LIB.T6G(SCH_1):PAGE32_I13@PURE_QUANTA.GENOA_SP5(CHIPS)':
 'VSS_BT10': CDS_PINID='VSS_BT10';
NODE_NAME     U25 BT11
 '@T6G_MB_LIB.T6G(SCH_1):PAGE32_I13@PURE_QUANTA.GENOA_SP5(CHIPS)':
 'VSS_BT11': CDS_PINID='VSS_BT11';
NODE_NAME     U25 BT12
 '@T6G_MB_LIB.T6G(SCH_1):PAGE32_I13@PURE_QUANTA.GENOA_SP5(CHIPS)':
 'VSS_BT12': CDS_PINID='VSS_BT12';
NODE_NAME     U25 BT14
 '@T6G_MB_LIB.T6G(SCH_1):PAGE32_I13@PURE_QUANTA.GENOA_SP5(CHIPS)':
 'VSS_BT14': CDS_PINID='VSS_BT14';
NODE_NAME     U25 BT15
 '@T6G_MB_LIB.T6G(SCH_1):PAGE32_I13@PURE_QUANTA.GENOA_SP5(CHIPS)':
 'VSS_BT15': CDS_PINID='VSS_BT15';
NODE_NAME     U25 BT17
 '@T6G_MB_LIB.T6G(SCH_1):PAGE32_I13@PURE_QUANTA.GENOA_SP5(CHIPS)':
 'VSS_BT17': CDS_PINID='VSS_BT17';
NODE_NAME     U25 BT18
 '@T6G_MB_LIB.T6G(SCH_1):PAGE32_I13@PURE_QUANTA.GENOA_SP5(CHIPS)':
 'VSS_BT18': CDS_PINID='VSS_BT18';
NODE_NAME     U25 BT19
 '@T6G_MB_LIB.T6G(SCH_1):PAGE32_I13@PURE_QUANTA.GENOA_SP5(CHIPS)':
 'VSS_BT19': CDS_PINID='VSS_BT19';
NODE_NAME     U25 BT21
 '@T6G_MB_LIB.T6G(SCH_1):PAGE32_I13@PURE_QUANTA.GENOA_SP5(CHIPS)':
 'VSS_BT21': CDS_PINID='VSS_BT21';
NODE_NAME     U25 BT22
 '@T6G_MB_LIB.T6G(SCH_1):PAGE32_I13@PURE_QUANTA.GENOA_SP5(CHIPS)':
 'VSS_BT22': CDS_PINID='VSS_BT22';
NODE_NAME     U25 BT25
 '@T6G_MB_LIB.T6G(SCH_1):PAGE32_I13@PURE_QUANTA.GENOA_SP5(CHIPS)':
 'VSS_BT25': CDS_PINID='VSS_BT25';
NODE_NAME     U25 BT28
 '@T6G_MB_LIB.T6G(SCH_1):PAGE32_I13@PURE_QUANTA.GENOA_SP5(CHIPS)':
 'VSS_BT28': CDS_PINID='VSS_BT28';
NODE_NAME     U25 BT31
 '@T6G_MB_LIB.T6G(SCH_1):PAGE32_I13@PURE_QUANTA.GENOA_SP5(CHIPS)':
 'VSS_BT31': CDS_PINID='VSS_BT31';
NODE_NAME     U25 BT34
 '@T6G_MB_LIB.T6G(SCH_1):PAGE32_I13@PURE_QUANTA.GENOA_SP5(CHIPS)':
 'VSS_BT34': CDS_PINID='VSS_BT34';
NODE_NAME     U25 BT37
 '@T6G_MB_LIB.T6G(SCH_1):PAGE32_I13@PURE_QUANTA.GENOA_SP5(CHIPS)':
 'VSS_BT37': CDS_PINID='VSS_BT37';
NODE_NAME     U25 BT39
 '@T6G_MB_LIB.T6G(SCH_1):PAGE32_I13@PURE_QUANTA.GENOA_SP5(CHIPS)':
 'VSS_BT39': CDS_PINID='VSS_BT39';
NODE_NAME     U25 BT42
 '@T6G_MB_LIB.T6G(SCH_1):PAGE32_I13@PURE_QUANTA.GENOA_SP5(CHIPS)':
 'VSS_BT42': CDS_PINID='VSS_BT42';
NODE_NAME     U25 BT45
 '@T6G_MB_LIB.T6G(SCH_1):PAGE32_I13@PURE_QUANTA.GENOA_SP5(CHIPS)':
 'VSS_BT45': CDS_PINID='VSS_BT45';
NODE_NAME     U25 BT48
 '@T6G_MB_LIB.T6G(SCH_1):PAGE32_I13@PURE_QUANTA.GENOA_SP5(CHIPS)':
 'VSS_BT48': CDS_PINID='VSS_BT48';
NODE_NAME     U25 BT51
 '@T6G_MB_LIB.T6G(SCH_1):PAGE32_I13@PURE_QUANTA.GENOA_SP5(CHIPS)':
 'VSS_BT51': CDS_PINID='VSS_BT51';
NODE_NAME     U25 BT54
 '@T6G_MB_LIB.T6G(SCH_1):PAGE32_I13@PURE_QUANTA.GENOA_SP5(CHIPS)':
 'VSS_BT54': CDS_PINID='VSS_BT54';
NODE_NAME     U25 BT55
 '@T6G_MB_LIB.T6G(SCH_1):PAGE32_I13@PURE_QUANTA.GENOA_SP5(CHIPS)':
 'VSS_BT55': CDS_PINID='VSS_BT55';
NODE_NAME     U25 BT57
 '@T6G_MB_LIB.T6G(SCH_1):PAGE32_I13@PURE_QUANTA.GENOA_SP5(CHIPS)':
 'VSS_BT57': CDS_PINID='VSS_BT57';
NODE_NAME     U25 BT58
 '@T6G_MB_LIB.T6G(SCH_1):PAGE32_I13@PURE_QUANTA.GENOA_SP5(CHIPS)':
 'VSS_BT58': CDS_PINID='VSS_BT58';
NODE_NAME     U25 BT59
 '@T6G_MB_LIB.T6G(SCH_1):PAGE32_I13@PURE_QUANTA.GENOA_SP5(CHIPS)':
 'VSS_BT59': CDS_PINID='VSS_BT59';
NODE_NAME     U25 BT61
 '@T6G_MB_LIB.T6G(SCH_1):PAGE32_I13@PURE_QUANTA.GENOA_SP5(CHIPS)':
 'VSS_BT61': CDS_PINID='VSS_BT61';
NODE_NAME     U25 BT62
 '@T6G_MB_LIB.T6G(SCH_1):PAGE32_I13@PURE_QUANTA.GENOA_SP5(CHIPS)':
 'VSS_BT62': CDS_PINID='VSS_BT62';
NODE_NAME     U25 BT64
 '@T6G_MB_LIB.T6G(SCH_1):PAGE32_I13@PURE_QUANTA.GENOA_SP5(CHIPS)':
 'VSS_BT64': CDS_PINID='VSS_BT64';
NODE_NAME     U25 BT65
 '@T6G_MB_LIB.T6G(SCH_1):PAGE32_I13@PURE_QUANTA.GENOA_SP5(CHIPS)':
 'VSS_BT65': CDS_PINID='VSS_BT65';
NODE_NAME     U25 BT66
 '@T6G_MB_LIB.T6G(SCH_1):PAGE32_I13@PURE_QUANTA.GENOA_SP5(CHIPS)':
 'VSS_BT66': CDS_PINID='VSS_BT66';
NODE_NAME     U25 BT68
 '@T6G_MB_LIB.T6G(SCH_1):PAGE32_I13@PURE_QUANTA.GENOA_SP5(CHIPS)':
 'VSS_BT68': CDS_PINID='VSS_BT68';
NODE_NAME     U25 BT69
 '@T6G_MB_LIB.T6G(SCH_1):PAGE32_I13@PURE_QUANTA.GENOA_SP5(CHIPS)':
 'VSS_BT69': CDS_PINID='VSS_BT69';
NODE_NAME     U25 BT71
 '@T6G_MB_LIB.T6G(SCH_1):PAGE32_I13@PURE_QUANTA.GENOA_SP5(CHIPS)':
 'VSS_BT71': CDS_PINID='VSS_BT71';
NODE_NAME     U25 BT72
 '@T6G_MB_LIB.T6G(SCH_1):PAGE32_I13@PURE_QUANTA.GENOA_SP5(CHIPS)':
 'VSS_BT72': CDS_PINID='VSS_BT72';
NODE_NAME     U25 BT73
 '@T6G_MB_LIB.T6G(SCH_1):PAGE32_I13@PURE_QUANTA.GENOA_SP5(CHIPS)':
 'VSS_BT73': CDS_PINID='VSS_BT73';
NODE_NAME     U25 BU1
 '@T6G_MB_LIB.T6G(SCH_1):PAGE32_I13@PURE_QUANTA.GENOA_SP5(CHIPS)':
 'VSS_BU1': CDS_PINID='VSS_BU1';
NODE_NAME     U25 BU4
 '@T6G_MB_LIB.T6G(SCH_1):PAGE32_I13@PURE_QUANTA.GENOA_SP5(CHIPS)':
 'VSS_BU4': CDS_PINID='VSS_BU4';
NODE_NAME     U25 BU6
 '@T6G_MB_LIB.T6G(SCH_1):PAGE32_I13@PURE_QUANTA.GENOA_SP5(CHIPS)':
 'VSS_BU6': CDS_PINID='VSS_BU6';
NODE_NAME     U25 BU8
 '@T6G_MB_LIB.T6G(SCH_1):PAGE32_I13@PURE_QUANTA.GENOA_SP5(CHIPS)':
 'VSS_BU8': CDS_PINID='VSS_BU8';
NODE_NAME     U25 BU11
 '@T6G_MB_LIB.T6G(SCH_1):PAGE32_I13@PURE_QUANTA.GENOA_SP5(CHIPS)':
 'VSS_BU11': CDS_PINID='VSS_BU11';
NODE_NAME     U25 BU13
 '@T6G_MB_LIB.T6G(SCH_1):PAGE32_I13@PURE_QUANTA.GENOA_SP5(CHIPS)':
 'VSS_BU13': CDS_PINID='VSS_BU13';
NODE_NAME     U25 BU15
 '@T6G_MB_LIB.T6G(SCH_1):PAGE32_I13@PURE_QUANTA.GENOA_SP5(CHIPS)':
 'VSS_BU15': CDS_PINID='VSS_BU15';
NODE_NAME     U25 BU18
 '@T6G_MB_LIB.T6G(SCH_1):PAGE32_I13@PURE_QUANTA.GENOA_SP5(CHIPS)':
 'VSS_BU18': CDS_PINID='VSS_BU18';
NODE_NAME     U25 BU20
 '@T6G_MB_LIB.T6G(SCH_1):PAGE32_I13@PURE_QUANTA.GENOA_SP5(CHIPS)':
 'VSS_BU20': CDS_PINID='VSS_BU20';
NODE_NAME     U25 BU22
 '@T6G_MB_LIB.T6G(SCH_1):PAGE32_I13@PURE_QUANTA.GENOA_SP5(CHIPS)':
 'VSS_BU22': CDS_PINID='VSS_BU22';
NODE_NAME     U25 BU25
 '@T6G_MB_LIB.T6G(SCH_1):PAGE32_I13@PURE_QUANTA.GENOA_SP5(CHIPS)':
 'VSS_BU25': CDS_PINID='VSS_BU25';
NODE_NAME     U25 BU28
 '@T6G_MB_LIB.T6G(SCH_1):PAGE32_I13@PURE_QUANTA.GENOA_SP5(CHIPS)':
 'VSS_BU28': CDS_PINID='VSS_BU28';
NODE_NAME     U25 BU31
 '@T6G_MB_LIB.T6G(SCH_1):PAGE32_I13@PURE_QUANTA.GENOA_SP5(CHIPS)':
 'VSS_BU31': CDS_PINID='VSS_BU31';
NODE_NAME     U25 BU34
 '@T6G_MB_LIB.T6G(SCH_1):PAGE32_I13@PURE_QUANTA.GENOA_SP5(CHIPS)':
 'VSS_BU34': CDS_PINID='VSS_BU34';
NODE_NAME     U25 BU35
 '@T6G_MB_LIB.T6G(SCH_1):PAGE32_I13@PURE_QUANTA.GENOA_SP5(CHIPS)':
 'VSS_BU35': CDS_PINID='VSS_BU35';
NODE_NAME     U25 BU36
 '@T6G_MB_LIB.T6G(SCH_1):PAGE32_I13@PURE_QUANTA.GENOA_SP5(CHIPS)':
 'VSS_BU36': CDS_PINID='VSS_BU36';
NODE_NAME     U25 BU40
 '@T6G_MB_LIB.T6G(SCH_1):PAGE32_I13@PURE_QUANTA.GENOA_SP5(CHIPS)':
 'VSS_BU40': CDS_PINID='VSS_BU40';
NODE_NAME     U25 BU41
 '@T6G_MB_LIB.T6G(SCH_1):PAGE32_I13@PURE_QUANTA.GENOA_SP5(CHIPS)':
 'VSS_BU41': CDS_PINID='VSS_BU41';
NODE_NAME     U25 BU42
 '@T6G_MB_LIB.T6G(SCH_1):PAGE32_I13@PURE_QUANTA.GENOA_SP5(CHIPS)':
 'VSS_BU42': CDS_PINID='VSS_BU42';
NODE_NAME     U25 BU45
 '@T6G_MB_LIB.T6G(SCH_1):PAGE32_I13@PURE_QUANTA.GENOA_SP5(CHIPS)':
 'VSS_BU45': CDS_PINID='VSS_BU45';
NODE_NAME     U25 BU48
 '@T6G_MB_LIB.T6G(SCH_1):PAGE32_I13@PURE_QUANTA.GENOA_SP5(CHIPS)':
 'VSS_BU48': CDS_PINID='VSS_BU48';
NODE_NAME     U25 BU51
 '@T6G_MB_LIB.T6G(SCH_1):PAGE32_I13@PURE_QUANTA.GENOA_SP5(CHIPS)':
 'VSS_BU51': CDS_PINID='VSS_BU51';
NODE_NAME     U25 BU54
 '@T6G_MB_LIB.T6G(SCH_1):PAGE32_I13@PURE_QUANTA.GENOA_SP5(CHIPS)':
 'VSS_BU54': CDS_PINID='VSS_BU54';
NODE_NAME     U25 BU56
 '@T6G_MB_LIB.T6G(SCH_1):PAGE32_I13@PURE_QUANTA.GENOA_SP5(CHIPS)':
 'VSS_BU56': CDS_PINID='VSS_BU56';
NODE_NAME     U25 BU58
 '@T6G_MB_LIB.T6G(SCH_1):PAGE32_I13@PURE_QUANTA.GENOA_SP5(CHIPS)':
 'VSS_BU58': CDS_PINID='VSS_BU58';
NODE_NAME     U25 BU61
 '@T6G_MB_LIB.T6G(SCH_1):PAGE32_I13@PURE_QUANTA.GENOA_SP5(CHIPS)':
 'VSS_BU61': CDS_PINID='VSS_BU61';
NODE_NAME     U25 BU63
 '@T6G_MB_LIB.T6G(SCH_1):PAGE32_I13@PURE_QUANTA.GENOA_SP5(CHIPS)':
 'VSS_BU63': CDS_PINID='VSS_BU63';
NODE_NAME     U25 BU65
 '@T6G_MB_LIB.T6G(SCH_1):PAGE32_I13@PURE_QUANTA.GENOA_SP5(CHIPS)':
 'VSS_BU65': CDS_PINID='VSS_BU65';
NODE_NAME     U25 BU68
 '@T6G_MB_LIB.T6G(SCH_1):PAGE32_I13@PURE_QUANTA.GENOA_SP5(CHIPS)':
 'VSS_BU68': CDS_PINID='VSS_BU68';
NODE_NAME     U25 BU70
 '@T6G_MB_LIB.T6G(SCH_1):PAGE32_I13@PURE_QUANTA.GENOA_SP5(CHIPS)':
 'VSS_BU70': CDS_PINID='VSS_BU70';
NODE_NAME     U25 BU72
 '@T6G_MB_LIB.T6G(SCH_1):PAGE32_I13@PURE_QUANTA.GENOA_SP5(CHIPS)':
 'VSS_BU72': CDS_PINID='VSS_BU72';
NODE_NAME     U25 BU75
 '@T6G_MB_LIB.T6G(SCH_1):PAGE32_I13@PURE_QUANTA.GENOA_SP5(CHIPS)':
 'VSS_BU75': CDS_PINID='VSS_BU75';
NODE_NAME     U25 BV3
 '@T6G_MB_LIB.T6G(SCH_1):PAGE32_I13@PURE_QUANTA.GENOA_SP5(CHIPS)':
 'VSS_BV3': CDS_PINID='VSS_BV3';
NODE_NAME     U25 BV8
 '@T6G_MB_LIB.T6G(SCH_1):PAGE32_I13@PURE_QUANTA.GENOA_SP5(CHIPS)':
 'VSS_BV8': CDS_PINID='VSS_BV8';
NODE_NAME     U25 BV10
 '@T6G_MB_LIB.T6G(SCH_1):PAGE32_I13@PURE_QUANTA.GENOA_SP5(CHIPS)':
 'VSS_BV10': CDS_PINID='VSS_BV10';
NODE_NAME     U25 BV15
 '@T6G_MB_LIB.T6G(SCH_1):PAGE32_I13@PURE_QUANTA.GENOA_SP5(CHIPS)':
 'VSS_BV15': CDS_PINID='VSS_BV15';
NODE_NAME     U25 BV17
 '@T6G_MB_LIB.T6G(SCH_1):PAGE32_I13@PURE_QUANTA.GENOA_SP5(CHIPS)':
 'VSS_BV17': CDS_PINID='VSS_BV17';
NODE_NAME     U25 BV23
 '@T6G_MB_LIB.T6G(SCH_1):PAGE32_I13@PURE_QUANTA.GENOA_SP5(CHIPS)':
 'VSS_BV23': CDS_PINID='VSS_BV23';
NODE_NAME     U25 BV24
 '@T6G_MB_LIB.T6G(SCH_1):PAGE32_I13@PURE_QUANTA.GENOA_SP5(CHIPS)':
 'VSS_BV24': CDS_PINID='VSS_BV24';
NODE_NAME     U25 BV25
 '@T6G_MB_LIB.T6G(SCH_1):PAGE32_I13@PURE_QUANTA.GENOA_SP5(CHIPS)':
 'VSS_BV25': CDS_PINID='VSS_BV25';
NODE_NAME     U25 BV26
 '@T6G_MB_LIB.T6G(SCH_1):PAGE32_I13@PURE_QUANTA.GENOA_SP5(CHIPS)':
 'VSS_BV26': CDS_PINID='VSS_BV26';
NODE_NAME     U25 BV27
 '@T6G_MB_LIB.T6G(SCH_1):PAGE32_I13@PURE_QUANTA.GENOA_SP5(CHIPS)':
 'VSS_BV27': CDS_PINID='VSS_BV27';
NODE_NAME     U25 BV28
 '@T6G_MB_LIB.T6G(SCH_1):PAGE32_I13@PURE_QUANTA.GENOA_SP5(CHIPS)':
 'VSS_BV28': CDS_PINID='VSS_BV28';
NODE_NAME     U25 BV29
 '@T6G_MB_LIB.T6G(SCH_1):PAGE32_I13@PURE_QUANTA.GENOA_SP5(CHIPS)':
 'VSS_BV29': CDS_PINID='VSS_BV29';
NODE_NAME     U25 BV30
 '@T6G_MB_LIB.T6G(SCH_1):PAGE32_I13@PURE_QUANTA.GENOA_SP5(CHIPS)':
 'VSS_BV30': CDS_PINID='VSS_BV30';
NODE_NAME     U25 BV31
 '@T6G_MB_LIB.T6G(SCH_1):PAGE32_I13@PURE_QUANTA.GENOA_SP5(CHIPS)':
 'VSS_BV31': CDS_PINID='VSS_BV31';
NODE_NAME     U25 BV32
 '@T6G_MB_LIB.T6G(SCH_1):PAGE32_I13@PURE_QUANTA.GENOA_SP5(CHIPS)':
 'VSS_BV32': CDS_PINID='VSS_BV32';
NODE_NAME     U25 BV33
 '@T6G_MB_LIB.T6G(SCH_1):PAGE32_I13@PURE_QUANTA.GENOA_SP5(CHIPS)':
 'VSS_BV33': CDS_PINID='VSS_BV33';
NODE_NAME     U25 BV34
 '@T6G_MB_LIB.T6G(SCH_1):PAGE32_I13@PURE_QUANTA.GENOA_SP5(CHIPS)':
 'VSS_BV34': CDS_PINID='VSS_BV34';
NODE_NAME     U25 BV37
 '@T6G_MB_LIB.T6G(SCH_1):PAGE32_I13@PURE_QUANTA.GENOA_SP5(CHIPS)':
 'VSS_BV37': CDS_PINID='VSS_BV37';
NODE_NAME     U25 BV39
 '@T6G_MB_LIB.T6G(SCH_1):PAGE32_I13@PURE_QUANTA.GENOA_SP5(CHIPS)':
 'VSS_BV39': CDS_PINID='VSS_BV39';
NODE_NAME     U25 BV43
 '@T6G_MB_LIB.T6G(SCH_1):PAGE32_I13@PURE_QUANTA.GENOA_SP5(CHIPS)':
 'VSS_BV43': CDS_PINID='VSS_BV43';
NODE_NAME     U25 BV44
 '@T6G_MB_LIB.T6G(SCH_1):PAGE32_I13@PURE_QUANTA.GENOA_SP5(CHIPS)':
 'VSS_BV44': CDS_PINID='VSS_BV44';
NODE_NAME     U25 BV45
 '@T6G_MB_LIB.T6G(SCH_1):PAGE32_I13@PURE_QUANTA.GENOA_SP5(CHIPS)':
 'VSS_BV45': CDS_PINID='VSS_BV45';
NODE_NAME     U25 BV46
 '@T6G_MB_LIB.T6G(SCH_1):PAGE32_I14@PURE_QUANTA.GENOA_SP5(CHIPS)':
 'VSS_BV46': CDS_PINID='VSS_BV46';
NODE_NAME     U25 BV47
 '@T6G_MB_LIB.T6G(SCH_1):PAGE32_I14@PURE_QUANTA.GENOA_SP5(CHIPS)':
 'VSS_BV47': CDS_PINID='VSS_BV47';
NODE_NAME     U25 BV48
 '@T6G_MB_LIB.T6G(SCH_1):PAGE32_I14@PURE_QUANTA.GENOA_SP5(CHIPS)':
 'VSS_BV48': CDS_PINID='VSS_BV48';
NODE_NAME     U25 BV49
 '@T6G_MB_LIB.T6G(SCH_1):PAGE32_I14@PURE_QUANTA.GENOA_SP5(CHIPS)':
 'VSS_BV49': CDS_PINID='VSS_BV49';
NODE_NAME     U25 BV50
 '@T6G_MB_LIB.T6G(SCH_1):PAGE32_I14@PURE_QUANTA.GENOA_SP5(CHIPS)':
 'VSS_BV50': CDS_PINID='VSS_BV50';
NODE_NAME     U25 BV51
 '@T6G_MB_LIB.T6G(SCH_1):PAGE32_I14@PURE_QUANTA.GENOA_SP5(CHIPS)':
 'VSS_BV51': CDS_PINID='VSS_BV51';
NODE_NAME     U25 BV52
 '@T6G_MB_LIB.T6G(SCH_1):PAGE32_I14@PURE_QUANTA.GENOA_SP5(CHIPS)':
 'VSS_BV52': CDS_PINID='VSS_BV52';
NODE_NAME     U25 BV53
 '@T6G_MB_LIB.T6G(SCH_1):PAGE32_I14@PURE_QUANTA.GENOA_SP5(CHIPS)':
 'VSS_BV53': CDS_PINID='VSS_BV53';
NODE_NAME     U25 BV59
 '@T6G_MB_LIB.T6G(SCH_1):PAGE32_I14@PURE_QUANTA.GENOA_SP5(CHIPS)':
 'VSS_BV59': CDS_PINID='VSS_BV59';
NODE_NAME     U25 BV61
 '@T6G_MB_LIB.T6G(SCH_1):PAGE32_I14@PURE_QUANTA.GENOA_SP5(CHIPS)':
 'VSS_BV61': CDS_PINID='VSS_BV61';
NODE_NAME     U25 BV66
 '@T6G_MB_LIB.T6G(SCH_1):PAGE32_I14@PURE_QUANTA.GENOA_SP5(CHIPS)':
 'VSS_BV66': CDS_PINID='VSS_BV66';
NODE_NAME     U25 BV68
 '@T6G_MB_LIB.T6G(SCH_1):PAGE32_I14@PURE_QUANTA.GENOA_SP5(CHIPS)':
 'VSS_BV68': CDS_PINID='VSS_BV68';
NODE_NAME     U25 BV73
 '@T6G_MB_LIB.T6G(SCH_1):PAGE32_I14@PURE_QUANTA.GENOA_SP5(CHIPS)':
 'VSS_BV73': CDS_PINID='VSS_BV73';
NODE_NAME     U25 BW1
 '@T6G_MB_LIB.T6G(SCH_1):PAGE32_I14@PURE_QUANTA.GENOA_SP5(CHIPS)':
 'VSS_BW1': CDS_PINID='VSS_BW1';
NODE_NAME     U25 BW4
 '@T6G_MB_LIB.T6G(SCH_1):PAGE32_I14@PURE_QUANTA.GENOA_SP5(CHIPS)':
 'VSS_BW4': CDS_PINID='VSS_BW4';
NODE_NAME     U25 BW6
 '@T6G_MB_LIB.T6G(SCH_1):PAGE32_I14@PURE_QUANTA.GENOA_SP5(CHIPS)':
 'VSS_BW6': CDS_PINID='VSS_BW6';
NODE_NAME     U25 BW8
 '@T6G_MB_LIB.T6G(SCH_1):PAGE32_I14@PURE_QUANTA.GENOA_SP5(CHIPS)':
 'VSS_BW8': CDS_PINID='VSS_BW8';
NODE_NAME     U25 BW11
 '@T6G_MB_LIB.T6G(SCH_1):PAGE32_I14@PURE_QUANTA.GENOA_SP5(CHIPS)':
 'VSS_BW11': CDS_PINID='VSS_BW11';
NODE_NAME     U25 BW13
 '@T6G_MB_LIB.T6G(SCH_1):PAGE32_I14@PURE_QUANTA.GENOA_SP5(CHIPS)':
 'VSS_BW13': CDS_PINID='VSS_BW13';
NODE_NAME     U25 BW15
 '@T6G_MB_LIB.T6G(SCH_1):PAGE32_I14@PURE_QUANTA.GENOA_SP5(CHIPS)':
 'VSS_BW15': CDS_PINID='VSS_BW15';
NODE_NAME     U25 BW18
 '@T6G_MB_LIB.T6G(SCH_1):PAGE32_I14@PURE_QUANTA.GENOA_SP5(CHIPS)':
 'VSS_BW18': CDS_PINID='VSS_BW18';
NODE_NAME     U25 BW20
 '@T6G_MB_LIB.T6G(SCH_1):PAGE32_I14@PURE_QUANTA.GENOA_SP5(CHIPS)':
 'VSS_BW20': CDS_PINID='VSS_BW20';
NODE_NAME     U25 BW22
 '@T6G_MB_LIB.T6G(SCH_1):PAGE32_I14@PURE_QUANTA.GENOA_SP5(CHIPS)':
 'VSS_BW22': CDS_PINID='VSS_BW22';
NODE_NAME     U25 BW28
 '@T6G_MB_LIB.T6G(SCH_1):PAGE32_I14@PURE_QUANTA.GENOA_SP5(CHIPS)':
 'VSS_BW28': CDS_PINID='VSS_BW28';
NODE_NAME     U25 BW31
 '@T6G_MB_LIB.T6G(SCH_1):PAGE32_I14@PURE_QUANTA.GENOA_SP5(CHIPS)':
 'VSS_BW31': CDS_PINID='VSS_BW31';
NODE_NAME     U25 BW34
 '@T6G_MB_LIB.T6G(SCH_1):PAGE32_I14@PURE_QUANTA.GENOA_SP5(CHIPS)':
 'VSS_BW34': CDS_PINID='VSS_BW34';
NODE_NAME     U25 BW42
 '@T6G_MB_LIB.T6G(SCH_1):PAGE32_I14@PURE_QUANTA.GENOA_SP5(CHIPS)':
 'VSS_BW42': CDS_PINID='VSS_BW42';
NODE_NAME     U25 BW45
 '@T6G_MB_LIB.T6G(SCH_1):PAGE32_I14@PURE_QUANTA.GENOA_SP5(CHIPS)':
 'VSS_BW45': CDS_PINID='VSS_BW45';
NODE_NAME     U25 BW48
 '@T6G_MB_LIB.T6G(SCH_1):PAGE32_I14@PURE_QUANTA.GENOA_SP5(CHIPS)':
 'VSS_BW48': CDS_PINID='VSS_BW48';
NODE_NAME     U25 BW51
 '@T6G_MB_LIB.T6G(SCH_1):PAGE32_I14@PURE_QUANTA.GENOA_SP5(CHIPS)':
 'VSS_BW51': CDS_PINID='VSS_BW51';
NODE_NAME     U25 BW54
 '@T6G_MB_LIB.T6G(SCH_1):PAGE32_I14@PURE_QUANTA.GENOA_SP5(CHIPS)':
 'VSS_BW54': CDS_PINID='VSS_BW54';
NODE_NAME     U25 BW56
 '@T6G_MB_LIB.T6G(SCH_1):PAGE32_I14@PURE_QUANTA.GENOA_SP5(CHIPS)':
 'VSS_BW56': CDS_PINID='VSS_BW56';
NODE_NAME     U25 BW58
 '@T6G_MB_LIB.T6G(SCH_1):PAGE32_I14@PURE_QUANTA.GENOA_SP5(CHIPS)':
 'VSS_BW58': CDS_PINID='VSS_BW58';
NODE_NAME     U25 BW61
 '@T6G_MB_LIB.T6G(SCH_1):PAGE32_I14@PURE_QUANTA.GENOA_SP5(CHIPS)':
 'VSS_BW61': CDS_PINID='VSS_BW61';
NODE_NAME     U25 BW63
 '@T6G_MB_LIB.T6G(SCH_1):PAGE32_I14@PURE_QUANTA.GENOA_SP5(CHIPS)':
 'VSS_BW63': CDS_PINID='VSS_BW63';
NODE_NAME     U25 BW65
 '@T6G_MB_LIB.T6G(SCH_1):PAGE32_I14@PURE_QUANTA.GENOA_SP5(CHIPS)':
 'VSS_BW65': CDS_PINID='VSS_BW65';
NODE_NAME     U25 BW68
 '@T6G_MB_LIB.T6G(SCH_1):PAGE32_I14@PURE_QUANTA.GENOA_SP5(CHIPS)':
 'VSS_BW68': CDS_PINID='VSS_BW68';
NODE_NAME     U25 BW70
 '@T6G_MB_LIB.T6G(SCH_1):PAGE32_I14@PURE_QUANTA.GENOA_SP5(CHIPS)':
 'VSS_BW70': CDS_PINID='VSS_BW70';
NODE_NAME     U25 BW72
 '@T6G_MB_LIB.T6G(SCH_1):PAGE32_I14@PURE_QUANTA.GENOA_SP5(CHIPS)':
 'VSS_BW72': CDS_PINID='VSS_BW72';
NODE_NAME     U25 BW75
 '@T6G_MB_LIB.T6G(SCH_1):PAGE32_I14@PURE_QUANTA.GENOA_SP5(CHIPS)':
 'VSS_BW75': CDS_PINID='VSS_BW75';
NODE_NAME     U25 BY3
 '@T6G_MB_LIB.T6G(SCH_1):PAGE32_I14@PURE_QUANTA.GENOA_SP5(CHIPS)':
 'VSS_BY3': CDS_PINID='VSS_BY3';
NODE_NAME     U25 BY5
 '@T6G_MB_LIB.T6G(SCH_1):PAGE32_I14@PURE_QUANTA.GENOA_SP5(CHIPS)':
 'VSS_BY5': CDS_PINID='VSS_BY5';
NODE_NAME     U25 BY8
 '@T6G_MB_LIB.T6G(SCH_1):PAGE32_I14@PURE_QUANTA.GENOA_SP5(CHIPS)':
 'VSS_BY8': CDS_PINID='VSS_BY8';
NODE_NAME     U25 BY10
 '@T6G_MB_LIB.T6G(SCH_1):PAGE32_I14@PURE_QUANTA.GENOA_SP5(CHIPS)':
 'VSS_BY10': CDS_PINID='VSS_BY10';
NODE_NAME     U25 BY12
 '@T6G_MB_LIB.T6G(SCH_1):PAGE32_I14@PURE_QUANTA.GENOA_SP5(CHIPS)':
 'VSS_BY12': CDS_PINID='VSS_BY12';
NODE_NAME     U25 BY15
 '@T6G_MB_LIB.T6G(SCH_1):PAGE32_I14@PURE_QUANTA.GENOA_SP5(CHIPS)':
 'VSS_BY15': CDS_PINID='VSS_BY15';
NODE_NAME     U25 BY17
 '@T6G_MB_LIB.T6G(SCH_1):PAGE32_I14@PURE_QUANTA.GENOA_SP5(CHIPS)':
 'VSS_BY17': CDS_PINID='VSS_BY17';
NODE_NAME     U25 BY19
 '@T6G_MB_LIB.T6G(SCH_1):PAGE32_I14@PURE_QUANTA.GENOA_SP5(CHIPS)':
 'VSS_BY19': CDS_PINID='VSS_BY19';
NODE_NAME     U25 BY22
 '@T6G_MB_LIB.T6G(SCH_1):PAGE32_I14@PURE_QUANTA.GENOA_SP5(CHIPS)':
 'VSS_BY22': CDS_PINID='VSS_BY22';
NODE_NAME     U25 BY25
 '@T6G_MB_LIB.T6G(SCH_1):PAGE32_I14@PURE_QUANTA.GENOA_SP5(CHIPS)':
 'VSS_BY25': CDS_PINID='VSS_BY25';
NODE_NAME     U25 BY28
 '@T6G_MB_LIB.T6G(SCH_1):PAGE32_I14@PURE_QUANTA.GENOA_SP5(CHIPS)':
 'VSS_BY28': CDS_PINID='VSS_BY28';
NODE_NAME     U25 BY31
 '@T6G_MB_LIB.T6G(SCH_1):PAGE32_I14@PURE_QUANTA.GENOA_SP5(CHIPS)':
 'VSS_BY31': CDS_PINID='VSS_BY31';
NODE_NAME     U25 BY34
 '@T6G_MB_LIB.T6G(SCH_1):PAGE32_I14@PURE_QUANTA.GENOA_SP5(CHIPS)':
 'VSS_BY34': CDS_PINID='VSS_BY34';
NODE_NAME     U25 BY37
 '@T6G_MB_LIB.T6G(SCH_1):PAGE32_I14@PURE_QUANTA.GENOA_SP5(CHIPS)':
 'VSS_BY37': CDS_PINID='VSS_BY37';
NODE_NAME     U25 BY39
 '@T6G_MB_LIB.T6G(SCH_1):PAGE32_I14@PURE_QUANTA.GENOA_SP5(CHIPS)':
 'VSS_BY39': CDS_PINID='VSS_BY39';
NODE_NAME     U25 BY42
 '@T6G_MB_LIB.T6G(SCH_1):PAGE32_I14@PURE_QUANTA.GENOA_SP5(CHIPS)':
 'VSS_BY42': CDS_PINID='VSS_BY42';
NODE_NAME     U25 BY45
 '@T6G_MB_LIB.T6G(SCH_1):PAGE32_I14@PURE_QUANTA.GENOA_SP5(CHIPS)':
 'VSS_BY45': CDS_PINID='VSS_BY45';
NODE_NAME     U25 BY48
 '@T6G_MB_LIB.T6G(SCH_1):PAGE32_I14@PURE_QUANTA.GENOA_SP5(CHIPS)':
 'VSS_BY48': CDS_PINID='VSS_BY48';
NODE_NAME     U25 BY51
 '@T6G_MB_LIB.T6G(SCH_1):PAGE32_I14@PURE_QUANTA.GENOA_SP5(CHIPS)':
 'VSS_BY51': CDS_PINID='VSS_BY51';
NODE_NAME     U25 BY54
 '@T6G_MB_LIB.T6G(SCH_1):PAGE32_I14@PURE_QUANTA.GENOA_SP5(CHIPS)':
 'VSS_BY54': CDS_PINID='VSS_BY54';
NODE_NAME     U25 BY57
 '@T6G_MB_LIB.T6G(SCH_1):PAGE32_I14@PURE_QUANTA.GENOA_SP5(CHIPS)':
 'VSS_BY57': CDS_PINID='VSS_BY57';
NODE_NAME     U25 BY59
 '@T6G_MB_LIB.T6G(SCH_1):PAGE32_I14@PURE_QUANTA.GENOA_SP5(CHIPS)':
 'VSS_BY59': CDS_PINID='VSS_BY59';
NODE_NAME     U25 BY61
 '@T6G_MB_LIB.T6G(SCH_1):PAGE32_I14@PURE_QUANTA.GENOA_SP5(CHIPS)':
 'VSS_BY61': CDS_PINID='VSS_BY61';
NODE_NAME     U25 BY64
 '@T6G_MB_LIB.T6G(SCH_1):PAGE32_I14@PURE_QUANTA.GENOA_SP5(CHIPS)':
 'VSS_BY64': CDS_PINID='VSS_BY64';
NODE_NAME     U25 BY66
 '@T6G_MB_LIB.T6G(SCH_1):PAGE32_I14@PURE_QUANTA.GENOA_SP5(CHIPS)':
 'VSS_BY66': CDS_PINID='VSS_BY66';
NODE_NAME     U25 BY68
 '@T6G_MB_LIB.T6G(SCH_1):PAGE32_I14@PURE_QUANTA.GENOA_SP5(CHIPS)':
 'VSS_BY68': CDS_PINID='VSS_BY68';
NODE_NAME     U25 BY71
 '@T6G_MB_LIB.T6G(SCH_1):PAGE32_I14@PURE_QUANTA.GENOA_SP5(CHIPS)':
 'VSS_BY71': CDS_PINID='VSS_BY71';
NODE_NAME     U25 BY73
 '@T6G_MB_LIB.T6G(SCH_1):PAGE32_I14@PURE_QUANTA.GENOA_SP5(CHIPS)':
 'VSS_BY73': CDS_PINID='VSS_BY73';
NODE_NAME     U25 CA1
 '@T6G_MB_LIB.T6G(SCH_1):PAGE32_I14@PURE_QUANTA.GENOA_SP5(CHIPS)':
 'VSS_CA1': CDS_PINID='VSS_CA1';
NODE_NAME     U25 CA6
 '@T6G_MB_LIB.T6G(SCH_1):PAGE32_I14@PURE_QUANTA.GENOA_SP5(CHIPS)':
 'VSS_CA6': CDS_PINID='VSS_CA6';
NODE_NAME     U25 CA8
 '@T6G_MB_LIB.T6G(SCH_1):PAGE32_I14@PURE_QUANTA.GENOA_SP5(CHIPS)':
 'VSS_CA8': CDS_PINID='VSS_CA8';
NODE_NAME     U25 CA13
 '@T6G_MB_LIB.T6G(SCH_1):PAGE32_I14@PURE_QUANTA.GENOA_SP5(CHIPS)':
 'VSS_CA13': CDS_PINID='VSS_CA13';
NODE_NAME     U25 CA15
 '@T6G_MB_LIB.T6G(SCH_1):PAGE32_I14@PURE_QUANTA.GENOA_SP5(CHIPS)':
 'VSS_CA15': CDS_PINID='VSS_CA15';
NODE_NAME     U25 CA20
 '@T6G_MB_LIB.T6G(SCH_1):PAGE32_I14@PURE_QUANTA.GENOA_SP5(CHIPS)':
 'VSS_CA20': CDS_PINID='VSS_CA20';
NODE_NAME     U25 CA22
 '@T6G_MB_LIB.T6G(SCH_1):PAGE32_I14@PURE_QUANTA.GENOA_SP5(CHIPS)':
 'VSS_CA22': CDS_PINID='VSS_CA22';
NODE_NAME     U25 CA25
 '@T6G_MB_LIB.T6G(SCH_1):PAGE32_I14@PURE_QUANTA.GENOA_SP5(CHIPS)':
 'VSS_CA25': CDS_PINID='VSS_CA25';
NODE_NAME     U25 CA28
 '@T6G_MB_LIB.T6G(SCH_1):PAGE32_I14@PURE_QUANTA.GENOA_SP5(CHIPS)':
 'VSS_CA28': CDS_PINID='VSS_CA28';
NODE_NAME     U25 CA31
 '@T6G_MB_LIB.T6G(SCH_1):PAGE32_I14@PURE_QUANTA.GENOA_SP5(CHIPS)':
 'VSS_CA31': CDS_PINID='VSS_CA31';
NODE_NAME     U25 CA34
 '@T6G_MB_LIB.T6G(SCH_1):PAGE32_I14@PURE_QUANTA.GENOA_SP5(CHIPS)':
 'VSS_CA34': CDS_PINID='VSS_CA34';
NODE_NAME     U25 CA35
 '@T6G_MB_LIB.T6G(SCH_1):PAGE32_I14@PURE_QUANTA.GENOA_SP5(CHIPS)':
 'VSS_CA35': CDS_PINID='VSS_CA35';
NODE_NAME     U25 CA36
 '@T6G_MB_LIB.T6G(SCH_1):PAGE32_I14@PURE_QUANTA.GENOA_SP5(CHIPS)':
 'VSS_CA36': CDS_PINID='VSS_CA36';
NODE_NAME     U25 CA40
 '@T6G_MB_LIB.T6G(SCH_1):PAGE32_I14@PURE_QUANTA.GENOA_SP5(CHIPS)':
 'VSS_CA40': CDS_PINID='VSS_CA40';
NODE_NAME     U25 CA41
 '@T6G_MB_LIB.T6G(SCH_1):PAGE32_I14@PURE_QUANTA.GENOA_SP5(CHIPS)':
 'VSS_CA41': CDS_PINID='VSS_CA41';
NODE_NAME     U25 CA42
 '@T6G_MB_LIB.T6G(SCH_1):PAGE32_I14@PURE_QUANTA.GENOA_SP5(CHIPS)':
 'VSS_CA42': CDS_PINID='VSS_CA42';
NODE_NAME     U25 CA45
 '@T6G_MB_LIB.T6G(SCH_1):PAGE32_I14@PURE_QUANTA.GENOA_SP5(CHIPS)':
 'VSS_CA45': CDS_PINID='VSS_CA45';
NODE_NAME     U25 CA48
 '@T6G_MB_LIB.T6G(SCH_1):PAGE32_I14@PURE_QUANTA.GENOA_SP5(CHIPS)':
 'VSS_CA48': CDS_PINID='VSS_CA48';
NODE_NAME     U25 CA51
 '@T6G_MB_LIB.T6G(SCH_1):PAGE32_I14@PURE_QUANTA.GENOA_SP5(CHIPS)':
 'VSS_CA51': CDS_PINID='VSS_CA51';
NODE_NAME     U25 CA54
 '@T6G_MB_LIB.T6G(SCH_1):PAGE32_I14@PURE_QUANTA.GENOA_SP5(CHIPS)':
 'VSS_CA54': CDS_PINID='VSS_CA54';
NODE_NAME     U25 CA56
 '@T6G_MB_LIB.T6G(SCH_1):PAGE32_I14@PURE_QUANTA.GENOA_SP5(CHIPS)':
 'VSS_CA56': CDS_PINID='VSS_CA56';
NODE_NAME     U25 CA61
 '@T6G_MB_LIB.T6G(SCH_1):PAGE32_I14@PURE_QUANTA.GENOA_SP5(CHIPS)':
 'VSS_CA61': CDS_PINID='VSS_CA61';
NODE_NAME     U25 CA63
 '@T6G_MB_LIB.T6G(SCH_1):PAGE32_I14@PURE_QUANTA.GENOA_SP5(CHIPS)':
 'VSS_CA63': CDS_PINID='VSS_CA63';
NODE_NAME     U25 CA68
 '@T6G_MB_LIB.T6G(SCH_1):PAGE32_I14@PURE_QUANTA.GENOA_SP5(CHIPS)':
 'VSS_CA68': CDS_PINID='VSS_CA68';
NODE_NAME     U25 CA70
 '@T6G_MB_LIB.T6G(SCH_1):PAGE32_I14@PURE_QUANTA.GENOA_SP5(CHIPS)':
 'VSS_CA70': CDS_PINID='VSS_CA70';
NODE_NAME     U25 CA75
 '@T6G_MB_LIB.T6G(SCH_1):PAGE32_I14@PURE_QUANTA.GENOA_SP5(CHIPS)':
 'VSS_CA75': CDS_PINID='VSS_CA75';
NODE_NAME     U25 CB3
 '@T6G_MB_LIB.T6G(SCH_1):PAGE32_I14@PURE_QUANTA.GENOA_SP5(CHIPS)':
 'VSS_CB3': CDS_PINID='VSS_CB3';
NODE_NAME     U25 CB5
 '@T6G_MB_LIB.T6G(SCH_1):PAGE32_I14@PURE_QUANTA.GENOA_SP5(CHIPS)':
 'VSS_CB5': CDS_PINID='VSS_CB5';
NODE_NAME     U25 CB8
 '@T6G_MB_LIB.T6G(SCH_1):PAGE32_I14@PURE_QUANTA.GENOA_SP5(CHIPS)':
 'VSS_CB8': CDS_PINID='VSS_CB8';
NODE_NAME     U25 CB10
 '@T6G_MB_LIB.T6G(SCH_1):PAGE32_I14@PURE_QUANTA.GENOA_SP5(CHIPS)':
 'VSS_CB10': CDS_PINID='VSS_CB10';
NODE_NAME     U25 CB12
 '@T6G_MB_LIB.T6G(SCH_1):PAGE32_I14@PURE_QUANTA.GENOA_SP5(CHIPS)':
 'VSS_CB12': CDS_PINID='VSS_CB12';
NODE_NAME     U25 CB15
 '@T6G_MB_LIB.T6G(SCH_1):PAGE32_I14@PURE_QUANTA.GENOA_SP5(CHIPS)':
 'VSS_CB15': CDS_PINID='VSS_CB15';
NODE_NAME     U25 CB17
 '@T6G_MB_LIB.T6G(SCH_1):PAGE32_I14@PURE_QUANTA.GENOA_SP5(CHIPS)':
 'VSS_CB17': CDS_PINID='VSS_CB17';
NODE_NAME     U25 CB19
 '@T6G_MB_LIB.T6G(SCH_1):PAGE32_I14@PURE_QUANTA.GENOA_SP5(CHIPS)':
 'VSS_CB19': CDS_PINID='VSS_CB19';
NODE_NAME     U25 CB23
 '@T6G_MB_LIB.T6G(SCH_1):PAGE32_I14@PURE_QUANTA.GENOA_SP5(CHIPS)':
 'VSS_CB23': CDS_PINID='VSS_CB23';
NODE_NAME     U25 CB24
 '@T6G_MB_LIB.T6G(SCH_1):PAGE32_I14@PURE_QUANTA.GENOA_SP5(CHIPS)':
 'VSS_CB24': CDS_PINID='VSS_CB24';
NODE_NAME     U25 CB25
 '@T6G_MB_LIB.T6G(SCH_1):PAGE32_I14@PURE_QUANTA.GENOA_SP5(CHIPS)':
 'VSS_CB25': CDS_PINID='VSS_CB25';
NODE_NAME     U25 CB26
 '@T6G_MB_LIB.T6G(SCH_1):PAGE32_I14@PURE_QUANTA.GENOA_SP5(CHIPS)':
 'VSS_CB26': CDS_PINID='VSS_CB26';
NODE_NAME     U25 CB27
 '@T6G_MB_LIB.T6G(SCH_1):PAGE32_I14@PURE_QUANTA.GENOA_SP5(CHIPS)':
 'VSS_CB27': CDS_PINID='VSS_CB27';
NODE_NAME     U25 CB28
 '@T6G_MB_LIB.T6G(SCH_1):PAGE32_I14@PURE_QUANTA.GENOA_SP5(CHIPS)':
 'VSS_CB28': CDS_PINID='VSS_CB28';
NODE_NAME     U25 CB29
 '@T6G_MB_LIB.T6G(SCH_1):PAGE32_I14@PURE_QUANTA.GENOA_SP5(CHIPS)':
 'VSS_CB29': CDS_PINID='VSS_CB29';
NODE_NAME     U25 CB30
 '@T6G_MB_LIB.T6G(SCH_1):PAGE32_I14@PURE_QUANTA.GENOA_SP5(CHIPS)':
 'VSS_CB30': CDS_PINID='VSS_CB30';
NODE_NAME     U25 CB31
 '@T6G_MB_LIB.T6G(SCH_1):PAGE32_I14@PURE_QUANTA.GENOA_SP5(CHIPS)':
 'VSS_CB31': CDS_PINID='VSS_CB31';
NODE_NAME     U25 CB32
 '@T6G_MB_LIB.T6G(SCH_1):PAGE32_I14@PURE_QUANTA.GENOA_SP5(CHIPS)':
 'VSS_CB32': CDS_PINID='VSS_CB32';
NODE_NAME     U25 CB33
 '@T6G_MB_LIB.T6G(SCH_1):PAGE32_I14@PURE_QUANTA.GENOA_SP5(CHIPS)':
 'VSS_CB33': CDS_PINID='VSS_CB33';
NODE_NAME     U25 CB34
 '@T6G_MB_LIB.T6G(SCH_1):PAGE32_I14@PURE_QUANTA.GENOA_SP5(CHIPS)':
 'VSS_CB34': CDS_PINID='VSS_CB34';
NODE_NAME     U25 CB37
 '@T6G_MB_LIB.T6G(SCH_1):PAGE32_I14@PURE_QUANTA.GENOA_SP5(CHIPS)':
 'VSS_CB37': CDS_PINID='VSS_CB37';
NODE_NAME     U25 CB39
 '@T6G_MB_LIB.T6G(SCH_1):PAGE32_I14@PURE_QUANTA.GENOA_SP5(CHIPS)':
 'VSS_CB39': CDS_PINID='VSS_CB39';
NODE_NAME     U25 CB42
 '@T6G_MB_LIB.T6G(SCH_1):PAGE32_I14@PURE_QUANTA.GENOA_SP5(CHIPS)':
 'VSS_CB42': CDS_PINID='VSS_CB42';
NODE_NAME     U25 CB43
 '@T6G_MB_LIB.T6G(SCH_1):PAGE32_I14@PURE_QUANTA.GENOA_SP5(CHIPS)':
 'VSS_CB43': CDS_PINID='VSS_CB43';
NODE_NAME     U25 CB45
 '@T6G_MB_LIB.T6G(SCH_1):PAGE32_I14@PURE_QUANTA.GENOA_SP5(CHIPS)':
 'VSS_CB45': CDS_PINID='VSS_CB45';
NODE_NAME     U25 CB46
 '@T6G_MB_LIB.T6G(SCH_1):PAGE32_I14@PURE_QUANTA.GENOA_SP5(CHIPS)':
 'VSS_CB46': CDS_PINID='VSS_CB46';
NODE_NAME     U25 CB47
 '@T6G_MB_LIB.T6G(SCH_1):PAGE32_I14@PURE_QUANTA.GENOA_SP5(CHIPS)':
 'VSS_CB47': CDS_PINID='VSS_CB47';
NODE_NAME     U25 CB48
 '@T6G_MB_LIB.T6G(SCH_1):PAGE32_I14@PURE_QUANTA.GENOA_SP5(CHIPS)':
 'VSS_CB48': CDS_PINID='VSS_CB48';
NODE_NAME     U25 CB49
 '@T6G_MB_LIB.T6G(SCH_1):PAGE32_I14@PURE_QUANTA.GENOA_SP5(CHIPS)':
 'VSS_CB49': CDS_PINID='VSS_CB49';
NODE_NAME     U25 CB50
 '@T6G_MB_LIB.T6G(SCH_1):PAGE32_I14@PURE_QUANTA.GENOA_SP5(CHIPS)':
 'VSS_CB50': CDS_PINID='VSS_CB50';
NODE_NAME     U25 CB51
 '@T6G_MB_LIB.T6G(SCH_1):PAGE32_I14@PURE_QUANTA.GENOA_SP5(CHIPS)':
 'VSS_CB51': CDS_PINID='VSS_CB51';
NODE_NAME     U25 CB52
 '@T6G_MB_LIB.T6G(SCH_1):PAGE32_I14@PURE_QUANTA.GENOA_SP5(CHIPS)':
 'VSS_CB52': CDS_PINID='VSS_CB52';
NODE_NAME     U25 CB53
 '@T6G_MB_LIB.T6G(SCH_1):PAGE32_I14@PURE_QUANTA.GENOA_SP5(CHIPS)':
 'VSS_CB53': CDS_PINID='VSS_CB53';
NODE_NAME     U25 CB57
 '@T6G_MB_LIB.T6G(SCH_1):PAGE32_I14@PURE_QUANTA.GENOA_SP5(CHIPS)':
 'VSS_CB57': CDS_PINID='VSS_CB57';
NODE_NAME     U25 CB59
 '@T6G_MB_LIB.T6G(SCH_1):PAGE32_I14@PURE_QUANTA.GENOA_SP5(CHIPS)':
 'VSS_CB59': CDS_PINID='VSS_CB59';
NODE_NAME     U25 CB61
 '@T6G_MB_LIB.T6G(SCH_1):PAGE32_I14@PURE_QUANTA.GENOA_SP5(CHIPS)':
 'VSS_CB61': CDS_PINID='VSS_CB61';
NODE_NAME     U25 CB64
 '@T6G_MB_LIB.T6G(SCH_1):PAGE32_I14@PURE_QUANTA.GENOA_SP5(CHIPS)':
 'VSS_CB64': CDS_PINID='VSS_CB64';
NODE_NAME     U25 CB66
 '@T6G_MB_LIB.T6G(SCH_1):PAGE32_I14@PURE_QUANTA.GENOA_SP5(CHIPS)':
 'VSS_CB66': CDS_PINID='VSS_CB66';
NODE_NAME     U25 CB68
 '@T6G_MB_LIB.T6G(SCH_1):PAGE32_I14@PURE_QUANTA.GENOA_SP5(CHIPS)':
 'VSS_CB68': CDS_PINID='VSS_CB68';
NODE_NAME     U25 CB71
 '@T6G_MB_LIB.T6G(SCH_1):PAGE32_I14@PURE_QUANTA.GENOA_SP5(CHIPS)':
 'VSS_CB71': CDS_PINID='VSS_CB71';
NODE_NAME     U25 CB73
 '@T6G_MB_LIB.T6G(SCH_1):PAGE32_I14@PURE_QUANTA.GENOA_SP5(CHIPS)':
 'VSS_CB73': CDS_PINID='VSS_CB73';
NODE_NAME     U25 CC1
 '@T6G_MB_LIB.T6G(SCH_1):PAGE32_I14@PURE_QUANTA.GENOA_SP5(CHIPS)':
 'VSS_CC1': CDS_PINID='VSS_CC1';
NODE_NAME     U25 CC4
 '@T6G_MB_LIB.T6G(SCH_1):PAGE32_I14@PURE_QUANTA.GENOA_SP5(CHIPS)':
 'VSS_CC4': CDS_PINID='VSS_CC4';
NODE_NAME     U25 CC6
 '@T6G_MB_LIB.T6G(SCH_1):PAGE32_I14@PURE_QUANTA.GENOA_SP5(CHIPS)':
 'VSS_CC6': CDS_PINID='VSS_CC6';
NODE_NAME     U25 CC8
 '@T6G_MB_LIB.T6G(SCH_1):PAGE32_I14@PURE_QUANTA.GENOA_SP5(CHIPS)':
 'VSS_CC8': CDS_PINID='VSS_CC8';
NODE_NAME     U25 CC11
 '@T6G_MB_LIB.T6G(SCH_1):PAGE32_I14@PURE_QUANTA.GENOA_SP5(CHIPS)':
 'VSS_CC11': CDS_PINID='VSS_CC11';
NODE_NAME     U25 CC13
 '@T6G_MB_LIB.T6G(SCH_1):PAGE32_I14@PURE_QUANTA.GENOA_SP5(CHIPS)':
 'VSS_CC13': CDS_PINID='VSS_CC13';
NODE_NAME     U25 CC15
 '@T6G_MB_LIB.T6G(SCH_1):PAGE32_I14@PURE_QUANTA.GENOA_SP5(CHIPS)':
 'VSS_CC15': CDS_PINID='VSS_CC15';
NODE_NAME     U25 CC18
 '@T6G_MB_LIB.T6G(SCH_1):PAGE32_I14@PURE_QUANTA.GENOA_SP5(CHIPS)':
 'VSS_CC18': CDS_PINID='VSS_CC18';
NODE_NAME     U25 CC20
 '@T6G_MB_LIB.T6G(SCH_1):PAGE32_I14@PURE_QUANTA.GENOA_SP5(CHIPS)':
 'VSS_CC20': CDS_PINID='VSS_CC20';
NODE_NAME     U25 CC25
 '@T6G_MB_LIB.T6G(SCH_1):PAGE32_I14@PURE_QUANTA.GENOA_SP5(CHIPS)':
 'VSS_CC25': CDS_PINID='VSS_CC25';
NODE_NAME     U25 CC28
 '@T6G_MB_LIB.T6G(SCH_1):PAGE32_I14@PURE_QUANTA.GENOA_SP5(CHIPS)':
 'VSS_CC28': CDS_PINID='VSS_CC28';
NODE_NAME     U25 CC31
 '@T6G_MB_LIB.T6G(SCH_1):PAGE32_I14@PURE_QUANTA.GENOA_SP5(CHIPS)':
 'VSS_CC31': CDS_PINID='VSS_CC31';
NODE_NAME     U25 CC34
 '@T6G_MB_LIB.T6G(SCH_1):PAGE32_I14@PURE_QUANTA.GENOA_SP5(CHIPS)':
 'VSS_CC34': CDS_PINID='VSS_CC34';
NODE_NAME     U25 CC42
 '@T6G_MB_LIB.T6G(SCH_1):PAGE32_I14@PURE_QUANTA.GENOA_SP5(CHIPS)':
 'VSS_CC42': CDS_PINID='VSS_CC42';
NODE_NAME     U25 CC45
 '@T6G_MB_LIB.T6G(SCH_1):PAGE32_I14@PURE_QUANTA.GENOA_SP5(CHIPS)':
 'VSS_CC45': CDS_PINID='VSS_CC45';
NODE_NAME     U25 CC48
 '@T6G_MB_LIB.T6G(SCH_1):PAGE32_I14@PURE_QUANTA.GENOA_SP5(CHIPS)':
 'VSS_CC48': CDS_PINID='VSS_CC48';
NODE_NAME     U25 CC51
 '@T6G_MB_LIB.T6G(SCH_1):PAGE32_I14@PURE_QUANTA.GENOA_SP5(CHIPS)':
 'VSS_CC51': CDS_PINID='VSS_CC51';
NODE_NAME     U25 CC54
 '@T6G_MB_LIB.T6G(SCH_1):PAGE32_I14@PURE_QUANTA.GENOA_SP5(CHIPS)':
 'VSS_CC54': CDS_PINID='VSS_CC54';
NODE_NAME     U25 CC56
 '@T6G_MB_LIB.T6G(SCH_1):PAGE32_I14@PURE_QUANTA.GENOA_SP5(CHIPS)':
 'VSS_CC56': CDS_PINID='VSS_CC56';
NODE_NAME     U25 CC58
 '@T6G_MB_LIB.T6G(SCH_1):PAGE32_I14@PURE_QUANTA.GENOA_SP5(CHIPS)':
 'VSS_CC58': CDS_PINID='VSS_CC58';
NODE_NAME     U25 CC61
 '@T6G_MB_LIB.T6G(SCH_1):PAGE32_I14@PURE_QUANTA.GENOA_SP5(CHIPS)':
 'VSS_CC61': CDS_PINID='VSS_CC61';
NODE_NAME     U25 CC63
 '@T6G_MB_LIB.T6G(SCH_1):PAGE32_I14@PURE_QUANTA.GENOA_SP5(CHIPS)':
 'VSS_CC63': CDS_PINID='VSS_CC63';
NODE_NAME     U25 CC65
 '@T6G_MB_LIB.T6G(SCH_1):PAGE32_I14@PURE_QUANTA.GENOA_SP5(CHIPS)':
 'VSS_CC65': CDS_PINID='VSS_CC65';
NODE_NAME     U25 CC68
 '@T6G_MB_LIB.T6G(SCH_1):PAGE32_I14@PURE_QUANTA.GENOA_SP5(CHIPS)':
 'VSS_CC68': CDS_PINID='VSS_CC68';
NODE_NAME     U25 CC70
 '@T6G_MB_LIB.T6G(SCH_1):PAGE32_I14@PURE_QUANTA.GENOA_SP5(CHIPS)':
 'VSS_CC70': CDS_PINID='VSS_CC70';
NODE_NAME     U25 CC72
 '@T6G_MB_LIB.T6G(SCH_1):PAGE32_I14@PURE_QUANTA.GENOA_SP5(CHIPS)':
 'VSS_CC72': CDS_PINID='VSS_CC72';
NODE_NAME     U25 CC75
 '@T6G_MB_LIB.T6G(SCH_1):PAGE32_I14@PURE_QUANTA.GENOA_SP5(CHIPS)':
 'VSS_CC75': CDS_PINID='VSS_CC75';
NODE_NAME     U25 CD3
 '@T6G_MB_LIB.T6G(SCH_1):PAGE32_I14@PURE_QUANTA.GENOA_SP5(CHIPS)':
 'VSS_CD3': CDS_PINID='VSS_CD3';
NODE_NAME     U25 CD8
 '@T6G_MB_LIB.T6G(SCH_1):PAGE32_I14@PURE_QUANTA.GENOA_SP5(CHIPS)':
 'VSS_CD8': CDS_PINID='VSS_CD8';
NODE_NAME     U25 CD10
 '@T6G_MB_LIB.T6G(SCH_1):PAGE32_I14@PURE_QUANTA.GENOA_SP5(CHIPS)':
 'VSS_CD10': CDS_PINID='VSS_CD10';
NODE_NAME     U25 CD15
 '@T6G_MB_LIB.T6G(SCH_1):PAGE32_I14@PURE_QUANTA.GENOA_SP5(CHIPS)':
 'VSS_CD15': CDS_PINID='VSS_CD15';
NODE_NAME     U25 CD17
 '@T6G_MB_LIB.T6G(SCH_1):PAGE32_I14@PURE_QUANTA.GENOA_SP5(CHIPS)':
 'VSS_CD17': CDS_PINID='VSS_CD17';
NODE_NAME     U25 CD22
 '@T6G_MB_LIB.T6G(SCH_1):PAGE32_I14@PURE_QUANTA.GENOA_SP5(CHIPS)':
 'VSS_CD22': CDS_PINID='VSS_CD22';
NODE_NAME     U25 CD25
 '@T6G_MB_LIB.T6G(SCH_1):PAGE32_I14@PURE_QUANTA.GENOA_SP5(CHIPS)':
 'VSS_CD25': CDS_PINID='VSS_CD25';
NODE_NAME     U25 CD28
 '@T6G_MB_LIB.T6G(SCH_1):PAGE32_I14@PURE_QUANTA.GENOA_SP5(CHIPS)':
 'VSS_CD28': CDS_PINID='VSS_CD28';
NODE_NAME     U25 CD31
 '@T6G_MB_LIB.T6G(SCH_1):PAGE32_I14@PURE_QUANTA.GENOA_SP5(CHIPS)':
 'VSS_CD31': CDS_PINID='VSS_CD31';
NODE_NAME     U25 CD34
 '@T6G_MB_LIB.T6G(SCH_1):PAGE32_I14@PURE_QUANTA.GENOA_SP5(CHIPS)':
 'VSS_CD34': CDS_PINID='VSS_CD34';
NODE_NAME     U25 CD37
 '@T6G_MB_LIB.T6G(SCH_1):PAGE32_I14@PURE_QUANTA.GENOA_SP5(CHIPS)':
 'VSS_CD37': CDS_PINID='VSS_CD37';
NODE_NAME     U25 CD39
 '@T6G_MB_LIB.T6G(SCH_1):PAGE32_I14@PURE_QUANTA.GENOA_SP5(CHIPS)':
 'VSS_CD39': CDS_PINID='VSS_CD39';
NODE_NAME     U25 CD42
 '@T6G_MB_LIB.T6G(SCH_1):PAGE32_I14@PURE_QUANTA.GENOA_SP5(CHIPS)':
 'VSS_CD42': CDS_PINID='VSS_CD42';
NODE_NAME     U25 CD45
 '@T6G_MB_LIB.T6G(SCH_1):PAGE32_I14@PURE_QUANTA.GENOA_SP5(CHIPS)':
 'VSS_CD45': CDS_PINID='VSS_CD45';
NODE_NAME     U25 CD48
 '@T6G_MB_LIB.T6G(SCH_1):PAGE32_I14@PURE_QUANTA.GENOA_SP5(CHIPS)':
 'VSS_CD48': CDS_PINID='VSS_CD48';
NODE_NAME     U25 CD51
 '@T6G_MB_LIB.T6G(SCH_1):PAGE32_I14@PURE_QUANTA.GENOA_SP5(CHIPS)':
 'VSS_CD51': CDS_PINID='VSS_CD51';
NODE_NAME     U25 CD54
 '@T6G_MB_LIB.T6G(SCH_1):PAGE32_I14@PURE_QUANTA.GENOA_SP5(CHIPS)':
 'VSS_CD54': CDS_PINID='VSS_CD54';
NODE_NAME     U25 CD59
 '@T6G_MB_LIB.T6G(SCH_1):PAGE32_I14@PURE_QUANTA.GENOA_SP5(CHIPS)':
 'VSS_CD59': CDS_PINID='VSS_CD59';
NODE_NAME     U25 CD61
 '@T6G_MB_LIB.T6G(SCH_1):PAGE32_I14@PURE_QUANTA.GENOA_SP5(CHIPS)':
 'VSS_CD61': CDS_PINID='VSS_CD61';
NODE_NAME     U25 CD66
 '@T6G_MB_LIB.T6G(SCH_1):PAGE32_I14@PURE_QUANTA.GENOA_SP5(CHIPS)':
 'VSS_CD66': CDS_PINID='VSS_CD66';
NODE_NAME     U25 CD68
 '@T6G_MB_LIB.T6G(SCH_1):PAGE32_I14@PURE_QUANTA.GENOA_SP5(CHIPS)':
 'VSS_CD68': CDS_PINID='VSS_CD68';
NODE_NAME     U25 CD73
 '@T6G_MB_LIB.T6G(SCH_1):PAGE32_I14@PURE_QUANTA.GENOA_SP5(CHIPS)':
 'VSS_CD73': CDS_PINID='VSS_CD73';
NODE_NAME     U25 CE1
 '@T6G_MB_LIB.T6G(SCH_1):PAGE32_I14@PURE_QUANTA.GENOA_SP5(CHIPS)':
 'VSS_CE1': CDS_PINID='VSS_CE1';
NODE_NAME     U25 CE4
 '@T6G_MB_LIB.T6G(SCH_1):PAGE32_I14@PURE_QUANTA.GENOA_SP5(CHIPS)':
 'VSS_CE4': CDS_PINID='VSS_CE4';
NODE_NAME     U25 CE6
 '@T6G_MB_LIB.T6G(SCH_1):PAGE32_I14@PURE_QUANTA.GENOA_SP5(CHIPS)':
 'VSS_CE6': CDS_PINID='VSS_CE6';
NODE_NAME     U25 CE8
 '@T6G_MB_LIB.T6G(SCH_1):PAGE32_I14@PURE_QUANTA.GENOA_SP5(CHIPS)':
 'VSS_CE8': CDS_PINID='VSS_CE8';
NODE_NAME     U25 CE11
 '@T6G_MB_LIB.T6G(SCH_1):PAGE32_I14@PURE_QUANTA.GENOA_SP5(CHIPS)':
 'VSS_CE11': CDS_PINID='VSS_CE11';
NODE_NAME     U25 CE13
 '@T6G_MB_LIB.T6G(SCH_1):PAGE32_I14@PURE_QUANTA.GENOA_SP5(CHIPS)':
 'VSS_CE13': CDS_PINID='VSS_CE13';
NODE_NAME     U25 CE15
 '@T6G_MB_LIB.T6G(SCH_1):PAGE32_I14@PURE_QUANTA.GENOA_SP5(CHIPS)':
 'VSS_CE15': CDS_PINID='VSS_CE15';
NODE_NAME     U25 CE18
 '@T6G_MB_LIB.T6G(SCH_1):PAGE32_I14@PURE_QUANTA.GENOA_SP5(CHIPS)':
 'VSS_CE18': CDS_PINID='VSS_CE18';
NODE_NAME     U25 CE20
 '@T6G_MB_LIB.T6G(SCH_1):PAGE32_I14@PURE_QUANTA.GENOA_SP5(CHIPS)':
 'VSS_CE20': CDS_PINID='VSS_CE20';
NODE_NAME     U25 CE22
 '@T6G_MB_LIB.T6G(SCH_1):PAGE32_I14@PURE_QUANTA.GENOA_SP5(CHIPS)':
 'VSS_CE22': CDS_PINID='VSS_CE22';
NODE_NAME     U25 CE25
 '@T6G_MB_LIB.T6G(SCH_1):PAGE32_I14@PURE_QUANTA.GENOA_SP5(CHIPS)':
 'VSS_CE25': CDS_PINID='VSS_CE25';
NODE_NAME     U25 CE28
 '@T6G_MB_LIB.T6G(SCH_1):PAGE32_I14@PURE_QUANTA.GENOA_SP5(CHIPS)':
 'VSS_CE28': CDS_PINID='VSS_CE28';
NODE_NAME     U25 CE31
 '@T6G_MB_LIB.T6G(SCH_1):PAGE32_I14@PURE_QUANTA.GENOA_SP5(CHIPS)':
 'VSS_CE31': CDS_PINID='VSS_CE31';
NODE_NAME     U25 CE34
 '@T6G_MB_LIB.T6G(SCH_1):PAGE32_I14@PURE_QUANTA.GENOA_SP5(CHIPS)':
 'VSS_CE34': CDS_PINID='VSS_CE34';
NODE_NAME     U25 CE35
 '@T6G_MB_LIB.T6G(SCH_1):PAGE32_I14@PURE_QUANTA.GENOA_SP5(CHIPS)':
 'VSS_CE35': CDS_PINID='VSS_CE35';
NODE_NAME     U25 CE36
 '@T6G_MB_LIB.T6G(SCH_1):PAGE32_I14@PURE_QUANTA.GENOA_SP5(CHIPS)':
 'VSS_CE36': CDS_PINID='VSS_CE36';
NODE_NAME     U25 CE40
 '@T6G_MB_LIB.T6G(SCH_1):PAGE32_I14@PURE_QUANTA.GENOA_SP5(CHIPS)':
 'VSS_CE40': CDS_PINID='VSS_CE40';
NODE_NAME     U25 CE41
 '@T6G_MB_LIB.T6G(SCH_1):PAGE32_I14@PURE_QUANTA.GENOA_SP5(CHIPS)':
 'VSS_CE41': CDS_PINID='VSS_CE41';
NODE_NAME     U25 CE42
 '@T6G_MB_LIB.T6G(SCH_1):PAGE32_I14@PURE_QUANTA.GENOA_SP5(CHIPS)':
 'VSS_CE42': CDS_PINID='VSS_CE42';
NODE_NAME     U25 CE45
 '@T6G_MB_LIB.T6G(SCH_1):PAGE32_I14@PURE_QUANTA.GENOA_SP5(CHIPS)':
 'VSS_CE45': CDS_PINID='VSS_CE45';
NODE_NAME     U25 CE48
 '@T6G_MB_LIB.T6G(SCH_1):PAGE32_I14@PURE_QUANTA.GENOA_SP5(CHIPS)':
 'VSS_CE48': CDS_PINID='VSS_CE48';
NODE_NAME     U25 CE51
 '@T6G_MB_LIB.T6G(SCH_1):PAGE32_I14@PURE_QUANTA.GENOA_SP5(CHIPS)':
 'VSS_CE51': CDS_PINID='VSS_CE51';
NODE_NAME     U25 CE54
 '@T6G_MB_LIB.T6G(SCH_1):PAGE32_I14@PURE_QUANTA.GENOA_SP5(CHIPS)':
 'VSS_CE54': CDS_PINID='VSS_CE54';
NODE_NAME     U25 CE56
 '@T6G_MB_LIB.T6G(SCH_1):PAGE32_I14@PURE_QUANTA.GENOA_SP5(CHIPS)':
 'VSS_CE56': CDS_PINID='VSS_CE56';
NODE_NAME     U25 CE58
 '@T6G_MB_LIB.T6G(SCH_1):PAGE32_I14@PURE_QUANTA.GENOA_SP5(CHIPS)':
 'VSS_CE58': CDS_PINID='VSS_CE58';
NODE_NAME     U25 CE61
 '@T6G_MB_LIB.T6G(SCH_1):PAGE32_I14@PURE_QUANTA.GENOA_SP5(CHIPS)':
 'VSS_CE61': CDS_PINID='VSS_CE61';
NODE_NAME     U25 CE63
 '@T6G_MB_LIB.T6G(SCH_1):PAGE32_I14@PURE_QUANTA.GENOA_SP5(CHIPS)':
 'VSS_CE63': CDS_PINID='VSS_CE63';
NODE_NAME     U25 CE65
 '@T6G_MB_LIB.T6G(SCH_1):PAGE32_I14@PURE_QUANTA.GENOA_SP5(CHIPS)':
 'VSS_CE65': CDS_PINID='VSS_CE65';
NODE_NAME     U25 CE68
 '@T6G_MB_LIB.T6G(SCH_1):PAGE32_I14@PURE_QUANTA.GENOA_SP5(CHIPS)':
 'VSS_CE68': CDS_PINID='VSS_CE68';
NODE_NAME     U25 CE70
 '@T6G_MB_LIB.T6G(SCH_1):PAGE32_I14@PURE_QUANTA.GENOA_SP5(CHIPS)':
 'VSS_CE70': CDS_PINID='VSS_CE70';
NODE_NAME     U25 CE72
 '@T6G_MB_LIB.T6G(SCH_1):PAGE32_I14@PURE_QUANTA.GENOA_SP5(CHIPS)':
 'VSS_CE72': CDS_PINID='VSS_CE72';
NODE_NAME     U25 CE75
 '@T6G_MB_LIB.T6G(SCH_1):PAGE32_I14@PURE_QUANTA.GENOA_SP5(CHIPS)':
 'VSS_CE75': CDS_PINID='VSS_CE75';
NODE_NAME     U25 CF3
 '@T6G_MB_LIB.T6G(SCH_1):PAGE32_I14@PURE_QUANTA.GENOA_SP5(CHIPS)':
 'VSS_CF3': CDS_PINID='VSS_CF3';
NODE_NAME     U25 CF5
 '@T6G_MB_LIB.T6G(SCH_1):PAGE32_I14@PURE_QUANTA.GENOA_SP5(CHIPS)':
 'VSS_CF5': CDS_PINID='VSS_CF5';
NODE_NAME     U25 CF8
 '@T6G_MB_LIB.T6G(SCH_1):PAGE32_I14@PURE_QUANTA.GENOA_SP5(CHIPS)':
 'VSS_CF8': CDS_PINID='VSS_CF8';
NODE_NAME     U25 CF10
 '@T6G_MB_LIB.T6G(SCH_1):PAGE32_I14@PURE_QUANTA.GENOA_SP5(CHIPS)':
 'VSS_CF10': CDS_PINID='VSS_CF10';
NODE_NAME     U25 CF12
 '@T6G_MB_LIB.T6G(SCH_1):PAGE32_I14@PURE_QUANTA.GENOA_SP5(CHIPS)':
 'VSS_CF12': CDS_PINID='VSS_CF12';
NODE_NAME     U25 CF15
 '@T6G_MB_LIB.T6G(SCH_1):PAGE32_I14@PURE_QUANTA.GENOA_SP5(CHIPS)':
 'VSS_CF15': CDS_PINID='VSS_CF15';
NODE_NAME     U25 CF17
 '@T6G_MB_LIB.T6G(SCH_1):PAGE32_I14@PURE_QUANTA.GENOA_SP5(CHIPS)':
 'VSS_CF17': CDS_PINID='VSS_CF17';
NODE_NAME     U25 CF19
 '@T6G_MB_LIB.T6G(SCH_1):PAGE32_I14@PURE_QUANTA.GENOA_SP5(CHIPS)':
 'VSS_CF19': CDS_PINID='VSS_CF19';
NODE_NAME     U25 CF23
 '@T6G_MB_LIB.T6G(SCH_1):PAGE32_I14@PURE_QUANTA.GENOA_SP5(CHIPS)':
 'VSS_CF23': CDS_PINID='VSS_CF23';
NODE_NAME     U25 CF24
 '@T6G_MB_LIB.T6G(SCH_1):PAGE32_I14@PURE_QUANTA.GENOA_SP5(CHIPS)':
 'VSS_CF24': CDS_PINID='VSS_CF24';
NODE_NAME     U25 CF25
 '@T6G_MB_LIB.T6G(SCH_1):PAGE32_I14@PURE_QUANTA.GENOA_SP5(CHIPS)':
 'VSS_CF25': CDS_PINID='VSS_CF25';
NODE_NAME     U25 CF26
 '@T6G_MB_LIB.T6G(SCH_1):PAGE32_I14@PURE_QUANTA.GENOA_SP5(CHIPS)':
 'VSS_CF26': CDS_PINID='VSS_CF26';
NODE_NAME     U25 CF27
 '@T6G_MB_LIB.T6G(SCH_1):PAGE32_I14@PURE_QUANTA.GENOA_SP5(CHIPS)':
 'VSS_CF27': CDS_PINID='VSS_CF27';
NODE_NAME     U25 CF28
 '@T6G_MB_LIB.T6G(SCH_1):PAGE32_I14@PURE_QUANTA.GENOA_SP5(CHIPS)':
 'VSS_CF28': CDS_PINID='VSS_CF28';
NODE_NAME     U25 CF29
 '@T6G_MB_LIB.T6G(SCH_1):PAGE32_I14@PURE_QUANTA.GENOA_SP5(CHIPS)':
 'VSS_CF29': CDS_PINID='VSS_CF29';
NODE_NAME     U25 CF30
 '@T6G_MB_LIB.T6G(SCH_1):PAGE32_I14@PURE_QUANTA.GENOA_SP5(CHIPS)':
 'VSS_CF30': CDS_PINID='VSS_CF30';
NODE_NAME     U25 CF31
 '@T6G_MB_LIB.T6G(SCH_1):PAGE32_I14@PURE_QUANTA.GENOA_SP5(CHIPS)':
 'VSS_CF31': CDS_PINID='VSS_CF31';
NODE_NAME     U25 CF32
 '@T6G_MB_LIB.T6G(SCH_1):PAGE32_I14@PURE_QUANTA.GENOA_SP5(CHIPS)':
 'VSS_CF32': CDS_PINID='VSS_CF32';
NODE_NAME     U25 CF33
 '@T6G_MB_LIB.T6G(SCH_1):PAGE32_I14@PURE_QUANTA.GENOA_SP5(CHIPS)':
 'VSS_CF33': CDS_PINID='VSS_CF33';
NODE_NAME     U25 CF34
 '@T6G_MB_LIB.T6G(SCH_1):PAGE32_I15@PURE_QUANTA.GENOA_SP5(CHIPS)':
 'VSS_CF34': CDS_PINID='VSS_CF34';
NODE_NAME     U25 CF37
 '@T6G_MB_LIB.T6G(SCH_1):PAGE32_I15@PURE_QUANTA.GENOA_SP5(CHIPS)':
 'VSS_CF37': CDS_PINID='VSS_CF37';
NODE_NAME     U25 CF39
 '@T6G_MB_LIB.T6G(SCH_1):PAGE32_I15@PURE_QUANTA.GENOA_SP5(CHIPS)':
 'VSS_CF39': CDS_PINID='VSS_CF39';
NODE_NAME     U25 CF42
 '@T6G_MB_LIB.T6G(SCH_1):PAGE32_I15@PURE_QUANTA.GENOA_SP5(CHIPS)':
 'VSS_CF42': CDS_PINID='VSS_CF42';
NODE_NAME     U25 CF43
 '@T6G_MB_LIB.T6G(SCH_1):PAGE32_I15@PURE_QUANTA.GENOA_SP5(CHIPS)':
 'VSS_CF43': CDS_PINID='VSS_CF43';
NODE_NAME     U25 CF44
 '@T6G_MB_LIB.T6G(SCH_1):PAGE32_I15@PURE_QUANTA.GENOA_SP5(CHIPS)':
 'VSS_CF44': CDS_PINID='VSS_CF44';
NODE_NAME     U25 CF45
 '@T6G_MB_LIB.T6G(SCH_1):PAGE32_I15@PURE_QUANTA.GENOA_SP5(CHIPS)':
 'VSS_CF45': CDS_PINID='VSS_CF45';
NODE_NAME     U25 CF47
 '@T6G_MB_LIB.T6G(SCH_1):PAGE32_I15@PURE_QUANTA.GENOA_SP5(CHIPS)':
 'VSS_CF47': CDS_PINID='VSS_CF47';
NODE_NAME     U25 CF48
 '@T6G_MB_LIB.T6G(SCH_1):PAGE32_I15@PURE_QUANTA.GENOA_SP5(CHIPS)':
 'VSS_CF48': CDS_PINID='VSS_CF48';
NODE_NAME     U25 CF49
 '@T6G_MB_LIB.T6G(SCH_1):PAGE32_I15@PURE_QUANTA.GENOA_SP5(CHIPS)':
 'VSS_CF49': CDS_PINID='VSS_CF49';
NODE_NAME     U25 CF50
 '@T6G_MB_LIB.T6G(SCH_1):PAGE32_I15@PURE_QUANTA.GENOA_SP5(CHIPS)':
 'VSS_CF50': CDS_PINID='VSS_CF50';
NODE_NAME     U25 CF51
 '@T6G_MB_LIB.T6G(SCH_1):PAGE32_I15@PURE_QUANTA.GENOA_SP5(CHIPS)':
 'VSS_CF51': CDS_PINID='VSS_CF51';
NODE_NAME     U25 CF52
 '@T6G_MB_LIB.T6G(SCH_1):PAGE32_I15@PURE_QUANTA.GENOA_SP5(CHIPS)':
 'VSS_CF52': CDS_PINID='VSS_CF52';
NODE_NAME     U25 CF53
 '@T6G_MB_LIB.T6G(SCH_1):PAGE32_I15@PURE_QUANTA.GENOA_SP5(CHIPS)':
 'VSS_CF53': CDS_PINID='VSS_CF53';
NODE_NAME     U25 CF57
 '@T6G_MB_LIB.T6G(SCH_1):PAGE32_I15@PURE_QUANTA.GENOA_SP5(CHIPS)':
 'VSS_CF57': CDS_PINID='VSS_CF57';
NODE_NAME     U25 CF59
 '@T6G_MB_LIB.T6G(SCH_1):PAGE32_I15@PURE_QUANTA.GENOA_SP5(CHIPS)':
 'VSS_CF59': CDS_PINID='VSS_CF59';
NODE_NAME     U25 CF61
 '@T6G_MB_LIB.T6G(SCH_1):PAGE32_I15@PURE_QUANTA.GENOA_SP5(CHIPS)':
 'VSS_CF61': CDS_PINID='VSS_CF61';
NODE_NAME     U25 CF64
 '@T6G_MB_LIB.T6G(SCH_1):PAGE32_I15@PURE_QUANTA.GENOA_SP5(CHIPS)':
 'VSS_CF64': CDS_PINID='VSS_CF64';
NODE_NAME     U25 CF66
 '@T6G_MB_LIB.T6G(SCH_1):PAGE32_I15@PURE_QUANTA.GENOA_SP5(CHIPS)':
 'VSS_CF66': CDS_PINID='VSS_CF66';
NODE_NAME     U25 CF68
 '@T6G_MB_LIB.T6G(SCH_1):PAGE32_I15@PURE_QUANTA.GENOA_SP5(CHIPS)':
 'VSS_CF68': CDS_PINID='VSS_CF68';
NODE_NAME     U25 CF71
 '@T6G_MB_LIB.T6G(SCH_1):PAGE32_I15@PURE_QUANTA.GENOA_SP5(CHIPS)':
 'VSS_CF71': CDS_PINID='VSS_CF71';
NODE_NAME     U25 CF73
 '@T6G_MB_LIB.T6G(SCH_1):PAGE32_I15@PURE_QUANTA.GENOA_SP5(CHIPS)':
 'VSS_CF73': CDS_PINID='VSS_CF73';
NODE_NAME     U25 CG1
 '@T6G_MB_LIB.T6G(SCH_1):PAGE32_I15@PURE_QUANTA.GENOA_SP5(CHIPS)':
 'VSS_CG1': CDS_PINID='VSS_CG1';
NODE_NAME     U25 CG6
 '@T6G_MB_LIB.T6G(SCH_1):PAGE32_I15@PURE_QUANTA.GENOA_SP5(CHIPS)':
 'VSS_CG6': CDS_PINID='VSS_CG6';
NODE_NAME     U25 CG8
 '@T6G_MB_LIB.T6G(SCH_1):PAGE32_I15@PURE_QUANTA.GENOA_SP5(CHIPS)':
 'VSS_CG8': CDS_PINID='VSS_CG8';
NODE_NAME     U25 CG13
 '@T6G_MB_LIB.T6G(SCH_1):PAGE32_I15@PURE_QUANTA.GENOA_SP5(CHIPS)':
 'VSS_CG13': CDS_PINID='VSS_CG13';
NODE_NAME     U25 CG15
 '@T6G_MB_LIB.T6G(SCH_1):PAGE32_I15@PURE_QUANTA.GENOA_SP5(CHIPS)':
 'VSS_CG15': CDS_PINID='VSS_CG15';
NODE_NAME     U25 CG20
 '@T6G_MB_LIB.T6G(SCH_1):PAGE32_I15@PURE_QUANTA.GENOA_SP5(CHIPS)':
 'VSS_CG20': CDS_PINID='VSS_CG20';
NODE_NAME     U25 CG22
 '@T6G_MB_LIB.T6G(SCH_1):PAGE32_I15@PURE_QUANTA.GENOA_SP5(CHIPS)':
 'VSS_CG22': CDS_PINID='VSS_CG22';
NODE_NAME     U25 CG25
 '@T6G_MB_LIB.T6G(SCH_1):PAGE32_I15@PURE_QUANTA.GENOA_SP5(CHIPS)':
 'VSS_CG25': CDS_PINID='VSS_CG25';
NODE_NAME     U25 CG28
 '@T6G_MB_LIB.T6G(SCH_1):PAGE32_I15@PURE_QUANTA.GENOA_SP5(CHIPS)':
 'VSS_CG28': CDS_PINID='VSS_CG28';
NODE_NAME     U25 CG31
 '@T6G_MB_LIB.T6G(SCH_1):PAGE32_I15@PURE_QUANTA.GENOA_SP5(CHIPS)':
 'VSS_CG31': CDS_PINID='VSS_CG31';
NODE_NAME     U25 CG34
 '@T6G_MB_LIB.T6G(SCH_1):PAGE32_I15@PURE_QUANTA.GENOA_SP5(CHIPS)':
 'VSS_CG34': CDS_PINID='VSS_CG34';
NODE_NAME     U25 CG45
 '@T6G_MB_LIB.T6G(SCH_1):PAGE32_I15@PURE_QUANTA.GENOA_SP5(CHIPS)':
 'VSS_CG45': CDS_PINID='VSS_CG45';
NODE_NAME     U25 CG48
 '@T6G_MB_LIB.T6G(SCH_1):PAGE32_I15@PURE_QUANTA.GENOA_SP5(CHIPS)':
 'VSS_CG48': CDS_PINID='VSS_CG48';
NODE_NAME     U25 CG51
 '@T6G_MB_LIB.T6G(SCH_1):PAGE32_I15@PURE_QUANTA.GENOA_SP5(CHIPS)':
 'VSS_CG51': CDS_PINID='VSS_CG51';
NODE_NAME     U25 CG54
 '@T6G_MB_LIB.T6G(SCH_1):PAGE32_I15@PURE_QUANTA.GENOA_SP5(CHIPS)':
 'VSS_CG54': CDS_PINID='VSS_CG54';
NODE_NAME     U25 CG56
 '@T6G_MB_LIB.T6G(SCH_1):PAGE32_I15@PURE_QUANTA.GENOA_SP5(CHIPS)':
 'VSS_CG56': CDS_PINID='VSS_CG56';
NODE_NAME     U25 CG61
 '@T6G_MB_LIB.T6G(SCH_1):PAGE32_I15@PURE_QUANTA.GENOA_SP5(CHIPS)':
 'VSS_CG61': CDS_PINID='VSS_CG61';
NODE_NAME     U25 CG63
 '@T6G_MB_LIB.T6G(SCH_1):PAGE32_I15@PURE_QUANTA.GENOA_SP5(CHIPS)':
 'VSS_CG63': CDS_PINID='VSS_CG63';
NODE_NAME     U25 CG68
 '@T6G_MB_LIB.T6G(SCH_1):PAGE32_I15@PURE_QUANTA.GENOA_SP5(CHIPS)':
 'VSS_CG68': CDS_PINID='VSS_CG68';
NODE_NAME     U25 CG70
 '@T6G_MB_LIB.T6G(SCH_1):PAGE32_I15@PURE_QUANTA.GENOA_SP5(CHIPS)':
 'VSS_CG70': CDS_PINID='VSS_CG70';
NODE_NAME     U25 CG75
 '@T6G_MB_LIB.T6G(SCH_1):PAGE32_I15@PURE_QUANTA.GENOA_SP5(CHIPS)':
 'VSS_CG75': CDS_PINID='VSS_CG75';
NODE_NAME     U25 CH3
 '@T6G_MB_LIB.T6G(SCH_1):PAGE32_I15@PURE_QUANTA.GENOA_SP5(CHIPS)':
 'VSS_CH3': CDS_PINID='VSS_CH3';
NODE_NAME     U25 CH5
 '@T6G_MB_LIB.T6G(SCH_1):PAGE32_I15@PURE_QUANTA.GENOA_SP5(CHIPS)':
 'VSS_CH5': CDS_PINID='VSS_CH5';
NODE_NAME     U25 CH8
 '@T6G_MB_LIB.T6G(SCH_1):PAGE32_I15@PURE_QUANTA.GENOA_SP5(CHIPS)':
 'VSS_CH8': CDS_PINID='VSS_CH8';
NODE_NAME     U25 CH10
 '@T6G_MB_LIB.T6G(SCH_1):PAGE32_I15@PURE_QUANTA.GENOA_SP5(CHIPS)':
 'VSS_CH10': CDS_PINID='VSS_CH10';
NODE_NAME     U25 CH12
 '@T6G_MB_LIB.T6G(SCH_1):PAGE32_I15@PURE_QUANTA.GENOA_SP5(CHIPS)':
 'VSS_CH12': CDS_PINID='VSS_CH12';
NODE_NAME     U25 CH15
 '@T6G_MB_LIB.T6G(SCH_1):PAGE32_I15@PURE_QUANTA.GENOA_SP5(CHIPS)':
 'VSS_CH15': CDS_PINID='VSS_CH15';
NODE_NAME     U25 CH17
 '@T6G_MB_LIB.T6G(SCH_1):PAGE32_I15@PURE_QUANTA.GENOA_SP5(CHIPS)':
 'VSS_CH17': CDS_PINID='VSS_CH17';
NODE_NAME     U25 CH19
 '@T6G_MB_LIB.T6G(SCH_1):PAGE32_I15@PURE_QUANTA.GENOA_SP5(CHIPS)':
 'VSS_CH19': CDS_PINID='VSS_CH19';
NODE_NAME     U25 CH22
 '@T6G_MB_LIB.T6G(SCH_1):PAGE32_I15@PURE_QUANTA.GENOA_SP5(CHIPS)':
 'VSS_CH22': CDS_PINID='VSS_CH22';
NODE_NAME     U25 CH25
 '@T6G_MB_LIB.T6G(SCH_1):PAGE32_I15@PURE_QUANTA.GENOA_SP5(CHIPS)':
 'VSS_CH25': CDS_PINID='VSS_CH25';
NODE_NAME     U25 CH28
 '@T6G_MB_LIB.T6G(SCH_1):PAGE32_I15@PURE_QUANTA.GENOA_SP5(CHIPS)':
 'VSS_CH28': CDS_PINID='VSS_CH28';
NODE_NAME     U25 CH31
 '@T6G_MB_LIB.T6G(SCH_1):PAGE32_I15@PURE_QUANTA.GENOA_SP5(CHIPS)':
 'VSS_CH31': CDS_PINID='VSS_CH31';
NODE_NAME     U25 CH34
 '@T6G_MB_LIB.T6G(SCH_1):PAGE32_I15@PURE_QUANTA.GENOA_SP5(CHIPS)':
 'VSS_CH34': CDS_PINID='VSS_CH34';
NODE_NAME     U25 CH37
 '@T6G_MB_LIB.T6G(SCH_1):PAGE32_I15@PURE_QUANTA.GENOA_SP5(CHIPS)':
 'VSS_CH37': CDS_PINID='VSS_CH37';
NODE_NAME     U25 CH39
 '@T6G_MB_LIB.T6G(SCH_1):PAGE32_I15@PURE_QUANTA.GENOA_SP5(CHIPS)':
 'VSS_CH39': CDS_PINID='VSS_CH39';
NODE_NAME     U25 CH42
 '@T6G_MB_LIB.T6G(SCH_1):PAGE32_I15@PURE_QUANTA.GENOA_SP5(CHIPS)':
 'VSS_CH42': CDS_PINID='VSS_CH42';
NODE_NAME     U25 CH45
 '@T6G_MB_LIB.T6G(SCH_1):PAGE32_I15@PURE_QUANTA.GENOA_SP5(CHIPS)':
 'VSS_CH45': CDS_PINID='VSS_CH45';
NODE_NAME     U25 CH48
 '@T6G_MB_LIB.T6G(SCH_1):PAGE32_I15@PURE_QUANTA.GENOA_SP5(CHIPS)':
 'VSS_CH48': CDS_PINID='VSS_CH48';
NODE_NAME     U25 CH51
 '@T6G_MB_LIB.T6G(SCH_1):PAGE32_I15@PURE_QUANTA.GENOA_SP5(CHIPS)':
 'VSS_CH51': CDS_PINID='VSS_CH51';
NODE_NAME     U25 CH54
 '@T6G_MB_LIB.T6G(SCH_1):PAGE32_I15@PURE_QUANTA.GENOA_SP5(CHIPS)':
 'VSS_CH54': CDS_PINID='VSS_CH54';
NODE_NAME     U25 CH57
 '@T6G_MB_LIB.T6G(SCH_1):PAGE32_I15@PURE_QUANTA.GENOA_SP5(CHIPS)':
 'VSS_CH57': CDS_PINID='VSS_CH57';
NODE_NAME     U25 CH59
 '@T6G_MB_LIB.T6G(SCH_1):PAGE32_I15@PURE_QUANTA.GENOA_SP5(CHIPS)':
 'VSS_CH59': CDS_PINID='VSS_CH59';
NODE_NAME     U25 CH61
 '@T6G_MB_LIB.T6G(SCH_1):PAGE32_I15@PURE_QUANTA.GENOA_SP5(CHIPS)':
 'VSS_CH61': CDS_PINID='VSS_CH61';
NODE_NAME     U25 CH64
 '@T6G_MB_LIB.T6G(SCH_1):PAGE32_I15@PURE_QUANTA.GENOA_SP5(CHIPS)':
 'VSS_CH64': CDS_PINID='VSS_CH64';
NODE_NAME     U25 CH66
 '@T6G_MB_LIB.T6G(SCH_1):PAGE32_I15@PURE_QUANTA.GENOA_SP5(CHIPS)':
 'VSS_CH66': CDS_PINID='VSS_CH66';
NODE_NAME     U25 CH68
 '@T6G_MB_LIB.T6G(SCH_1):PAGE32_I15@PURE_QUANTA.GENOA_SP5(CHIPS)':
 'VSS_CH68': CDS_PINID='VSS_CH68';
NODE_NAME     U25 CH71
 '@T6G_MB_LIB.T6G(SCH_1):PAGE32_I15@PURE_QUANTA.GENOA_SP5(CHIPS)':
 'VSS_CH71': CDS_PINID='VSS_CH71';
NODE_NAME     U25 CH73
 '@T6G_MB_LIB.T6G(SCH_1):PAGE32_I15@PURE_QUANTA.GENOA_SP5(CHIPS)':
 'VSS_CH73': CDS_PINID='VSS_CH73';
NODE_NAME     U25 CJ1
 '@T6G_MB_LIB.T6G(SCH_1):PAGE32_I15@PURE_QUANTA.GENOA_SP5(CHIPS)':
 'VSS_CJ1': CDS_PINID='VSS_CJ1';
NODE_NAME     U25 CJ4
 '@T6G_MB_LIB.T6G(SCH_1):PAGE32_I15@PURE_QUANTA.GENOA_SP5(CHIPS)':
 'VSS_CJ4': CDS_PINID='VSS_CJ4';
NODE_NAME     U25 CJ6
 '@T6G_MB_LIB.T6G(SCH_1):PAGE32_I15@PURE_QUANTA.GENOA_SP5(CHIPS)':
 'VSS_CJ6': CDS_PINID='VSS_CJ6';
NODE_NAME     U25 CJ8
 '@T6G_MB_LIB.T6G(SCH_1):PAGE32_I15@PURE_QUANTA.GENOA_SP5(CHIPS)':
 'VSS_CJ8': CDS_PINID='VSS_CJ8';
NODE_NAME     U25 CJ11
 '@T6G_MB_LIB.T6G(SCH_1):PAGE32_I15@PURE_QUANTA.GENOA_SP5(CHIPS)':
 'VSS_CJ11': CDS_PINID='VSS_CJ11';
NODE_NAME     U25 CJ13
 '@T6G_MB_LIB.T6G(SCH_1):PAGE32_I15@PURE_QUANTA.GENOA_SP5(CHIPS)':
 'VSS_CJ13': CDS_PINID='VSS_CJ13';
NODE_NAME     U25 CJ15
 '@T6G_MB_LIB.T6G(SCH_1):PAGE32_I15@PURE_QUANTA.GENOA_SP5(CHIPS)':
 'VSS_CJ15': CDS_PINID='VSS_CJ15';
NODE_NAME     U25 CJ18
 '@T6G_MB_LIB.T6G(SCH_1):PAGE32_I15@PURE_QUANTA.GENOA_SP5(CHIPS)':
 'VSS_CJ18': CDS_PINID='VSS_CJ18';
NODE_NAME     U25 CJ20
 '@T6G_MB_LIB.T6G(SCH_1):PAGE32_I15@PURE_QUANTA.GENOA_SP5(CHIPS)':
 'VSS_CJ20': CDS_PINID='VSS_CJ20';
NODE_NAME     U25 CJ23
 '@T6G_MB_LIB.T6G(SCH_1):PAGE32_I15@PURE_QUANTA.GENOA_SP5(CHIPS)':
 'VSS_CJ23': CDS_PINID='VSS_CJ23';
NODE_NAME     U25 CJ31
 '@T6G_MB_LIB.T6G(SCH_1):PAGE32_I15@PURE_QUANTA.GENOA_SP5(CHIPS)':
 'VSS_CJ31': CDS_PINID='VSS_CJ31';
NODE_NAME     U25 CJ34
 '@T6G_MB_LIB.T6G(SCH_1):PAGE32_I15@PURE_QUANTA.GENOA_SP5(CHIPS)':
 'VSS_CJ34': CDS_PINID='VSS_CJ34';
NODE_NAME     U25 CJ35
 '@T6G_MB_LIB.T6G(SCH_1):PAGE32_I15@PURE_QUANTA.GENOA_SP5(CHIPS)':
 'VSS_CJ35': CDS_PINID='VSS_CJ35';
NODE_NAME     U25 CJ36
 '@T6G_MB_LIB.T6G(SCH_1):PAGE32_I15@PURE_QUANTA.GENOA_SP5(CHIPS)':
 'VSS_CJ36': CDS_PINID='VSS_CJ36';
NODE_NAME     U25 CJ40
 '@T6G_MB_LIB.T6G(SCH_1):PAGE32_I15@PURE_QUANTA.GENOA_SP5(CHIPS)':
 'VSS_CJ40': CDS_PINID='VSS_CJ40';
NODE_NAME     U25 CJ41
 '@T6G_MB_LIB.T6G(SCH_1):PAGE32_I15@PURE_QUANTA.GENOA_SP5(CHIPS)':
 'VSS_CJ41': CDS_PINID='VSS_CJ41';
NODE_NAME     U25 CJ42
 '@T6G_MB_LIB.T6G(SCH_1):PAGE32_I15@PURE_QUANTA.GENOA_SP5(CHIPS)':
 'VSS_CJ42': CDS_PINID='VSS_CJ42';
NODE_NAME     U25 CJ45
 '@T6G_MB_LIB.T6G(SCH_1):PAGE32_I15@PURE_QUANTA.GENOA_SP5(CHIPS)':
 'VSS_CJ45': CDS_PINID='VSS_CJ45';
NODE_NAME     U25 CJ56
 '@T6G_MB_LIB.T6G(SCH_1):PAGE32_I15@PURE_QUANTA.GENOA_SP5(CHIPS)':
 'VSS_CJ56': CDS_PINID='VSS_CJ56';
NODE_NAME     U25 CJ58
 '@T6G_MB_LIB.T6G(SCH_1):PAGE32_I15@PURE_QUANTA.GENOA_SP5(CHIPS)':
 'VSS_CJ58': CDS_PINID='VSS_CJ58';
NODE_NAME     U25 CJ61
 '@T6G_MB_LIB.T6G(SCH_1):PAGE32_I15@PURE_QUANTA.GENOA_SP5(CHIPS)':
 'VSS_CJ61': CDS_PINID='VSS_CJ61';
NODE_NAME     U25 CJ63
 '@T6G_MB_LIB.T6G(SCH_1):PAGE32_I15@PURE_QUANTA.GENOA_SP5(CHIPS)':
 'VSS_CJ63': CDS_PINID='VSS_CJ63';
NODE_NAME     U25 CJ65
 '@T6G_MB_LIB.T6G(SCH_1):PAGE32_I15@PURE_QUANTA.GENOA_SP5(CHIPS)':
 'VSS_CJ65': CDS_PINID='VSS_CJ65';
NODE_NAME     U25 CJ68
 '@T6G_MB_LIB.T6G(SCH_1):PAGE32_I15@PURE_QUANTA.GENOA_SP5(CHIPS)':
 'VSS_CJ68': CDS_PINID='VSS_CJ68';
NODE_NAME     U25 CJ70
 '@T6G_MB_LIB.T6G(SCH_1):PAGE32_I15@PURE_QUANTA.GENOA_SP5(CHIPS)':
 'VSS_CJ70': CDS_PINID='VSS_CJ70';
NODE_NAME     U25 CJ72
 '@T6G_MB_LIB.T6G(SCH_1):PAGE32_I15@PURE_QUANTA.GENOA_SP5(CHIPS)':
 'VSS_CJ72': CDS_PINID='VSS_CJ72';
NODE_NAME     U25 CJ75
 '@T6G_MB_LIB.T6G(SCH_1):PAGE32_I15@PURE_QUANTA.GENOA_SP5(CHIPS)':
 'VSS_CJ75': CDS_PINID='VSS_CJ75';
NODE_NAME     U25 CK3
 '@T6G_MB_LIB.T6G(SCH_1):PAGE32_I15@PURE_QUANTA.GENOA_SP5(CHIPS)':
 'VSS_CK3': CDS_PINID='VSS_CK3';
NODE_NAME     U25 CK8
 '@T6G_MB_LIB.T6G(SCH_1):PAGE32_I15@PURE_QUANTA.GENOA_SP5(CHIPS)':
 'VSS_CK8': CDS_PINID='VSS_CK8';
NODE_NAME     U25 CK15
 '@T6G_MB_LIB.T6G(SCH_1):PAGE32_I15@PURE_QUANTA.GENOA_SP5(CHIPS)':
 'VSS_CK15': CDS_PINID='VSS_CK15';
NODE_NAME     U25 CK17
 '@T6G_MB_LIB.T6G(SCH_1):PAGE32_I15@PURE_QUANTA.GENOA_SP5(CHIPS)':
 'VSS_CK17': CDS_PINID='VSS_CK17';
NODE_NAME     U25 CK22
 '@T6G_MB_LIB.T6G(SCH_1):PAGE32_I15@PURE_QUANTA.GENOA_SP5(CHIPS)':
 'VSS_CK22': CDS_PINID='VSS_CK22';
NODE_NAME     U25 CK23
 '@T6G_MB_LIB.T6G(SCH_1):PAGE32_I15@PURE_QUANTA.GENOA_SP5(CHIPS)':
 'VSS_CK23': CDS_PINID='VSS_CK23';
NODE_NAME     U25 CK24
 '@T6G_MB_LIB.T6G(SCH_1):PAGE32_I15@PURE_QUANTA.GENOA_SP5(CHIPS)':
 'VSS_CK24': CDS_PINID='VSS_CK24';
NODE_NAME     U25 CK25
 '@T6G_MB_LIB.T6G(SCH_1):PAGE32_I15@PURE_QUANTA.GENOA_SP5(CHIPS)':
 'VSS_CK25': CDS_PINID='VSS_CK25';
NODE_NAME     U25 CK26
 '@T6G_MB_LIB.T6G(SCH_1):PAGE32_I15@PURE_QUANTA.GENOA_SP5(CHIPS)':
 'VSS_CK26': CDS_PINID='VSS_CK26';
NODE_NAME     U25 CK27
 '@T6G_MB_LIB.T6G(SCH_1):PAGE32_I15@PURE_QUANTA.GENOA_SP5(CHIPS)':
 'VSS_CK27': CDS_PINID='VSS_CK27';
NODE_NAME     U25 CK28
 '@T6G_MB_LIB.T6G(SCH_1):PAGE32_I15@PURE_QUANTA.GENOA_SP5(CHIPS)':
 'VSS_CK28': CDS_PINID='VSS_CK28';
NODE_NAME     U25 CK32
 '@T6G_MB_LIB.T6G(SCH_1):PAGE32_I15@PURE_QUANTA.GENOA_SP5(CHIPS)':
 'VSS_CK32': CDS_PINID='VSS_CK32';
NODE_NAME     U25 CK33
 '@T6G_MB_LIB.T6G(SCH_1):PAGE32_I15@PURE_QUANTA.GENOA_SP5(CHIPS)':
 'VSS_CK33': CDS_PINID='VSS_CK33';
NODE_NAME     U25 CK34
 '@T6G_MB_LIB.T6G(SCH_1):PAGE32_I15@PURE_QUANTA.GENOA_SP5(CHIPS)':
 'VSS_CK34': CDS_PINID='VSS_CK34';
NODE_NAME     U25 CK37
 '@T6G_MB_LIB.T6G(SCH_1):PAGE32_I15@PURE_QUANTA.GENOA_SP5(CHIPS)':
 'VSS_CK37': CDS_PINID='VSS_CK37';
NODE_NAME     U25 CK39
 '@T6G_MB_LIB.T6G(SCH_1):PAGE32_I15@PURE_QUANTA.GENOA_SP5(CHIPS)':
 'VSS_CK39': CDS_PINID='VSS_CK39';
NODE_NAME     U25 CK42
 '@T6G_MB_LIB.T6G(SCH_1):PAGE32_I15@PURE_QUANTA.GENOA_SP5(CHIPS)':
 'VSS_CK42': CDS_PINID='VSS_CK42';
NODE_NAME     U25 CK43
 '@T6G_MB_LIB.T6G(SCH_1):PAGE32_I15@PURE_QUANTA.GENOA_SP5(CHIPS)':
 'VSS_CK43': CDS_PINID='VSS_CK43';
NODE_NAME     U25 CK44
 '@T6G_MB_LIB.T6G(SCH_1):PAGE32_I15@PURE_QUANTA.GENOA_SP5(CHIPS)':
 'VSS_CK44': CDS_PINID='VSS_CK44';
NODE_NAME     U25 CK45
 '@T6G_MB_LIB.T6G(SCH_1):PAGE32_I15@PURE_QUANTA.GENOA_SP5(CHIPS)':
 'VSS_CK45': CDS_PINID='VSS_CK45';
NODE_NAME     U25 CK48
 '@T6G_MB_LIB.T6G(SCH_1):PAGE32_I15@PURE_QUANTA.GENOA_SP5(CHIPS)':
 'VSS_CK48': CDS_PINID='VSS_CK48';
NODE_NAME     U25 CK49
 '@T6G_MB_LIB.T6G(SCH_1):PAGE32_I15@PURE_QUANTA.GENOA_SP5(CHIPS)':
 'VSS_CK49': CDS_PINID='VSS_CK49';
NODE_NAME     U25 CK50
 '@T6G_MB_LIB.T6G(SCH_1):PAGE32_I15@PURE_QUANTA.GENOA_SP5(CHIPS)':
 'VSS_CK50': CDS_PINID='VSS_CK50';
NODE_NAME     U25 CK51
 '@T6G_MB_LIB.T6G(SCH_1):PAGE32_I15@PURE_QUANTA.GENOA_SP5(CHIPS)':
 'VSS_CK51': CDS_PINID='VSS_CK51';
NODE_NAME     U25 CK52
 '@T6G_MB_LIB.T6G(SCH_1):PAGE32_I15@PURE_QUANTA.GENOA_SP5(CHIPS)':
 'VSS_CK52': CDS_PINID='VSS_CK52';
NODE_NAME     U25 CK53
 '@T6G_MB_LIB.T6G(SCH_1):PAGE32_I15@PURE_QUANTA.GENOA_SP5(CHIPS)':
 'VSS_CK53': CDS_PINID='VSS_CK53';
NODE_NAME     U25 CK54
 '@T6G_MB_LIB.T6G(SCH_1):PAGE32_I15@PURE_QUANTA.GENOA_SP5(CHIPS)':
 'VSS_CK54': CDS_PINID='VSS_CK54';
NODE_NAME     U25 CK59
 '@T6G_MB_LIB.T6G(SCH_1):PAGE32_I15@PURE_QUANTA.GENOA_SP5(CHIPS)':
 'VSS_CK59': CDS_PINID='VSS_CK59';
NODE_NAME     U25 CK61
 '@T6G_MB_LIB.T6G(SCH_1):PAGE32_I15@PURE_QUANTA.GENOA_SP5(CHIPS)':
 'VSS_CK61': CDS_PINID='VSS_CK61';
NODE_NAME     U25 CK66
 '@T6G_MB_LIB.T6G(SCH_1):PAGE32_I15@PURE_QUANTA.GENOA_SP5(CHIPS)':
 'VSS_CK66': CDS_PINID='VSS_CK66';
NODE_NAME     U25 CK68
 '@T6G_MB_LIB.T6G(SCH_1):PAGE32_I15@PURE_QUANTA.GENOA_SP5(CHIPS)':
 'VSS_CK68': CDS_PINID='VSS_CK68';
NODE_NAME     U25 CK73
 '@T6G_MB_LIB.T6G(SCH_1):PAGE32_I15@PURE_QUANTA.GENOA_SP5(CHIPS)':
 'VSS_CK73': CDS_PINID='VSS_CK73';
NODE_NAME     U25 CL1
 '@T6G_MB_LIB.T6G(SCH_1):PAGE32_I15@PURE_QUANTA.GENOA_SP5(CHIPS)':
 'VSS_CL1': CDS_PINID='VSS_CL1';
NODE_NAME     U25 CL4
 '@T6G_MB_LIB.T6G(SCH_1):PAGE32_I15@PURE_QUANTA.GENOA_SP5(CHIPS)':
 'VSS_CL4': CDS_PINID='VSS_CL4';
NODE_NAME     U25 CL6
 '@T6G_MB_LIB.T6G(SCH_1):PAGE32_I15@PURE_QUANTA.GENOA_SP5(CHIPS)':
 'VSS_CL6': CDS_PINID='VSS_CL6';
NODE_NAME     U25 CL8
 '@T6G_MB_LIB.T6G(SCH_1):PAGE32_I15@PURE_QUANTA.GENOA_SP5(CHIPS)':
 'VSS_CL8': CDS_PINID='VSS_CL8';
NODE_NAME     U25 CL11
 '@T6G_MB_LIB.T6G(SCH_1):PAGE32_I15@PURE_QUANTA.GENOA_SP5(CHIPS)':
 'VSS_CL11': CDS_PINID='VSS_CL11';
NODE_NAME     U25 CL13
 '@T6G_MB_LIB.T6G(SCH_1):PAGE32_I15@PURE_QUANTA.GENOA_SP5(CHIPS)':
 'VSS_CL13': CDS_PINID='VSS_CL13';
NODE_NAME     U25 CL15
 '@T6G_MB_LIB.T6G(SCH_1):PAGE32_I15@PURE_QUANTA.GENOA_SP5(CHIPS)':
 'VSS_CL15': CDS_PINID='VSS_CL15';
NODE_NAME     U25 CL18
 '@T6G_MB_LIB.T6G(SCH_1):PAGE32_I15@PURE_QUANTA.GENOA_SP5(CHIPS)':
 'VSS_CL18': CDS_PINID='VSS_CL18';
NODE_NAME     U25 CL20
 '@T6G_MB_LIB.T6G(SCH_1):PAGE32_I15@PURE_QUANTA.GENOA_SP5(CHIPS)':
 'VSS_CL20': CDS_PINID='VSS_CL20';
NODE_NAME     U25 CL22
 '@T6G_MB_LIB.T6G(SCH_1):PAGE32_I15@PURE_QUANTA.GENOA_SP5(CHIPS)':
 'VSS_CL22': CDS_PINID='VSS_CL22';
NODE_NAME     U25 CL25
 '@T6G_MB_LIB.T6G(SCH_1):PAGE32_I15@PURE_QUANTA.GENOA_SP5(CHIPS)':
 'VSS_CL25': CDS_PINID='VSS_CL25';
NODE_NAME     U25 CL28
 '@T6G_MB_LIB.T6G(SCH_1):PAGE32_I15@PURE_QUANTA.GENOA_SP5(CHIPS)':
 'VSS_CL28': CDS_PINID='VSS_CL28';
NODE_NAME     U25 CL31
 '@T6G_MB_LIB.T6G(SCH_1):PAGE32_I15@PURE_QUANTA.GENOA_SP5(CHIPS)':
 'VSS_CL31': CDS_PINID='VSS_CL31';
NODE_NAME     U25 CL34
 '@T6G_MB_LIB.T6G(SCH_1):PAGE32_I15@PURE_QUANTA.GENOA_SP5(CHIPS)':
 'VSS_CL34': CDS_PINID='VSS_CL34';
NODE_NAME     U25 CL35
 '@T6G_MB_LIB.T6G(SCH_1):PAGE32_I15@PURE_QUANTA.GENOA_SP5(CHIPS)':
 'VSS_CL35': CDS_PINID='VSS_CL35';
NODE_NAME     U25 CL36
 '@T6G_MB_LIB.T6G(SCH_1):PAGE32_I15@PURE_QUANTA.GENOA_SP5(CHIPS)':
 'VSS_CL36': CDS_PINID='VSS_CL36';
NODE_NAME     U25 CL40
 '@T6G_MB_LIB.T6G(SCH_1):PAGE32_I15@PURE_QUANTA.GENOA_SP5(CHIPS)':
 'VSS_CL40': CDS_PINID='VSS_CL40';
NODE_NAME     U25 CL41
 '@T6G_MB_LIB.T6G(SCH_1):PAGE32_I15@PURE_QUANTA.GENOA_SP5(CHIPS)':
 'VSS_CL41': CDS_PINID='VSS_CL41';
NODE_NAME     U25 CL42
 '@T6G_MB_LIB.T6G(SCH_1):PAGE32_I15@PURE_QUANTA.GENOA_SP5(CHIPS)':
 'VSS_CL42': CDS_PINID='VSS_CL42';
NODE_NAME     U25 CL45
 '@T6G_MB_LIB.T6G(SCH_1):PAGE32_I15@PURE_QUANTA.GENOA_SP5(CHIPS)':
 'VSS_CL45': CDS_PINID='VSS_CL45';
NODE_NAME     U25 CL48
 '@T6G_MB_LIB.T6G(SCH_1):PAGE32_I15@PURE_QUANTA.GENOA_SP5(CHIPS)':
 'VSS_CL48': CDS_PINID='VSS_CL48';
NODE_NAME     U25 CL51
 '@T6G_MB_LIB.T6G(SCH_1):PAGE32_I15@PURE_QUANTA.GENOA_SP5(CHIPS)':
 'VSS_CL51': CDS_PINID='VSS_CL51';
NODE_NAME     U25 CL54
 '@T6G_MB_LIB.T6G(SCH_1):PAGE32_I15@PURE_QUANTA.GENOA_SP5(CHIPS)':
 'VSS_CL54': CDS_PINID='VSS_CL54';
NODE_NAME     U25 CL56
 '@T6G_MB_LIB.T6G(SCH_1):PAGE32_I15@PURE_QUANTA.GENOA_SP5(CHIPS)':
 'VSS_CL56': CDS_PINID='VSS_CL56';
NODE_NAME     U25 CL58
 '@T6G_MB_LIB.T6G(SCH_1):PAGE32_I15@PURE_QUANTA.GENOA_SP5(CHIPS)':
 'VSS_CL58': CDS_PINID='VSS_CL58';
NODE_NAME     U25 CL61
 '@T6G_MB_LIB.T6G(SCH_1):PAGE32_I15@PURE_QUANTA.GENOA_SP5(CHIPS)':
 'VSS_CL61': CDS_PINID='VSS_CL61';
NODE_NAME     U25 CL63
 '@T6G_MB_LIB.T6G(SCH_1):PAGE32_I15@PURE_QUANTA.GENOA_SP5(CHIPS)':
 'VSS_CL63': CDS_PINID='VSS_CL63';
NODE_NAME     U25 CL65
 '@T6G_MB_LIB.T6G(SCH_1):PAGE32_I15@PURE_QUANTA.GENOA_SP5(CHIPS)':
 'VSS_CL65': CDS_PINID='VSS_CL65';
NODE_NAME     U25 CL68
 '@T6G_MB_LIB.T6G(SCH_1):PAGE32_I15@PURE_QUANTA.GENOA_SP5(CHIPS)':
 'VSS_CL68': CDS_PINID='VSS_CL68';
NODE_NAME     U25 CL70
 '@T6G_MB_LIB.T6G(SCH_1):PAGE32_I15@PURE_QUANTA.GENOA_SP5(CHIPS)':
 'VSS_CL70': CDS_PINID='VSS_CL70';
NODE_NAME     U25 CL72
 '@T6G_MB_LIB.T6G(SCH_1):PAGE32_I15@PURE_QUANTA.GENOA_SP5(CHIPS)':
 'VSS_CL72': CDS_PINID='VSS_CL72';
NODE_NAME     U25 CL75
 '@T6G_MB_LIB.T6G(SCH_1):PAGE32_I15@PURE_QUANTA.GENOA_SP5(CHIPS)':
 'VSS_CL75': CDS_PINID='VSS_CL75';
NODE_NAME     U25 CM3
 '@T6G_MB_LIB.T6G(SCH_1):PAGE32_I15@PURE_QUANTA.GENOA_SP5(CHIPS)':
 'VSS_CM3': CDS_PINID='VSS_CM3';
NODE_NAME     U25 CM5
 '@T6G_MB_LIB.T6G(SCH_1):PAGE32_I15@PURE_QUANTA.GENOA_SP5(CHIPS)':
 'VSS_CM5': CDS_PINID='VSS_CM5';
NODE_NAME     U25 CM8
 '@T6G_MB_LIB.T6G(SCH_1):PAGE32_I15@PURE_QUANTA.GENOA_SP5(CHIPS)':
 'VSS_CM8': CDS_PINID='VSS_CM8';
NODE_NAME     U25 CM10
 '@T6G_MB_LIB.T6G(SCH_1):PAGE32_I15@PURE_QUANTA.GENOA_SP5(CHIPS)':
 'VSS_CM10': CDS_PINID='VSS_CM10';
NODE_NAME     U25 CM12
 '@T6G_MB_LIB.T6G(SCH_1):PAGE32_I15@PURE_QUANTA.GENOA_SP5(CHIPS)':
 'VSS_CM12': CDS_PINID='VSS_CM12';
NODE_NAME     U25 CM15
 '@T6G_MB_LIB.T6G(SCH_1):PAGE32_I15@PURE_QUANTA.GENOA_SP5(CHIPS)':
 'VSS_CM15': CDS_PINID='VSS_CM15';
NODE_NAME     U25 CM17
 '@T6G_MB_LIB.T6G(SCH_1):PAGE32_I15@PURE_QUANTA.GENOA_SP5(CHIPS)':
 'VSS_CM17': CDS_PINID='VSS_CM17';
NODE_NAME     U25 CM19
 '@T6G_MB_LIB.T6G(SCH_1):PAGE32_I15@PURE_QUANTA.GENOA_SP5(CHIPS)':
 'VSS_CM19': CDS_PINID='VSS_CM19';
NODE_NAME     U25 CM23
 '@T6G_MB_LIB.T6G(SCH_1):PAGE32_I15@PURE_QUANTA.GENOA_SP5(CHIPS)':
 'VSS_CM23': CDS_PINID='VSS_CM23';
NODE_NAME     U25 CM24
 '@T6G_MB_LIB.T6G(SCH_1):PAGE32_I15@PURE_QUANTA.GENOA_SP5(CHIPS)':
 'VSS_CM24': CDS_PINID='VSS_CM24';
NODE_NAME     U25 CM25
 '@T6G_MB_LIB.T6G(SCH_1):PAGE32_I15@PURE_QUANTA.GENOA_SP5(CHIPS)':
 'VSS_CM25': CDS_PINID='VSS_CM25';
NODE_NAME     U25 CM26
 '@T6G_MB_LIB.T6G(SCH_1):PAGE32_I15@PURE_QUANTA.GENOA_SP5(CHIPS)':
 'VSS_CM26': CDS_PINID='VSS_CM26';
NODE_NAME     U25 CM27
 '@T6G_MB_LIB.T6G(SCH_1):PAGE32_I15@PURE_QUANTA.GENOA_SP5(CHIPS)':
 'VSS_CM27': CDS_PINID='VSS_CM27';
NODE_NAME     U25 CM28
 '@T6G_MB_LIB.T6G(SCH_1):PAGE32_I15@PURE_QUANTA.GENOA_SP5(CHIPS)':
 'VSS_CM28': CDS_PINID='VSS_CM28';
NODE_NAME     U25 CM29
 '@T6G_MB_LIB.T6G(SCH_1):PAGE32_I15@PURE_QUANTA.GENOA_SP5(CHIPS)':
 'VSS_CM29': CDS_PINID='VSS_CM29';
NODE_NAME     U25 CM30
 '@T6G_MB_LIB.T6G(SCH_1):PAGE32_I15@PURE_QUANTA.GENOA_SP5(CHIPS)':
 'VSS_CM30': CDS_PINID='VSS_CM30';
NODE_NAME     U25 CM31
 '@T6G_MB_LIB.T6G(SCH_1):PAGE32_I15@PURE_QUANTA.GENOA_SP5(CHIPS)':
 'VSS_CM31': CDS_PINID='VSS_CM31';
NODE_NAME     U25 CM32
 '@T6G_MB_LIB.T6G(SCH_1):PAGE32_I15@PURE_QUANTA.GENOA_SP5(CHIPS)':
 'VSS_CM32': CDS_PINID='VSS_CM32';
NODE_NAME     U25 CM33
 '@T6G_MB_LIB.T6G(SCH_1):PAGE32_I15@PURE_QUANTA.GENOA_SP5(CHIPS)':
 'VSS_CM33': CDS_PINID='VSS_CM33';
NODE_NAME     U25 CM34
 '@T6G_MB_LIB.T6G(SCH_1):PAGE32_I15@PURE_QUANTA.GENOA_SP5(CHIPS)':
 'VSS_CM34': CDS_PINID='VSS_CM34';
NODE_NAME     U25 CM37
 '@T6G_MB_LIB.T6G(SCH_1):PAGE32_I15@PURE_QUANTA.GENOA_SP5(CHIPS)':
 'VSS_CM37': CDS_PINID='VSS_CM37';
NODE_NAME     U25 CM39
 '@T6G_MB_LIB.T6G(SCH_1):PAGE32_I15@PURE_QUANTA.GENOA_SP5(CHIPS)':
 'VSS_CM39': CDS_PINID='VSS_CM39';
NODE_NAME     U25 CM42
 '@T6G_MB_LIB.T6G(SCH_1):PAGE32_I15@PURE_QUANTA.GENOA_SP5(CHIPS)':
 'VSS_CM42': CDS_PINID='VSS_CM42';
NODE_NAME     U25 CM43
 '@T6G_MB_LIB.T6G(SCH_1):PAGE32_I15@PURE_QUANTA.GENOA_SP5(CHIPS)':
 'VSS_CM43': CDS_PINID='VSS_CM43';
NODE_NAME     U25 CM44
 '@T6G_MB_LIB.T6G(SCH_1):PAGE32_I15@PURE_QUANTA.GENOA_SP5(CHIPS)':
 'VSS_CM44': CDS_PINID='VSS_CM44';
NODE_NAME     U25 CM45
 '@T6G_MB_LIB.T6G(SCH_1):PAGE32_I15@PURE_QUANTA.GENOA_SP5(CHIPS)':
 'VSS_CM45': CDS_PINID='VSS_CM45';
NODE_NAME     U25 CM46
 '@T6G_MB_LIB.T6G(SCH_1):PAGE32_I15@PURE_QUANTA.GENOA_SP5(CHIPS)':
 'VSS_CM46': CDS_PINID='VSS_CM46';
NODE_NAME     U25 CM47
 '@T6G_MB_LIB.T6G(SCH_1):PAGE32_I15@PURE_QUANTA.GENOA_SP5(CHIPS)':
 'VSS_CM47': CDS_PINID='VSS_CM47';
NODE_NAME     U25 CM48
 '@T6G_MB_LIB.T6G(SCH_1):PAGE32_I15@PURE_QUANTA.GENOA_SP5(CHIPS)':
 'VSS_CM48': CDS_PINID='VSS_CM48';
NODE_NAME     U25 CM49
 '@T6G_MB_LIB.T6G(SCH_1):PAGE32_I15@PURE_QUANTA.GENOA_SP5(CHIPS)':
 'VSS_CM49': CDS_PINID='VSS_CM49';
NODE_NAME     U25 CM51
 '@T6G_MB_LIB.T6G(SCH_1):PAGE32_I15@PURE_QUANTA.GENOA_SP5(CHIPS)':
 'VSS_CM51': CDS_PINID='VSS_CM51';
NODE_NAME     U25 CM52
 '@T6G_MB_LIB.T6G(SCH_1):PAGE32_I15@PURE_QUANTA.GENOA_SP5(CHIPS)':
 'VSS_CM52': CDS_PINID='VSS_CM52';
NODE_NAME     U25 CM53
 '@T6G_MB_LIB.T6G(SCH_1):PAGE32_I15@PURE_QUANTA.GENOA_SP5(CHIPS)':
 'VSS_CM53': CDS_PINID='VSS_CM53';
NODE_NAME     U25 CM57
 '@T6G_MB_LIB.T6G(SCH_1):PAGE32_I15@PURE_QUANTA.GENOA_SP5(CHIPS)':
 'VSS_CM57': CDS_PINID='VSS_CM57';
NODE_NAME     U25 CM59
 '@T6G_MB_LIB.T6G(SCH_1):PAGE32_I15@PURE_QUANTA.GENOA_SP5(CHIPS)':
 'VSS_CM59': CDS_PINID='VSS_CM59';
NODE_NAME     U25 CM61
 '@T6G_MB_LIB.T6G(SCH_1):PAGE32_I15@PURE_QUANTA.GENOA_SP5(CHIPS)':
 'VSS_CM61': CDS_PINID='VSS_CM61';
NODE_NAME     U25 CM64
 '@T6G_MB_LIB.T6G(SCH_1):PAGE32_I15@PURE_QUANTA.GENOA_SP5(CHIPS)':
 'VSS_CM64': CDS_PINID='VSS_CM64';
NODE_NAME     U25 CM66
 '@T6G_MB_LIB.T6G(SCH_1):PAGE32_I15@PURE_QUANTA.GENOA_SP5(CHIPS)':
 'VSS_CM66': CDS_PINID='VSS_CM66';
NODE_NAME     U25 CM68
 '@T6G_MB_LIB.T6G(SCH_1):PAGE32_I15@PURE_QUANTA.GENOA_SP5(CHIPS)':
 'VSS_CM68': CDS_PINID='VSS_CM68';
NODE_NAME     U25 CM71
 '@T6G_MB_LIB.T6G(SCH_1):PAGE32_I15@PURE_QUANTA.GENOA_SP5(CHIPS)':
 'VSS_CM71': CDS_PINID='VSS_CM71';
NODE_NAME     U25 CM73
 '@T6G_MB_LIB.T6G(SCH_1):PAGE32_I15@PURE_QUANTA.GENOA_SP5(CHIPS)':
 'VSS_CM73': CDS_PINID='VSS_CM73';
NODE_NAME     U25 CN1
 '@T6G_MB_LIB.T6G(SCH_1):PAGE32_I15@PURE_QUANTA.GENOA_SP5(CHIPS)':
 'VSS_CN1': CDS_PINID='VSS_CN1';
NODE_NAME     U25 CN6
 '@T6G_MB_LIB.T6G(SCH_1):PAGE32_I15@PURE_QUANTA.GENOA_SP5(CHIPS)':
 'VSS_CN6': CDS_PINID='VSS_CN6';
NODE_NAME     U25 CN8
 '@T6G_MB_LIB.T6G(SCH_1):PAGE32_I15@PURE_QUANTA.GENOA_SP5(CHIPS)':
 'VSS_CN8': CDS_PINID='VSS_CN8';
NODE_NAME     U25 CN13
 '@T6G_MB_LIB.T6G(SCH_1):PAGE32_I15@PURE_QUANTA.GENOA_SP5(CHIPS)':
 'VSS_CN13': CDS_PINID='VSS_CN13';
NODE_NAME     U25 CN15
 '@T6G_MB_LIB.T6G(SCH_1):PAGE32_I15@PURE_QUANTA.GENOA_SP5(CHIPS)':
 'VSS_CN15': CDS_PINID='VSS_CN15';
NODE_NAME     U25 CN20
 '@T6G_MB_LIB.T6G(SCH_1):PAGE32_I15@PURE_QUANTA.GENOA_SP5(CHIPS)':
 'VSS_CN20': CDS_PINID='VSS_CN20';
NODE_NAME     U25 CN22
 '@T6G_MB_LIB.T6G(SCH_1):PAGE32_I15@PURE_QUANTA.GENOA_SP5(CHIPS)':
 'VSS_CN22': CDS_PINID='VSS_CN22';
NODE_NAME     U25 CN25
 '@T6G_MB_LIB.T6G(SCH_1):PAGE32_I15@PURE_QUANTA.GENOA_SP5(CHIPS)':
 'VSS_CN25': CDS_PINID='VSS_CN25';
NODE_NAME     U25 CN28
 '@T6G_MB_LIB.T6G(SCH_1):PAGE32_I15@PURE_QUANTA.GENOA_SP5(CHIPS)':
 'VSS_CN28': CDS_PINID='VSS_CN28';
NODE_NAME     U25 CN31
 '@T6G_MB_LIB.T6G(SCH_1):PAGE32_I15@PURE_QUANTA.GENOA_SP5(CHIPS)':
 'VSS_CN31': CDS_PINID='VSS_CN31';
NODE_NAME     U25 CN34
 '@T6G_MB_LIB.T6G(SCH_1):PAGE32_I15@PURE_QUANTA.GENOA_SP5(CHIPS)':
 'VSS_CN34': CDS_PINID='VSS_CN34';
NODE_NAME     U25 CN42
 '@T6G_MB_LIB.T6G(SCH_1):PAGE32_I15@PURE_QUANTA.GENOA_SP5(CHIPS)':
 'VSS_CN42': CDS_PINID='VSS_CN42';
NODE_NAME     U25 CN45
 '@T6G_MB_LIB.T6G(SCH_1):PAGE32_I15@PURE_QUANTA.GENOA_SP5(CHIPS)':
 'VSS_CN45': CDS_PINID='VSS_CN45';
NODE_NAME     U25 CN48
 '@T6G_MB_LIB.T6G(SCH_1):PAGE32_I15@PURE_QUANTA.GENOA_SP5(CHIPS)':
 'VSS_CN48': CDS_PINID='VSS_CN48';
NODE_NAME     U25 CN51
 '@T6G_MB_LIB.T6G(SCH_1):PAGE32_I15@PURE_QUANTA.GENOA_SP5(CHIPS)':
 'VSS_CN51': CDS_PINID='VSS_CN51';
NODE_NAME     U25 CN56
 '@T6G_MB_LIB.T6G(SCH_1):PAGE32_I15@PURE_QUANTA.GENOA_SP5(CHIPS)':
 'VSS_CN56': CDS_PINID='VSS_CN56';
NODE_NAME     U25 CN61
 '@T6G_MB_LIB.T6G(SCH_1):PAGE32_I15@PURE_QUANTA.GENOA_SP5(CHIPS)':
 'VSS_CN61': CDS_PINID='VSS_CN61';
NODE_NAME     U25 CN63
 '@T6G_MB_LIB.T6G(SCH_1):PAGE32_I15@PURE_QUANTA.GENOA_SP5(CHIPS)':
 'VSS_CN63': CDS_PINID='VSS_CN63';
NODE_NAME     U25 CN68
 '@T6G_MB_LIB.T6G(SCH_1):PAGE32_I15@PURE_QUANTA.GENOA_SP5(CHIPS)':
 'VSS_CN68': CDS_PINID='VSS_CN68';
NODE_NAME     U25 CN70
 '@T6G_MB_LIB.T6G(SCH_1):PAGE32_I15@PURE_QUANTA.GENOA_SP5(CHIPS)':
 'VSS_CN70': CDS_PINID='VSS_CN70';
NODE_NAME     U25 CN75
 '@T6G_MB_LIB.T6G(SCH_1):PAGE32_I15@PURE_QUANTA.GENOA_SP5(CHIPS)':
 'VSS_CN75': CDS_PINID='VSS_CN75';
NODE_NAME     U25 CP3
 '@T6G_MB_LIB.T6G(SCH_1):PAGE32_I15@PURE_QUANTA.GENOA_SP5(CHIPS)':
 'VSS_CP3': CDS_PINID='VSS_CP3';
NODE_NAME     U25 CP5
 '@T6G_MB_LIB.T6G(SCH_1):PAGE32_I15@PURE_QUANTA.GENOA_SP5(CHIPS)':
 'VSS_CP5': CDS_PINID='VSS_CP5';
NODE_NAME     U25 CP8
 '@T6G_MB_LIB.T6G(SCH_1):PAGE32_I15@PURE_QUANTA.GENOA_SP5(CHIPS)':
 'VSS_CP8': CDS_PINID='VSS_CP8';
NODE_NAME     U25 CP10
 '@T6G_MB_LIB.T6G(SCH_1):PAGE32_I15@PURE_QUANTA.GENOA_SP5(CHIPS)':
 'VSS_CP10': CDS_PINID='VSS_CP10';
NODE_NAME     U25 CP12
 '@T6G_MB_LIB.T6G(SCH_1):PAGE32_I15@PURE_QUANTA.GENOA_SP5(CHIPS)':
 'VSS_CP12': CDS_PINID='VSS_CP12';
NODE_NAME     U25 CP15
 '@T6G_MB_LIB.T6G(SCH_1):PAGE32_I15@PURE_QUANTA.GENOA_SP5(CHIPS)':
 'VSS_CP15': CDS_PINID='VSS_CP15';
NODE_NAME     U25 CP17
 '@T6G_MB_LIB.T6G(SCH_1):PAGE32_I15@PURE_QUANTA.GENOA_SP5(CHIPS)':
 'VSS_CP17': CDS_PINID='VSS_CP17';
NODE_NAME     U25 CP19
 '@T6G_MB_LIB.T6G(SCH_1):PAGE32_I15@PURE_QUANTA.GENOA_SP5(CHIPS)':
 'VSS_CP19': CDS_PINID='VSS_CP19';
NODE_NAME     U25 CP22
 '@T6G_MB_LIB.T6G(SCH_1):PAGE32_I16@PURE_QUANTA.GENOA_SP5(CHIPS)':
 'VSS_CP22': CDS_PINID='VSS_CP22';
NODE_NAME     U25 CP25
 '@T6G_MB_LIB.T6G(SCH_1):PAGE32_I16@PURE_QUANTA.GENOA_SP5(CHIPS)':
 'VSS_CP25': CDS_PINID='VSS_CP25';
NODE_NAME     U25 CP28
 '@T6G_MB_LIB.T6G(SCH_1):PAGE32_I16@PURE_QUANTA.GENOA_SP5(CHIPS)':
 'VSS_CP28': CDS_PINID='VSS_CP28';
NODE_NAME     U25 CP31
 '@T6G_MB_LIB.T6G(SCH_1):PAGE32_I16@PURE_QUANTA.GENOA_SP5(CHIPS)':
 'VSS_CP31': CDS_PINID='VSS_CP31';
NODE_NAME     U25 CP34
 '@T6G_MB_LIB.T6G(SCH_1):PAGE32_I16@PURE_QUANTA.GENOA_SP5(CHIPS)':
 'VSS_CP34': CDS_PINID='VSS_CP34';
NODE_NAME     U25 CP37
 '@T6G_MB_LIB.T6G(SCH_1):PAGE32_I16@PURE_QUANTA.GENOA_SP5(CHIPS)':
 'VSS_CP37': CDS_PINID='VSS_CP37';
NODE_NAME     U25 CP39
 '@T6G_MB_LIB.T6G(SCH_1):PAGE32_I16@PURE_QUANTA.GENOA_SP5(CHIPS)':
 'VSS_CP39': CDS_PINID='VSS_CP39';
NODE_NAME     U25 CP42
 '@T6G_MB_LIB.T6G(SCH_1):PAGE32_I16@PURE_QUANTA.GENOA_SP5(CHIPS)':
 'VSS_CP42': CDS_PINID='VSS_CP42';
NODE_NAME     U25 CP45
 '@T6G_MB_LIB.T6G(SCH_1):PAGE32_I16@PURE_QUANTA.GENOA_SP5(CHIPS)':
 'VSS_CP45': CDS_PINID='VSS_CP45';
NODE_NAME     U25 CP48
 '@T6G_MB_LIB.T6G(SCH_1):PAGE32_I16@PURE_QUANTA.GENOA_SP5(CHIPS)':
 'VSS_CP48': CDS_PINID='VSS_CP48';
NODE_NAME     U25 CP51
 '@T6G_MB_LIB.T6G(SCH_1):PAGE32_I16@PURE_QUANTA.GENOA_SP5(CHIPS)':
 'VSS_CP51': CDS_PINID='VSS_CP51';
NODE_NAME     U25 CP54
 '@T6G_MB_LIB.T6G(SCH_1):PAGE32_I16@PURE_QUANTA.GENOA_SP5(CHIPS)':
 'VSS_CP54': CDS_PINID='VSS_CP54';
NODE_NAME     U25 CP57
 '@T6G_MB_LIB.T6G(SCH_1):PAGE32_I16@PURE_QUANTA.GENOA_SP5(CHIPS)':
 'VSS_CP57': CDS_PINID='VSS_CP57';
NODE_NAME     U25 CP59
 '@T6G_MB_LIB.T6G(SCH_1):PAGE32_I16@PURE_QUANTA.GENOA_SP5(CHIPS)':
 'VSS_CP59': CDS_PINID='VSS_CP59';
NODE_NAME     U25 CP61
 '@T6G_MB_LIB.T6G(SCH_1):PAGE32_I16@PURE_QUANTA.GENOA_SP5(CHIPS)':
 'VSS_CP61': CDS_PINID='VSS_CP61';
NODE_NAME     U25 CP64
 '@T6G_MB_LIB.T6G(SCH_1):PAGE32_I16@PURE_QUANTA.GENOA_SP5(CHIPS)':
 'VSS_CP64': CDS_PINID='VSS_CP64';
NODE_NAME     U25 CP66
 '@T6G_MB_LIB.T6G(SCH_1):PAGE32_I16@PURE_QUANTA.GENOA_SP5(CHIPS)':
 'VSS_CP66': CDS_PINID='VSS_CP66';
NODE_NAME     U25 CP68
 '@T6G_MB_LIB.T6G(SCH_1):PAGE32_I16@PURE_QUANTA.GENOA_SP5(CHIPS)':
 'VSS_CP68': CDS_PINID='VSS_CP68';
NODE_NAME     U25 CP71
 '@T6G_MB_LIB.T6G(SCH_1):PAGE32_I16@PURE_QUANTA.GENOA_SP5(CHIPS)':
 'VSS_CP71': CDS_PINID='VSS_CP71';
NODE_NAME     U25 CP73
 '@T6G_MB_LIB.T6G(SCH_1):PAGE32_I16@PURE_QUANTA.GENOA_SP5(CHIPS)':
 'VSS_CP73': CDS_PINID='VSS_CP73';
NODE_NAME     U25 CR1
 '@T6G_MB_LIB.T6G(SCH_1):PAGE32_I16@PURE_QUANTA.GENOA_SP5(CHIPS)':
 'VSS_CR1': CDS_PINID='VSS_CR1';
NODE_NAME     U25 CR4
 '@T6G_MB_LIB.T6G(SCH_1):PAGE32_I16@PURE_QUANTA.GENOA_SP5(CHIPS)':
 'VSS_CR4': CDS_PINID='VSS_CR4';
NODE_NAME     U25 CR6
 '@T6G_MB_LIB.T6G(SCH_1):PAGE32_I16@PURE_QUANTA.GENOA_SP5(CHIPS)':
 'VSS_CR6': CDS_PINID='VSS_CR6';
NODE_NAME     U25 CR8
 '@T6G_MB_LIB.T6G(SCH_1):PAGE32_I16@PURE_QUANTA.GENOA_SP5(CHIPS)':
 'VSS_CR8': CDS_PINID='VSS_CR8';
NODE_NAME     U25 CR11
 '@T6G_MB_LIB.T6G(SCH_1):PAGE32_I16@PURE_QUANTA.GENOA_SP5(CHIPS)':
 'VSS_CR11': CDS_PINID='VSS_CR11';
NODE_NAME     U25 CR13
 '@T6G_MB_LIB.T6G(SCH_1):PAGE32_I16@PURE_QUANTA.GENOA_SP5(CHIPS)':
 'VSS_CR13': CDS_PINID='VSS_CR13';
NODE_NAME     U25 CR15
 '@T6G_MB_LIB.T6G(SCH_1):PAGE32_I16@PURE_QUANTA.GENOA_SP5(CHIPS)':
 'VSS_CR15': CDS_PINID='VSS_CR15';
NODE_NAME     U25 CR18
 '@T6G_MB_LIB.T6G(SCH_1):PAGE32_I16@PURE_QUANTA.GENOA_SP5(CHIPS)':
 'VSS_CR18': CDS_PINID='VSS_CR18';
NODE_NAME     U25 CR20
 '@T6G_MB_LIB.T6G(SCH_1):PAGE32_I16@PURE_QUANTA.GENOA_SP5(CHIPS)':
 'VSS_CR20': CDS_PINID='VSS_CR20';
NODE_NAME     U25 CR22
 '@T6G_MB_LIB.T6G(SCH_1):PAGE32_I16@PURE_QUANTA.GENOA_SP5(CHIPS)':
 'VSS_CR22': CDS_PINID='VSS_CR22';
NODE_NAME     U25 CR25
 '@T6G_MB_LIB.T6G(SCH_1):PAGE32_I16@PURE_QUANTA.GENOA_SP5(CHIPS)':
 'VSS_CR25': CDS_PINID='VSS_CR25';
NODE_NAME     U25 CR28
 '@T6G_MB_LIB.T6G(SCH_1):PAGE32_I16@PURE_QUANTA.GENOA_SP5(CHIPS)':
 'VSS_CR28': CDS_PINID='VSS_CR28';
NODE_NAME     U25 CR31
 '@T6G_MB_LIB.T6G(SCH_1):PAGE32_I16@PURE_QUANTA.GENOA_SP5(CHIPS)':
 'VSS_CR31': CDS_PINID='VSS_CR31';
NODE_NAME     U25 CR34
 '@T6G_MB_LIB.T6G(SCH_1):PAGE32_I16@PURE_QUANTA.GENOA_SP5(CHIPS)':
 'VSS_CR34': CDS_PINID='VSS_CR34';
NODE_NAME     U25 CR35
 '@T6G_MB_LIB.T6G(SCH_1):PAGE32_I16@PURE_QUANTA.GENOA_SP5(CHIPS)':
 'VSS_CR35': CDS_PINID='VSS_CR35';
NODE_NAME     U25 CR36
 '@T6G_MB_LIB.T6G(SCH_1):PAGE32_I16@PURE_QUANTA.GENOA_SP5(CHIPS)':
 'VSS_CR36': CDS_PINID='VSS_CR36';
NODE_NAME     U25 CR40
 '@T6G_MB_LIB.T6G(SCH_1):PAGE32_I16@PURE_QUANTA.GENOA_SP5(CHIPS)':
 'VSS_CR40': CDS_PINID='VSS_CR40';
NODE_NAME     U25 CR41
 '@T6G_MB_LIB.T6G(SCH_1):PAGE32_I16@PURE_QUANTA.GENOA_SP5(CHIPS)':
 'VSS_CR41': CDS_PINID='VSS_CR41';
NODE_NAME     U25 CR42
 '@T6G_MB_LIB.T6G(SCH_1):PAGE32_I16@PURE_QUANTA.GENOA_SP5(CHIPS)':
 'VSS_CR42': CDS_PINID='VSS_CR42';
NODE_NAME     U25 CR45
 '@T6G_MB_LIB.T6G(SCH_1):PAGE32_I16@PURE_QUANTA.GENOA_SP5(CHIPS)':
 'VSS_CR45': CDS_PINID='VSS_CR45';
NODE_NAME     U25 CR48
 '@T6G_MB_LIB.T6G(SCH_1):PAGE32_I16@PURE_QUANTA.GENOA_SP5(CHIPS)':
 'VSS_CR48': CDS_PINID='VSS_CR48';
NODE_NAME     U25 CR51
 '@T6G_MB_LIB.T6G(SCH_1):PAGE32_I16@PURE_QUANTA.GENOA_SP5(CHIPS)':
 'VSS_CR51': CDS_PINID='VSS_CR51';
NODE_NAME     U25 CR54
 '@T6G_MB_LIB.T6G(SCH_1):PAGE32_I16@PURE_QUANTA.GENOA_SP5(CHIPS)':
 'VSS_CR54': CDS_PINID='VSS_CR54';
NODE_NAME     U25 CR56
 '@T6G_MB_LIB.T6G(SCH_1):PAGE32_I16@PURE_QUANTA.GENOA_SP5(CHIPS)':
 'VSS_CR56': CDS_PINID='VSS_CR56';
NODE_NAME     U25 CR58
 '@T6G_MB_LIB.T6G(SCH_1):PAGE32_I16@PURE_QUANTA.GENOA_SP5(CHIPS)':
 'VSS_CR58': CDS_PINID='VSS_CR58';
NODE_NAME     U25 CR61
 '@T6G_MB_LIB.T6G(SCH_1):PAGE32_I16@PURE_QUANTA.GENOA_SP5(CHIPS)':
 'VSS_CR61': CDS_PINID='VSS_CR61';
NODE_NAME     U25 CR63
 '@T6G_MB_LIB.T6G(SCH_1):PAGE32_I16@PURE_QUANTA.GENOA_SP5(CHIPS)':
 'VSS_CR63': CDS_PINID='VSS_CR63';
NODE_NAME     U25 CR65
 '@T6G_MB_LIB.T6G(SCH_1):PAGE32_I16@PURE_QUANTA.GENOA_SP5(CHIPS)':
 'VSS_CR65': CDS_PINID='VSS_CR65';
NODE_NAME     U25 CR68
 '@T6G_MB_LIB.T6G(SCH_1):PAGE32_I16@PURE_QUANTA.GENOA_SP5(CHIPS)':
 'VSS_CR68': CDS_PINID='VSS_CR68';
NODE_NAME     U25 CR70
 '@T6G_MB_LIB.T6G(SCH_1):PAGE32_I16@PURE_QUANTA.GENOA_SP5(CHIPS)':
 'VSS_CR70': CDS_PINID='VSS_CR70';
NODE_NAME     U25 CR72
 '@T6G_MB_LIB.T6G(SCH_1):PAGE32_I16@PURE_QUANTA.GENOA_SP5(CHIPS)':
 'VSS_CR72': CDS_PINID='VSS_CR72';
NODE_NAME     U25 CR75
 '@T6G_MB_LIB.T6G(SCH_1):PAGE32_I16@PURE_QUANTA.GENOA_SP5(CHIPS)':
 'VSS_CR75': CDS_PINID='VSS_CR75';
NODE_NAME     U25 CT3
 '@T6G_MB_LIB.T6G(SCH_1):PAGE32_I16@PURE_QUANTA.GENOA_SP5(CHIPS)':
 'VSS_CT3': CDS_PINID='VSS_CT3';
NODE_NAME     U25 CT8
 '@T6G_MB_LIB.T6G(SCH_1):PAGE32_I16@PURE_QUANTA.GENOA_SP5(CHIPS)':
 'VSS_CT8': CDS_PINID='VSS_CT8';
NODE_NAME     U25 CT10
 '@T6G_MB_LIB.T6G(SCH_1):PAGE32_I16@PURE_QUANTA.GENOA_SP5(CHIPS)':
 'VSS_CT10': CDS_PINID='VSS_CT10';
NODE_NAME     U25 CT15
 '@T6G_MB_LIB.T6G(SCH_1):PAGE32_I16@PURE_QUANTA.GENOA_SP5(CHIPS)':
 'VSS_CT15': CDS_PINID='VSS_CT15';
NODE_NAME     U25 CT17
 '@T6G_MB_LIB.T6G(SCH_1):PAGE32_I16@PURE_QUANTA.GENOA_SP5(CHIPS)':
 'VSS_CT17': CDS_PINID='VSS_CT17';
NODE_NAME     U25 CT23
 '@T6G_MB_LIB.T6G(SCH_1):PAGE32_I16@PURE_QUANTA.GENOA_SP5(CHIPS)':
 'VSS_CT23': CDS_PINID='VSS_CT23';
NODE_NAME     U25 CT24
 '@T6G_MB_LIB.T6G(SCH_1):PAGE32_I16@PURE_QUANTA.GENOA_SP5(CHIPS)':
 'VSS_CT24': CDS_PINID='VSS_CT24';
NODE_NAME     U25 CT25
 '@T6G_MB_LIB.T6G(SCH_1):PAGE32_I16@PURE_QUANTA.GENOA_SP5(CHIPS)':
 'VSS_CT25': CDS_PINID='VSS_CT25';
NODE_NAME     U25 CT26
 '@T6G_MB_LIB.T6G(SCH_1):PAGE32_I16@PURE_QUANTA.GENOA_SP5(CHIPS)':
 'VSS_CT26': CDS_PINID='VSS_CT26';
NODE_NAME     U25 CT27
 '@T6G_MB_LIB.T6G(SCH_1):PAGE32_I16@PURE_QUANTA.GENOA_SP5(CHIPS)':
 'VSS_CT27': CDS_PINID='VSS_CT27';
NODE_NAME     U25 CT28
 '@T6G_MB_LIB.T6G(SCH_1):PAGE32_I16@PURE_QUANTA.GENOA_SP5(CHIPS)':
 'VSS_CT28': CDS_PINID='VSS_CT28';
NODE_NAME     U25 CT29
 '@T6G_MB_LIB.T6G(SCH_1):PAGE32_I16@PURE_QUANTA.GENOA_SP5(CHIPS)':
 'VSS_CT29': CDS_PINID='VSS_CT29';
NODE_NAME     U25 CT30
 '@T6G_MB_LIB.T6G(SCH_1):PAGE32_I16@PURE_QUANTA.GENOA_SP5(CHIPS)':
 'VSS_CT30': CDS_PINID='VSS_CT30';
NODE_NAME     U25 CT31
 '@T6G_MB_LIB.T6G(SCH_1):PAGE32_I16@PURE_QUANTA.GENOA_SP5(CHIPS)':
 'VSS_CT31': CDS_PINID='VSS_CT31';
NODE_NAME     U25 CT32
 '@T6G_MB_LIB.T6G(SCH_1):PAGE32_I16@PURE_QUANTA.GENOA_SP5(CHIPS)':
 'VSS_CT32': CDS_PINID='VSS_CT32';
NODE_NAME     U25 CT33
 '@T6G_MB_LIB.T6G(SCH_1):PAGE32_I16@PURE_QUANTA.GENOA_SP5(CHIPS)':
 'VSS_CT33': CDS_PINID='VSS_CT33';
NODE_NAME     U25 CT34
 '@T6G_MB_LIB.T6G(SCH_1):PAGE32_I16@PURE_QUANTA.GENOA_SP5(CHIPS)':
 'VSS_CT34': CDS_PINID='VSS_CT34';
NODE_NAME     U25 CT37
 '@T6G_MB_LIB.T6G(SCH_1):PAGE32_I16@PURE_QUANTA.GENOA_SP5(CHIPS)':
 'VSS_CT37': CDS_PINID='VSS_CT37';
NODE_NAME     U25 CT39
 '@T6G_MB_LIB.T6G(SCH_1):PAGE32_I16@PURE_QUANTA.GENOA_SP5(CHIPS)':
 'VSS_CT39': CDS_PINID='VSS_CT39';
NODE_NAME     U25 CT42
 '@T6G_MB_LIB.T6G(SCH_1):PAGE32_I16@PURE_QUANTA.GENOA_SP5(CHIPS)':
 'VSS_CT42': CDS_PINID='VSS_CT42';
NODE_NAME     U25 CT43
 '@T6G_MB_LIB.T6G(SCH_1):PAGE32_I16@PURE_QUANTA.GENOA_SP5(CHIPS)':
 'VSS_CT43': CDS_PINID='VSS_CT43';
NODE_NAME     U25 CT44
 '@T6G_MB_LIB.T6G(SCH_1):PAGE32_I16@PURE_QUANTA.GENOA_SP5(CHIPS)':
 'VSS_CT44': CDS_PINID='VSS_CT44';
NODE_NAME     U25 CT45
 '@T6G_MB_LIB.T6G(SCH_1):PAGE32_I16@PURE_QUANTA.GENOA_SP5(CHIPS)':
 'VSS_CT45': CDS_PINID='VSS_CT45';
NODE_NAME     U25 CT46
 '@T6G_MB_LIB.T6G(SCH_1):PAGE32_I16@PURE_QUANTA.GENOA_SP5(CHIPS)':
 'VSS_CT46': CDS_PINID='VSS_CT46';
NODE_NAME     U25 CT47
 '@T6G_MB_LIB.T6G(SCH_1):PAGE32_I16@PURE_QUANTA.GENOA_SP5(CHIPS)':
 'VSS_CT47': CDS_PINID='VSS_CT47';
NODE_NAME     U25 CT48
 '@T6G_MB_LIB.T6G(SCH_1):PAGE32_I16@PURE_QUANTA.GENOA_SP5(CHIPS)':
 'VSS_CT48': CDS_PINID='VSS_CT48';
NODE_NAME     U25 CT49
 '@T6G_MB_LIB.T6G(SCH_1):PAGE32_I16@PURE_QUANTA.GENOA_SP5(CHIPS)':
 'VSS_CT49': CDS_PINID='VSS_CT49';
NODE_NAME     U25 CT50
 '@T6G_MB_LIB.T6G(SCH_1):PAGE32_I16@PURE_QUANTA.GENOA_SP5(CHIPS)':
 'VSS_CT50': CDS_PINID='VSS_CT50';
NODE_NAME     U25 CT51
 '@T6G_MB_LIB.T6G(SCH_1):PAGE32_I16@PURE_QUANTA.GENOA_SP5(CHIPS)':
 'VSS_CT51': CDS_PINID='VSS_CT51';
NODE_NAME     U25 CT53
 '@T6G_MB_LIB.T6G(SCH_1):PAGE32_I16@PURE_QUANTA.GENOA_SP5(CHIPS)':
 'VSS_CT53': CDS_PINID='VSS_CT53';
NODE_NAME     U25 CT59
 '@T6G_MB_LIB.T6G(SCH_1):PAGE32_I16@PURE_QUANTA.GENOA_SP5(CHIPS)':
 'VSS_CT59': CDS_PINID='VSS_CT59';
NODE_NAME     U25 CT61
 '@T6G_MB_LIB.T6G(SCH_1):PAGE32_I16@PURE_QUANTA.GENOA_SP5(CHIPS)':
 'VSS_CT61': CDS_PINID='VSS_CT61';
NODE_NAME     U25 CT66
 '@T6G_MB_LIB.T6G(SCH_1):PAGE32_I16@PURE_QUANTA.GENOA_SP5(CHIPS)':
 'VSS_CT66': CDS_PINID='VSS_CT66';
NODE_NAME     U25 CT68
 '@T6G_MB_LIB.T6G(SCH_1):PAGE32_I16@PURE_QUANTA.GENOA_SP5(CHIPS)':
 'VSS_CT68': CDS_PINID='VSS_CT68';
NODE_NAME     U25 CT73
 '@T6G_MB_LIB.T6G(SCH_1):PAGE32_I16@PURE_QUANTA.GENOA_SP5(CHIPS)':
 'VSS_CT73': CDS_PINID='VSS_CT73';
NODE_NAME     U25 CU1
 '@T6G_MB_LIB.T6G(SCH_1):PAGE32_I16@PURE_QUANTA.GENOA_SP5(CHIPS)':
 'VSS_CU1': CDS_PINID='VSS_CU1';
NODE_NAME     U25 CU4
 '@T6G_MB_LIB.T6G(SCH_1):PAGE32_I16@PURE_QUANTA.GENOA_SP5(CHIPS)':
 'VSS_CU4': CDS_PINID='VSS_CU4';
NODE_NAME     U25 CU6
 '@T6G_MB_LIB.T6G(SCH_1):PAGE32_I16@PURE_QUANTA.GENOA_SP5(CHIPS)':
 'VSS_CU6': CDS_PINID='VSS_CU6';
NODE_NAME     U25 CU8
 '@T6G_MB_LIB.T6G(SCH_1):PAGE32_I16@PURE_QUANTA.GENOA_SP5(CHIPS)':
 'VSS_CU8': CDS_PINID='VSS_CU8';
NODE_NAME     U25 CU11
 '@T6G_MB_LIB.T6G(SCH_1):PAGE32_I16@PURE_QUANTA.GENOA_SP5(CHIPS)':
 'VSS_CU11': CDS_PINID='VSS_CU11';
NODE_NAME     U25 CU13
 '@T6G_MB_LIB.T6G(SCH_1):PAGE32_I16@PURE_QUANTA.GENOA_SP5(CHIPS)':
 'VSS_CU13': CDS_PINID='VSS_CU13';
NODE_NAME     U25 CU15
 '@T6G_MB_LIB.T6G(SCH_1):PAGE32_I16@PURE_QUANTA.GENOA_SP5(CHIPS)':
 'VSS_CU15': CDS_PINID='VSS_CU15';
NODE_NAME     U25 CU18
 '@T6G_MB_LIB.T6G(SCH_1):PAGE32_I16@PURE_QUANTA.GENOA_SP5(CHIPS)':
 'VSS_CU18': CDS_PINID='VSS_CU18';
NODE_NAME     U25 CU20
 '@T6G_MB_LIB.T6G(SCH_1):PAGE32_I16@PURE_QUANTA.GENOA_SP5(CHIPS)':
 'VSS_CU20': CDS_PINID='VSS_CU20';
NODE_NAME     U25 CU22
 '@T6G_MB_LIB.T6G(SCH_1):PAGE32_I16@PURE_QUANTA.GENOA_SP5(CHIPS)':
 'VSS_CU22': CDS_PINID='VSS_CU22';
NODE_NAME     U25 CU25
 '@T6G_MB_LIB.T6G(SCH_1):PAGE32_I16@PURE_QUANTA.GENOA_SP5(CHIPS)':
 'VSS_CU25': CDS_PINID='VSS_CU25';
NODE_NAME     U25 CU28
 '@T6G_MB_LIB.T6G(SCH_1):PAGE32_I16@PURE_QUANTA.GENOA_SP5(CHIPS)':
 'VSS_CU28': CDS_PINID='VSS_CU28';
NODE_NAME     U25 CU31
 '@T6G_MB_LIB.T6G(SCH_1):PAGE32_I16@PURE_QUANTA.GENOA_SP5(CHIPS)':
 'VSS_CU31': CDS_PINID='VSS_CU31';
NODE_NAME     U25 CU34
 '@T6G_MB_LIB.T6G(SCH_1):PAGE32_I16@PURE_QUANTA.GENOA_SP5(CHIPS)':
 'VSS_CU34': CDS_PINID='VSS_CU34';
NODE_NAME     U25 CU42
 '@T6G_MB_LIB.T6G(SCH_1):PAGE32_I16@PURE_QUANTA.GENOA_SP5(CHIPS)':
 'VSS_CU42': CDS_PINID='VSS_CU42';
NODE_NAME     U25 CU45
 '@T6G_MB_LIB.T6G(SCH_1):PAGE32_I16@PURE_QUANTA.GENOA_SP5(CHIPS)':
 'VSS_CU45': CDS_PINID='VSS_CU45';
NODE_NAME     U25 CU48
 '@T6G_MB_LIB.T6G(SCH_1):PAGE32_I16@PURE_QUANTA.GENOA_SP5(CHIPS)':
 'VSS_CU48': CDS_PINID='VSS_CU48';
NODE_NAME     U25 CU51
 '@T6G_MB_LIB.T6G(SCH_1):PAGE32_I16@PURE_QUANTA.GENOA_SP5(CHIPS)':
 'VSS_CU51': CDS_PINID='VSS_CU51';
NODE_NAME     U25 CU54
 '@T6G_MB_LIB.T6G(SCH_1):PAGE32_I16@PURE_QUANTA.GENOA_SP5(CHIPS)':
 'VSS_CU54': CDS_PINID='VSS_CU54';
NODE_NAME     U25 CU56
 '@T6G_MB_LIB.T6G(SCH_1):PAGE32_I16@PURE_QUANTA.GENOA_SP5(CHIPS)':
 'VSS_CU56': CDS_PINID='VSS_CU56';
NODE_NAME     U25 CU61
 '@T6G_MB_LIB.T6G(SCH_1):PAGE32_I16@PURE_QUANTA.GENOA_SP5(CHIPS)':
 'VSS_CU61': CDS_PINID='VSS_CU61';
NODE_NAME     U25 CU63
 '@T6G_MB_LIB.T6G(SCH_1):PAGE32_I16@PURE_QUANTA.GENOA_SP5(CHIPS)':
 'VSS_CU63': CDS_PINID='VSS_CU63';
NODE_NAME     U25 CU65
 '@T6G_MB_LIB.T6G(SCH_1):PAGE32_I16@PURE_QUANTA.GENOA_SP5(CHIPS)':
 'VSS_CU65': CDS_PINID='VSS_CU65';
NODE_NAME     U25 CU68
 '@T6G_MB_LIB.T6G(SCH_1):PAGE32_I16@PURE_QUANTA.GENOA_SP5(CHIPS)':
 'VSS_CU68': CDS_PINID='VSS_CU68';
NODE_NAME     U25 CU70
 '@T6G_MB_LIB.T6G(SCH_1):PAGE32_I16@PURE_QUANTA.GENOA_SP5(CHIPS)':
 'VSS_CU70': CDS_PINID='VSS_CU70';
NODE_NAME     U25 CU72
 '@T6G_MB_LIB.T6G(SCH_1):PAGE32_I16@PURE_QUANTA.GENOA_SP5(CHIPS)':
 'VSS_CU72': CDS_PINID='VSS_CU72';
NODE_NAME     U25 CU75
 '@T6G_MB_LIB.T6G(SCH_1):PAGE32_I16@PURE_QUANTA.GENOA_SP5(CHIPS)':
 'VSS_CU75': CDS_PINID='VSS_CU75';
NODE_NAME     U25 CV3
 '@T6G_MB_LIB.T6G(SCH_1):PAGE32_I16@PURE_QUANTA.GENOA_SP5(CHIPS)':
 'VSS_CV3': CDS_PINID='VSS_CV3';
NODE_NAME     U25 CV5
 '@T6G_MB_LIB.T6G(SCH_1):PAGE32_I16@PURE_QUANTA.GENOA_SP5(CHIPS)':
 'VSS_CV5': CDS_PINID='VSS_CV5';
NODE_NAME     U25 CV8
 '@T6G_MB_LIB.T6G(SCH_1):PAGE32_I16@PURE_QUANTA.GENOA_SP5(CHIPS)':
 'VSS_CV8': CDS_PINID='VSS_CV8';
NODE_NAME     U25 CV10
 '@T6G_MB_LIB.T6G(SCH_1):PAGE32_I16@PURE_QUANTA.GENOA_SP5(CHIPS)':
 'VSS_CV10': CDS_PINID='VSS_CV10';
NODE_NAME     U25 CV12
 '@T6G_MB_LIB.T6G(SCH_1):PAGE32_I16@PURE_QUANTA.GENOA_SP5(CHIPS)':
 'VSS_CV12': CDS_PINID='VSS_CV12';
NODE_NAME     U25 CV15
 '@T6G_MB_LIB.T6G(SCH_1):PAGE32_I16@PURE_QUANTA.GENOA_SP5(CHIPS)':
 'VSS_CV15': CDS_PINID='VSS_CV15';
NODE_NAME     U25 CV17
 '@T6G_MB_LIB.T6G(SCH_1):PAGE32_I16@PURE_QUANTA.GENOA_SP5(CHIPS)':
 'VSS_CV17': CDS_PINID='VSS_CV17';
NODE_NAME     U25 CV19
 '@T6G_MB_LIB.T6G(SCH_1):PAGE32_I16@PURE_QUANTA.GENOA_SP5(CHIPS)':
 'VSS_CV19': CDS_PINID='VSS_CV19';
NODE_NAME     U25 CV22
 '@T6G_MB_LIB.T6G(SCH_1):PAGE32_I16@PURE_QUANTA.GENOA_SP5(CHIPS)':
 'VSS_CV22': CDS_PINID='VSS_CV22';
NODE_NAME     U25 CV25
 '@T6G_MB_LIB.T6G(SCH_1):PAGE32_I16@PURE_QUANTA.GENOA_SP5(CHIPS)':
 'VSS_CV25': CDS_PINID='VSS_CV25';
NODE_NAME     U25 CV28
 '@T6G_MB_LIB.T6G(SCH_1):PAGE32_I16@PURE_QUANTA.GENOA_SP5(CHIPS)':
 'VSS_CV28': CDS_PINID='VSS_CV28';
NODE_NAME     U25 CV31
 '@T6G_MB_LIB.T6G(SCH_1):PAGE32_I16@PURE_QUANTA.GENOA_SP5(CHIPS)':
 'VSS_CV31': CDS_PINID='VSS_CV31';
NODE_NAME     U25 CV34
 '@T6G_MB_LIB.T6G(SCH_1):PAGE32_I16@PURE_QUANTA.GENOA_SP5(CHIPS)':
 'VSS_CV34': CDS_PINID='VSS_CV34';
NODE_NAME     U25 CV37
 '@T6G_MB_LIB.T6G(SCH_1):PAGE32_I16@PURE_QUANTA.GENOA_SP5(CHIPS)':
 'VSS_CV37': CDS_PINID='VSS_CV37';
NODE_NAME     U25 CV39
 '@T6G_MB_LIB.T6G(SCH_1):PAGE32_I16@PURE_QUANTA.GENOA_SP5(CHIPS)':
 'VSS_CV39': CDS_PINID='VSS_CV39';
NODE_NAME     U25 CV42
 '@T6G_MB_LIB.T6G(SCH_1):PAGE32_I16@PURE_QUANTA.GENOA_SP5(CHIPS)':
 'VSS_CV42': CDS_PINID='VSS_CV42';
NODE_NAME     U25 CV45
 '@T6G_MB_LIB.T6G(SCH_1):PAGE32_I16@PURE_QUANTA.GENOA_SP5(CHIPS)':
 'VSS_CV45': CDS_PINID='VSS_CV45';
NODE_NAME     U25 CV48
 '@T6G_MB_LIB.T6G(SCH_1):PAGE32_I16@PURE_QUANTA.GENOA_SP5(CHIPS)':
 'VSS_CV48': CDS_PINID='VSS_CV48';
NODE_NAME     U25 CV51
 '@T6G_MB_LIB.T6G(SCH_1):PAGE32_I16@PURE_QUANTA.GENOA_SP5(CHIPS)':
 'VSS_CV51': CDS_PINID='VSS_CV51';
NODE_NAME     U25 CV54
 '@T6G_MB_LIB.T6G(SCH_1):PAGE32_I16@PURE_QUANTA.GENOA_SP5(CHIPS)':
 'VSS_CV54': CDS_PINID='VSS_CV54';
NODE_NAME     U25 CV57
 '@T6G_MB_LIB.T6G(SCH_1):PAGE32_I16@PURE_QUANTA.GENOA_SP5(CHIPS)':
 'VSS_CV57': CDS_PINID='VSS_CV57';
NODE_NAME     U25 CV59
 '@T6G_MB_LIB.T6G(SCH_1):PAGE32_I16@PURE_QUANTA.GENOA_SP5(CHIPS)':
 'VSS_CV59': CDS_PINID='VSS_CV59';
NODE_NAME     U25 CV61
 '@T6G_MB_LIB.T6G(SCH_1):PAGE32_I16@PURE_QUANTA.GENOA_SP5(CHIPS)':
 'VSS_CV61': CDS_PINID='VSS_CV61';
NODE_NAME     U25 CV64
 '@T6G_MB_LIB.T6G(SCH_1):PAGE32_I16@PURE_QUANTA.GENOA_SP5(CHIPS)':
 'VSS_CV64': CDS_PINID='VSS_CV64';
NODE_NAME     U25 CV66
 '@T6G_MB_LIB.T6G(SCH_1):PAGE32_I16@PURE_QUANTA.GENOA_SP5(CHIPS)':
 'VSS_CV66': CDS_PINID='VSS_CV66';
NODE_NAME     U25 CV68
 '@T6G_MB_LIB.T6G(SCH_1):PAGE32_I16@PURE_QUANTA.GENOA_SP5(CHIPS)':
 'VSS_CV68': CDS_PINID='VSS_CV68';
NODE_NAME     U25 CV71
 '@T6G_MB_LIB.T6G(SCH_1):PAGE32_I16@PURE_QUANTA.GENOA_SP5(CHIPS)':
 'VSS_CV71': CDS_PINID='VSS_CV71';
NODE_NAME     U25 CV73
 '@T6G_MB_LIB.T6G(SCH_1):PAGE32_I16@PURE_QUANTA.GENOA_SP5(CHIPS)':
 'VSS_CV73': CDS_PINID='VSS_CV73';
NODE_NAME     U25 CW1
 '@T6G_MB_LIB.T6G(SCH_1):PAGE32_I16@PURE_QUANTA.GENOA_SP5(CHIPS)':
 'VSS_CW1': CDS_PINID='VSS_CW1';
NODE_NAME     U25 CW6
 '@T6G_MB_LIB.T6G(SCH_1):PAGE32_I16@PURE_QUANTA.GENOA_SP5(CHIPS)':
 'VSS_CW6': CDS_PINID='VSS_CW6';
NODE_NAME     U25 CW8
 '@T6G_MB_LIB.T6G(SCH_1):PAGE32_I16@PURE_QUANTA.GENOA_SP5(CHIPS)':
 'VSS_CW8': CDS_PINID='VSS_CW8';
NODE_NAME     U25 CW13
 '@T6G_MB_LIB.T6G(SCH_1):PAGE32_I16@PURE_QUANTA.GENOA_SP5(CHIPS)':
 'VSS_CW13': CDS_PINID='VSS_CW13';
NODE_NAME     U25 CW15
 '@T6G_MB_LIB.T6G(SCH_1):PAGE32_I16@PURE_QUANTA.GENOA_SP5(CHIPS)':
 'VSS_CW15': CDS_PINID='VSS_CW15';
NODE_NAME     U25 CW20
 '@T6G_MB_LIB.T6G(SCH_1):PAGE32_I16@PURE_QUANTA.GENOA_SP5(CHIPS)':
 'VSS_CW20': CDS_PINID='VSS_CW20';
NODE_NAME     U25 CW22
 '@T6G_MB_LIB.T6G(SCH_1):PAGE32_I16@PURE_QUANTA.GENOA_SP5(CHIPS)':
 'VSS_CW22': CDS_PINID='VSS_CW22';
NODE_NAME     U25 CW25
 '@T6G_MB_LIB.T6G(SCH_1):PAGE32_I16@PURE_QUANTA.GENOA_SP5(CHIPS)':
 'VSS_CW25': CDS_PINID='VSS_CW25';
NODE_NAME     U25 CW28
 '@T6G_MB_LIB.T6G(SCH_1):PAGE32_I16@PURE_QUANTA.GENOA_SP5(CHIPS)':
 'VSS_CW28': CDS_PINID='VSS_CW28';
NODE_NAME     U25 CW31
 '@T6G_MB_LIB.T6G(SCH_1):PAGE32_I16@PURE_QUANTA.GENOA_SP5(CHIPS)':
 'VSS_CW31': CDS_PINID='VSS_CW31';
NODE_NAME     U25 CW34
 '@T6G_MB_LIB.T6G(SCH_1):PAGE32_I16@PURE_QUANTA.GENOA_SP5(CHIPS)':
 'VSS_CW34': CDS_PINID='VSS_CW34';
NODE_NAME     U25 CW35
 '@T6G_MB_LIB.T6G(SCH_1):PAGE32_I16@PURE_QUANTA.GENOA_SP5(CHIPS)':
 'VSS_CW35': CDS_PINID='VSS_CW35';
NODE_NAME     U25 CW36
 '@T6G_MB_LIB.T6G(SCH_1):PAGE32_I16@PURE_QUANTA.GENOA_SP5(CHIPS)':
 'VSS_CW36': CDS_PINID='VSS_CW36';
NODE_NAME     U25 CW40
 '@T6G_MB_LIB.T6G(SCH_1):PAGE32_I16@PURE_QUANTA.GENOA_SP5(CHIPS)':
 'VSS_CW40': CDS_PINID='VSS_CW40';
NODE_NAME     U25 CW41
 '@T6G_MB_LIB.T6G(SCH_1):PAGE32_I16@PURE_QUANTA.GENOA_SP5(CHIPS)':
 'VSS_CW41': CDS_PINID='VSS_CW41';
NODE_NAME     U25 CW42
 '@T6G_MB_LIB.T6G(SCH_1):PAGE32_I16@PURE_QUANTA.GENOA_SP5(CHIPS)':
 'VSS_CW42': CDS_PINID='VSS_CW42';
NODE_NAME     U25 CW45
 '@T6G_MB_LIB.T6G(SCH_1):PAGE32_I16@PURE_QUANTA.GENOA_SP5(CHIPS)':
 'VSS_CW45': CDS_PINID='VSS_CW45';
NODE_NAME     U25 CW48
 '@T6G_MB_LIB.T6G(SCH_1):PAGE32_I16@PURE_QUANTA.GENOA_SP5(CHIPS)':
 'VSS_CW48': CDS_PINID='VSS_CW48';
NODE_NAME     U25 CW51
 '@T6G_MB_LIB.T6G(SCH_1):PAGE32_I16@PURE_QUANTA.GENOA_SP5(CHIPS)':
 'VSS_CW51': CDS_PINID='VSS_CW51';
NODE_NAME     U25 CW54
 '@T6G_MB_LIB.T6G(SCH_1):PAGE32_I16@PURE_QUANTA.GENOA_SP5(CHIPS)':
 'VSS_CW54': CDS_PINID='VSS_CW54';
NODE_NAME     U25 CW56
 '@T6G_MB_LIB.T6G(SCH_1):PAGE32_I16@PURE_QUANTA.GENOA_SP5(CHIPS)':
 'VSS_CW56': CDS_PINID='VSS_CW56';
NODE_NAME     U25 CW61
 '@T6G_MB_LIB.T6G(SCH_1):PAGE32_I16@PURE_QUANTA.GENOA_SP5(CHIPS)':
 'VSS_CW61': CDS_PINID='VSS_CW61';
NODE_NAME     U25 CW63
 '@T6G_MB_LIB.T6G(SCH_1):PAGE32_I16@PURE_QUANTA.GENOA_SP5(CHIPS)':
 'VSS_CW63': CDS_PINID='VSS_CW63';
NODE_NAME     U25 CW68
 '@T6G_MB_LIB.T6G(SCH_1):PAGE32_I16@PURE_QUANTA.GENOA_SP5(CHIPS)':
 'VSS_CW68': CDS_PINID='VSS_CW68';
NODE_NAME     U25 CW70
 '@T6G_MB_LIB.T6G(SCH_1):PAGE32_I16@PURE_QUANTA.GENOA_SP5(CHIPS)':
 'VSS_CW70': CDS_PINID='VSS_CW70';
NODE_NAME     U25 CW75
 '@T6G_MB_LIB.T6G(SCH_1):PAGE32_I16@PURE_QUANTA.GENOA_SP5(CHIPS)':
 'VSS_CW75': CDS_PINID='VSS_CW75';
NODE_NAME     U25 CY3
 '@T6G_MB_LIB.T6G(SCH_1):PAGE32_I16@PURE_QUANTA.GENOA_SP5(CHIPS)':
 'VSS_CY3': CDS_PINID='VSS_CY3';
NODE_NAME     U25 CY5
 '@T6G_MB_LIB.T6G(SCH_1):PAGE32_I16@PURE_QUANTA.GENOA_SP5(CHIPS)':
 'VSS_CY5': CDS_PINID='VSS_CY5';
NODE_NAME     U25 CY8
 '@T6G_MB_LIB.T6G(SCH_1):PAGE32_I16@PURE_QUANTA.GENOA_SP5(CHIPS)':
 'VSS_CY8': CDS_PINID='VSS_CY8';
NODE_NAME     U25 CY10
 '@T6G_MB_LIB.T6G(SCH_1):PAGE32_I16@PURE_QUANTA.GENOA_SP5(CHIPS)':
 'VSS_CY10': CDS_PINID='VSS_CY10';
NODE_NAME     U25 CY12
 '@T6G_MB_LIB.T6G(SCH_1):PAGE32_I16@PURE_QUANTA.GENOA_SP5(CHIPS)':
 'VSS_CY12': CDS_PINID='VSS_CY12';
NODE_NAME     U25 CY15
 '@T6G_MB_LIB.T6G(SCH_1):PAGE32_I16@PURE_QUANTA.GENOA_SP5(CHIPS)':
 'VSS_CY15': CDS_PINID='VSS_CY15';
NODE_NAME     U25 CY17
 '@T6G_MB_LIB.T6G(SCH_1):PAGE32_I16@PURE_QUANTA.GENOA_SP5(CHIPS)':
 'VSS_CY17': CDS_PINID='VSS_CY17';
NODE_NAME     U25 CY19
 '@T6G_MB_LIB.T6G(SCH_1):PAGE32_I16@PURE_QUANTA.GENOA_SP5(CHIPS)':
 'VSS_CY19': CDS_PINID='VSS_CY19';
NODE_NAME     U25 CY23
 '@T6G_MB_LIB.T6G(SCH_1):PAGE32_I16@PURE_QUANTA.GENOA_SP5(CHIPS)':
 'VSS_CY23': CDS_PINID='VSS_CY23';
NODE_NAME     U25 CY24
 '@T6G_MB_LIB.T6G(SCH_1):PAGE32_I16@PURE_QUANTA.GENOA_SP5(CHIPS)':
 'VSS_CY24': CDS_PINID='VSS_CY24';
NODE_NAME     U25 CY25
 '@T6G_MB_LIB.T6G(SCH_1):PAGE32_I16@PURE_QUANTA.GENOA_SP5(CHIPS)':
 'VSS_CY25': CDS_PINID='VSS_CY25';
NODE_NAME     U25 CY26
 '@T6G_MB_LIB.T6G(SCH_1):PAGE32_I16@PURE_QUANTA.GENOA_SP5(CHIPS)':
 'VSS_CY26': CDS_PINID='VSS_CY26';
NODE_NAME     U25 CY27
 '@T6G_MB_LIB.T6G(SCH_1):PAGE32_I16@PURE_QUANTA.GENOA_SP5(CHIPS)':
 'VSS_CY27': CDS_PINID='VSS_CY27';
NODE_NAME     U25 CY28
 '@T6G_MB_LIB.T6G(SCH_1):PAGE32_I16@PURE_QUANTA.GENOA_SP5(CHIPS)':
 'VSS_CY28': CDS_PINID='VSS_CY28';
NODE_NAME     U25 CY29
 '@T6G_MB_LIB.T6G(SCH_1):PAGE32_I16@PURE_QUANTA.GENOA_SP5(CHIPS)':
 'VSS_CY29': CDS_PINID='VSS_CY29';
NODE_NAME     U25 CY30
 '@T6G_MB_LIB.T6G(SCH_1):PAGE32_I16@PURE_QUANTA.GENOA_SP5(CHIPS)':
 'VSS_CY30': CDS_PINID='VSS_CY30';
NODE_NAME     U25 CY31
 '@T6G_MB_LIB.T6G(SCH_1):PAGE32_I16@PURE_QUANTA.GENOA_SP5(CHIPS)':
 'VSS_CY31': CDS_PINID='VSS_CY31';
NODE_NAME     U25 CY32
 '@T6G_MB_LIB.T6G(SCH_1):PAGE32_I16@PURE_QUANTA.GENOA_SP5(CHIPS)':
 'VSS_CY32': CDS_PINID='VSS_CY32';
NODE_NAME     U25 CY33
 '@T6G_MB_LIB.T6G(SCH_1):PAGE32_I16@PURE_QUANTA.GENOA_SP5(CHIPS)':
 'VSS_CY33': CDS_PINID='VSS_CY33';
NODE_NAME     U25 CY34
 '@T6G_MB_LIB.T6G(SCH_1):PAGE32_I16@PURE_QUANTA.GENOA_SP5(CHIPS)':
 'VSS_CY34': CDS_PINID='VSS_CY34';
NODE_NAME     U25 CY37
 '@T6G_MB_LIB.T6G(SCH_1):PAGE32_I16@PURE_QUANTA.GENOA_SP5(CHIPS)':
 'VSS_CY37': CDS_PINID='VSS_CY37';
NODE_NAME     U25 CY39
 '@T6G_MB_LIB.T6G(SCH_1):PAGE32_I16@PURE_QUANTA.GENOA_SP5(CHIPS)':
 'VSS_CY39': CDS_PINID='VSS_CY39';
NODE_NAME     U25 CY42
 '@T6G_MB_LIB.T6G(SCH_1):PAGE32_I16@PURE_QUANTA.GENOA_SP5(CHIPS)':
 'VSS_CY42': CDS_PINID='VSS_CY42';
NODE_NAME     U25 CY43
 '@T6G_MB_LIB.T6G(SCH_1):PAGE32_I16@PURE_QUANTA.GENOA_SP5(CHIPS)':
 'VSS_CY43': CDS_PINID='VSS_CY43';
NODE_NAME     U25 CY44
 '@T6G_MB_LIB.T6G(SCH_1):PAGE32_I16@PURE_QUANTA.GENOA_SP5(CHIPS)':
 'VSS_CY44': CDS_PINID='VSS_CY44';
NODE_NAME     U25 CY45
 '@T6G_MB_LIB.T6G(SCH_1):PAGE32_I16@PURE_QUANTA.GENOA_SP5(CHIPS)':
 'VSS_CY45': CDS_PINID='VSS_CY45';
NODE_NAME     U25 CY46
 '@T6G_MB_LIB.T6G(SCH_1):PAGE32_I16@PURE_QUANTA.GENOA_SP5(CHIPS)':
 'VSS_CY46': CDS_PINID='VSS_CY46';
NODE_NAME     U25 CY47
 '@T6G_MB_LIB.T6G(SCH_1):PAGE32_I16@PURE_QUANTA.GENOA_SP5(CHIPS)':
 'VSS_CY47': CDS_PINID='VSS_CY47';
NODE_NAME     U25 CY48
 '@T6G_MB_LIB.T6G(SCH_1):PAGE32_I16@PURE_QUANTA.GENOA_SP5(CHIPS)':
 'VSS_CY48': CDS_PINID='VSS_CY48';
NODE_NAME     U25 CY49
 '@T6G_MB_LIB.T6G(SCH_1):PAGE32_I16@PURE_QUANTA.GENOA_SP5(CHIPS)':
 'VSS_CY49': CDS_PINID='VSS_CY49';
NODE_NAME     U25 CY50
 '@T6G_MB_LIB.T6G(SCH_1):PAGE32_I16@PURE_QUANTA.GENOA_SP5(CHIPS)':
 'VSS_CY50': CDS_PINID='VSS_CY50';
NODE_NAME     U25 CY51
 '@T6G_MB_LIB.T6G(SCH_1):PAGE32_I16@PURE_QUANTA.GENOA_SP5(CHIPS)':
 'VSS_CY51': CDS_PINID='VSS_CY51';
NODE_NAME     U25 CY52
 '@T6G_MB_LIB.T6G(SCH_1):PAGE32_I16@PURE_QUANTA.GENOA_SP5(CHIPS)':
 'VSS_CY52': CDS_PINID='VSS_CY52';
NODE_NAME     U25 CY53
 '@T6G_MB_LIB.T6G(SCH_1):PAGE32_I16@PURE_QUANTA.GENOA_SP5(CHIPS)':
 'VSS_CY53': CDS_PINID='VSS_CY53';
NODE_NAME     U25 CY59
 '@T6G_MB_LIB.T6G(SCH_1):PAGE32_I16@PURE_QUANTA.GENOA_SP5(CHIPS)':
 'VSS_CY59': CDS_PINID='VSS_CY59';
NODE_NAME     U25 CY61
 '@T6G_MB_LIB.T6G(SCH_1):PAGE32_I16@PURE_QUANTA.GENOA_SP5(CHIPS)':
 'VSS_CY61': CDS_PINID='VSS_CY61';
NODE_NAME     U25 CY64
 '@T6G_MB_LIB.T6G(SCH_1):PAGE32_I16@PURE_QUANTA.GENOA_SP5(CHIPS)':
 'VSS_CY64': CDS_PINID='VSS_CY64';
NODE_NAME     U25 CY66
 '@T6G_MB_LIB.T6G(SCH_1):PAGE32_I16@PURE_QUANTA.GENOA_SP5(CHIPS)':
 'VSS_CY66': CDS_PINID='VSS_CY66';
NODE_NAME     U25 CY68
 '@T6G_MB_LIB.T6G(SCH_1):PAGE32_I16@PURE_QUANTA.GENOA_SP5(CHIPS)':
 'VSS_CY68': CDS_PINID='VSS_CY68';
NODE_NAME     U25 CY71
 '@T6G_MB_LIB.T6G(SCH_1):PAGE32_I16@PURE_QUANTA.GENOA_SP5(CHIPS)':
 'VSS_CY71': CDS_PINID='VSS_CY71';
NODE_NAME     U25 CY73
 '@T6G_MB_LIB.T6G(SCH_1):PAGE32_I16@PURE_QUANTA.GENOA_SP5(CHIPS)':
 'VSS_CY73': CDS_PINID='VSS_CY73';
NODE_NAME     U25 DA1
 '@T6G_MB_LIB.T6G(SCH_1):PAGE32_I16@PURE_QUANTA.GENOA_SP5(CHIPS)':
 'VSS_DA1': CDS_PINID='VSS_DA1';
NODE_NAME     U25 DA4
 '@T6G_MB_LIB.T6G(SCH_1):PAGE32_I16@PURE_QUANTA.GENOA_SP5(CHIPS)':
 'VSS_DA4': CDS_PINID='VSS_DA4';
NODE_NAME     U25 DA6
 '@T6G_MB_LIB.T6G(SCH_1):PAGE32_I16@PURE_QUANTA.GENOA_SP5(CHIPS)':
 'VSS_DA6': CDS_PINID='VSS_DA6';
NODE_NAME     U25 DA8
 '@T6G_MB_LIB.T6G(SCH_1):PAGE32_I16@PURE_QUANTA.GENOA_SP5(CHIPS)':
 'VSS_DA8': CDS_PINID='VSS_DA8';
NODE_NAME     U25 DA11
 '@T6G_MB_LIB.T6G(SCH_1):PAGE32_I16@PURE_QUANTA.GENOA_SP5(CHIPS)':
 'VSS_DA11': CDS_PINID='VSS_DA11';
NODE_NAME     U25 DA13
 '@T6G_MB_LIB.T6G(SCH_1):PAGE32_I16@PURE_QUANTA.GENOA_SP5(CHIPS)':
 'VSS_DA13': CDS_PINID='VSS_DA13';
NODE_NAME     U25 DA15
 '@T6G_MB_LIB.T6G(SCH_1):PAGE32_I16@PURE_QUANTA.GENOA_SP5(CHIPS)':
 'VSS_DA15': CDS_PINID='VSS_DA15';
NODE_NAME     U25 DA18
 '@T6G_MB_LIB.T6G(SCH_1):PAGE32_I16@PURE_QUANTA.GENOA_SP5(CHIPS)':
 'VSS_DA18': CDS_PINID='VSS_DA18';
NODE_NAME     U25 DA20
 '@T6G_MB_LIB.T6G(SCH_1):PAGE32_I16@PURE_QUANTA.GENOA_SP5(CHIPS)':
 'VSS_DA20': CDS_PINID='VSS_DA20';
NODE_NAME     U25 DA22
 '@T6G_MB_LIB.T6G(SCH_1):PAGE32_I16@PURE_QUANTA.GENOA_SP5(CHIPS)':
 'VSS_DA22': CDS_PINID='VSS_DA22';
NODE_NAME     U25 DA25
 '@T6G_MB_LIB.T6G(SCH_1):PAGE32_I16@PURE_QUANTA.GENOA_SP5(CHIPS)':
 'VSS_DA25': CDS_PINID='VSS_DA25';
NODE_NAME     U25 DA28
 '@T6G_MB_LIB.T6G(SCH_1):PAGE32_I16@PURE_QUANTA.GENOA_SP5(CHIPS)':
 'VSS_DA28': CDS_PINID='VSS_DA28';
NODE_NAME     U25 DA31
 '@T6G_MB_LIB.T6G(SCH_1):PAGE32_I16@PURE_QUANTA.GENOA_SP5(CHIPS)':
 'VSS_DA31': CDS_PINID='VSS_DA31';
NODE_NAME     U25 DA34
 '@T6G_MB_LIB.T6G(SCH_1):PAGE32_I16@PURE_QUANTA.GENOA_SP5(CHIPS)':
 'VSS_DA34': CDS_PINID='VSS_DA34';
NODE_NAME     U25 DA42
 '@T6G_MB_LIB.T6G(SCH_1):PAGE32_I16@PURE_QUANTA.GENOA_SP5(CHIPS)':
 'VSS_DA42': CDS_PINID='VSS_DA42';
NODE_NAME     U25 DA45
 '@T6G_MB_LIB.T6G(SCH_1):PAGE32_I16@PURE_QUANTA.GENOA_SP5(CHIPS)':
 'VSS_DA45': CDS_PINID='VSS_DA45';
NODE_NAME     U25 DA48
 '@T6G_MB_LIB.T6G(SCH_1):PAGE32_I16@PURE_QUANTA.GENOA_SP5(CHIPS)':
 'VSS_DA48': CDS_PINID='VSS_DA48';
NODE_NAME     U25 DA51
 '@T6G_MB_LIB.T6G(SCH_1):PAGE32_I16@PURE_QUANTA.GENOA_SP5(CHIPS)':
 'VSS_DA51': CDS_PINID='VSS_DA51';
NODE_NAME     U25 DA54
 '@T6G_MB_LIB.T6G(SCH_1):PAGE32_I16@PURE_QUANTA.GENOA_SP5(CHIPS)':
 'VSS_DA54': CDS_PINID='VSS_DA54';
NODE_NAME     U25 DA58
 '@T6G_MB_LIB.T6G(SCH_1):PAGE32_I16@PURE_QUANTA.GENOA_SP5(CHIPS)':
 'VSS_DA58': CDS_PINID='VSS_DA58';
NODE_NAME     U25 DA61
 '@T6G_MB_LIB.T6G(SCH_1):PAGE32_I16@PURE_QUANTA.GENOA_SP5(CHIPS)':
 'VSS_DA61': CDS_PINID='VSS_DA61';
NODE_NAME     U25 DA63
 '@T6G_MB_LIB.T6G(SCH_1):PAGE32_I16@PURE_QUANTA.GENOA_SP5(CHIPS)':
 'VSS_DA63': CDS_PINID='VSS_DA63';
NODE_NAME     U25 DA65
 '@T6G_MB_LIB.T6G(SCH_1):PAGE32_I16@PURE_QUANTA.GENOA_SP5(CHIPS)':
 'VSS_DA65': CDS_PINID='VSS_DA65';
NODE_NAME     U25 DA68
 '@T6G_MB_LIB.T6G(SCH_1):PAGE32_I16@PURE_QUANTA.GENOA_SP5(CHIPS)':
 'VSS_DA68': CDS_PINID='VSS_DA68';
NODE_NAME     U25 DA70
 '@T6G_MB_LIB.T6G(SCH_1):PAGE32_I16@PURE_QUANTA.GENOA_SP5(CHIPS)':
 'VSS_DA70': CDS_PINID='VSS_DA70';
NODE_NAME     U25 AA42
 '@T6G_MB_LIB.T6G(SCH_1):PAGE33_I4@PURE_QUANTA.GENOA_SP5(CHIPS)':
 'VSS_AA42': CDS_PINID='VSS_AA42';
NODE_NAME     U25 AA72
 '@T6G_MB_LIB.T6G(SCH_1):PAGE33_I4@PURE_QUANTA.GENOA_SP5(CHIPS)':
 'VSS_AA72': CDS_PINID='VSS_AA72';
NODE_NAME     U25 AD31
 '@T6G_MB_LIB.T6G(SCH_1):PAGE33_I4@PURE_QUANTA.GENOA_SP5(CHIPS)':
 'VSS_AD31': CDS_PINID='VSS_AD31';
NODE_NAME     U25 AE4
 '@T6G_MB_LIB.T6G(SCH_1):PAGE33_I4@PURE_QUANTA.GENOA_SP5(CHIPS)':
 'VSS_AE4': CDS_PINID='VSS_AE4';
NODE_NAME     U25 AH33
 '@T6G_MB_LIB.T6G(SCH_1):PAGE33_I4@PURE_QUANTA.GENOA_SP5(CHIPS)':
 'VSS_AH33': CDS_PINID='VSS_AH33';
NODE_NAME     U25 AJ13
 '@T6G_MB_LIB.T6G(SCH_1):PAGE33_I4@PURE_QUANTA.GENOA_SP5(CHIPS)':
 'VSS_AJ13': CDS_PINID='VSS_AJ13';
NODE_NAME     U25 AM37
 '@T6G_MB_LIB.T6G(SCH_1):PAGE33_I4@PURE_QUANTA.GENOA_SP5(CHIPS)':
 'VSS_AM37': CDS_PINID='VSS_AM37';
NODE_NAME     U25 AN20
 '@T6G_MB_LIB.T6G(SCH_1):PAGE33_I4@PURE_QUANTA.GENOA_SP5(CHIPS)':
 'VSS_AN20': CDS_PINID='VSS_AN20';
NODE_NAME     U25 BV42
 '@T6G_MB_LIB.T6G(SCH_1):PAGE33_I4@PURE_QUANTA.GENOA_SP5(CHIPS)':
 'VSS_BV42': CDS_PINID='VSS_BV42';
NODE_NAME     U25 BW25
 '@T6G_MB_LIB.T6G(SCH_1):PAGE33_I4@PURE_QUANTA.GENOA_SP5(CHIPS)':
 'VSS_BW25': CDS_PINID='VSS_BW25';
NODE_NAME     U25 CB44
 '@T6G_MB_LIB.T6G(SCH_1):PAGE33_I4@PURE_QUANTA.GENOA_SP5(CHIPS)':
 'VSS_CB44': CDS_PINID='VSS_CB44';
NODE_NAME     U25 CC22
 '@T6G_MB_LIB.T6G(SCH_1):PAGE33_I4@PURE_QUANTA.GENOA_SP5(CHIPS)':
 'VSS_CC22': CDS_PINID='VSS_CC22';
NODE_NAME     U25 CF46
 '@T6G_MB_LIB.T6G(SCH_1):PAGE33_I4@PURE_QUANTA.GENOA_SP5(CHIPS)':
 'VSS_CF46': CDS_PINID='VSS_CF46';
NODE_NAME     U25 CG42
 '@T6G_MB_LIB.T6G(SCH_1):PAGE33_I4@PURE_QUANTA.GENOA_SP5(CHIPS)':
 'VSS_CG42': CDS_PINID='VSS_CG42';
NODE_NAME     U25 CK10
 '@T6G_MB_LIB.T6G(SCH_1):PAGE33_I4@PURE_QUANTA.GENOA_SP5(CHIPS)':
 'VSS_CK10': CDS_PINID='VSS_CK10';
NODE_NAME     U25 CK31
 '@T6G_MB_LIB.T6G(SCH_1):PAGE33_I4@PURE_QUANTA.GENOA_SP5(CHIPS)':
 'VSS_CK31': CDS_PINID='VSS_CK31';
NODE_NAME     U25 CM50
 '@T6G_MB_LIB.T6G(SCH_1):PAGE33_I4@PURE_QUANTA.GENOA_SP5(CHIPS)':
 'VSS_CM50': CDS_PINID='VSS_CM50';
NODE_NAME     U25 CN54
 '@T6G_MB_LIB.T6G(SCH_1):PAGE33_I4@PURE_QUANTA.GENOA_SP5(CHIPS)':
 'VSS_CN54': CDS_PINID='VSS_CN54';
NODE_NAME     U25 CT52
 '@T6G_MB_LIB.T6G(SCH_1):PAGE33_I4@PURE_QUANTA.GENOA_SP5(CHIPS)':
 'VSS_CT52': CDS_PINID='VSS_CT52';
NODE_NAME     U25 CU58
 '@T6G_MB_LIB.T6G(SCH_1):PAGE33_I4@PURE_QUANTA.GENOA_SP5(CHIPS)':
 'VSS_CU58': CDS_PINID='VSS_CU58';
NODE_NAME     U25 CY57
 '@T6G_MB_LIB.T6G(SCH_1):PAGE33_I4@PURE_QUANTA.GENOA_SP5(CHIPS)':
 'VSS_CY57': CDS_PINID='VSS_CY57';
NODE_NAME     U25 DA56
 '@T6G_MB_LIB.T6G(SCH_1):PAGE33_I4@PURE_QUANTA.GENOA_SP5(CHIPS)':
 'VSS_DA56': CDS_PINID='VSS_DA56';
NODE_NAME     U25 DA72
 '@T6G_MB_LIB.T6G(SCH_1):PAGE33_I4@PURE_QUANTA.GENOA_SP5(CHIPS)':
 'VSS_DA72': CDS_PINID='VSS_DA72';
NODE_NAME     U25 DA75
 '@T6G_MB_LIB.T6G(SCH_1):PAGE33_I4@PURE_QUANTA.GENOA_SP5(CHIPS)':
 'VSS_DA75': CDS_PINID='VSS_DA75';
NODE_NAME     U25 DB3
 '@T6G_MB_LIB.T6G(SCH_1):PAGE33_I4@PURE_QUANTA.GENOA_SP5(CHIPS)':
 'VSS_DB3': CDS_PINID='VSS_DB3';
NODE_NAME     U25 DB8
 '@T6G_MB_LIB.T6G(SCH_1):PAGE33_I4@PURE_QUANTA.GENOA_SP5(CHIPS)':
 'VSS_DB8': CDS_PINID='VSS_DB8';
NODE_NAME     U25 DB10
 '@T6G_MB_LIB.T6G(SCH_1):PAGE33_I4@PURE_QUANTA.GENOA_SP5(CHIPS)':
 'VSS_DB10': CDS_PINID='VSS_DB10';
NODE_NAME     U25 DB15
 '@T6G_MB_LIB.T6G(SCH_1):PAGE33_I4@PURE_QUANTA.GENOA_SP5(CHIPS)':
 'VSS_DB15': CDS_PINID='VSS_DB15';
NODE_NAME     U25 DB17
 '@T6G_MB_LIB.T6G(SCH_1):PAGE33_I4@PURE_QUANTA.GENOA_SP5(CHIPS)':
 'VSS_DB17': CDS_PINID='VSS_DB17';
NODE_NAME     U25 DB22
 '@T6G_MB_LIB.T6G(SCH_1):PAGE33_I4@PURE_QUANTA.GENOA_SP5(CHIPS)':
 'VSS_DB22': CDS_PINID='VSS_DB22';
NODE_NAME     U25 DB25
 '@T6G_MB_LIB.T6G(SCH_1):PAGE33_I4@PURE_QUANTA.GENOA_SP5(CHIPS)':
 'VSS_DB25': CDS_PINID='VSS_DB25';
NODE_NAME     U25 DB28
 '@T6G_MB_LIB.T6G(SCH_1):PAGE33_I4@PURE_QUANTA.GENOA_SP5(CHIPS)':
 'VSS_DB28': CDS_PINID='VSS_DB28';
NODE_NAME     U25 DB31
 '@T6G_MB_LIB.T6G(SCH_1):PAGE33_I4@PURE_QUANTA.GENOA_SP5(CHIPS)':
 'VSS_DB31': CDS_PINID='VSS_DB31';
NODE_NAME     U25 DB34
 '@T6G_MB_LIB.T6G(SCH_1):PAGE33_I4@PURE_QUANTA.GENOA_SP5(CHIPS)':
 'VSS_DB34': CDS_PINID='VSS_DB34';
NODE_NAME     U25 DB37
 '@T6G_MB_LIB.T6G(SCH_1):PAGE33_I4@PURE_QUANTA.GENOA_SP5(CHIPS)':
 'VSS_DB37': CDS_PINID='VSS_DB37';
NODE_NAME     U25 DB39
 '@T6G_MB_LIB.T6G(SCH_1):PAGE33_I4@PURE_QUANTA.GENOA_SP5(CHIPS)':
 'VSS_DB39': CDS_PINID='VSS_DB39';
NODE_NAME     U25 DB42
 '@T6G_MB_LIB.T6G(SCH_1):PAGE33_I4@PURE_QUANTA.GENOA_SP5(CHIPS)':
 'VSS_DB42': CDS_PINID='VSS_DB42';
NODE_NAME     U25 DB45
 '@T6G_MB_LIB.T6G(SCH_1):PAGE33_I4@PURE_QUANTA.GENOA_SP5(CHIPS)':
 'VSS_DB45': CDS_PINID='VSS_DB45';
NODE_NAME     U25 DB48
 '@T6G_MB_LIB.T6G(SCH_1):PAGE33_I4@PURE_QUANTA.GENOA_SP5(CHIPS)':
 'VSS_DB48': CDS_PINID='VSS_DB48';
NODE_NAME     U25 DB51
 '@T6G_MB_LIB.T6G(SCH_1):PAGE33_I4@PURE_QUANTA.GENOA_SP5(CHIPS)':
 'VSS_DB51': CDS_PINID='VSS_DB51';
NODE_NAME     U25 DB54
 '@T6G_MB_LIB.T6G(SCH_1):PAGE33_I4@PURE_QUANTA.GENOA_SP5(CHIPS)':
 'VSS_DB54': CDS_PINID='VSS_DB54';
NODE_NAME     U25 DB59
 '@T6G_MB_LIB.T6G(SCH_1):PAGE33_I4@PURE_QUANTA.GENOA_SP5(CHIPS)':
 'VSS_DB59': CDS_PINID='VSS_DB59';
NODE_NAME     U25 DB61
 '@T6G_MB_LIB.T6G(SCH_1):PAGE33_I4@PURE_QUANTA.GENOA_SP5(CHIPS)':
 'VSS_DB61': CDS_PINID='VSS_DB61';
NODE_NAME     U25 DB66
 '@T6G_MB_LIB.T6G(SCH_1):PAGE33_I4@PURE_QUANTA.GENOA_SP5(CHIPS)':
 'VSS_DB66': CDS_PINID='VSS_DB66';
NODE_NAME     U25 DB68
 '@T6G_MB_LIB.T6G(SCH_1):PAGE33_I4@PURE_QUANTA.GENOA_SP5(CHIPS)':
 'VSS_DB68': CDS_PINID='VSS_DB68';
NODE_NAME     U25 DB73
 '@T6G_MB_LIB.T6G(SCH_1):PAGE33_I4@PURE_QUANTA.GENOA_SP5(CHIPS)':
 'VSS_DB73': CDS_PINID='VSS_DB73';
NODE_NAME     U25 DC1
 '@T6G_MB_LIB.T6G(SCH_1):PAGE33_I4@PURE_QUANTA.GENOA_SP5(CHIPS)':
 'VSS_DC1': CDS_PINID='VSS_DC1';
NODE_NAME     U25 DC4
 '@T6G_MB_LIB.T6G(SCH_1):PAGE33_I4@PURE_QUANTA.GENOA_SP5(CHIPS)':
 'VSS_DC4': CDS_PINID='VSS_DC4';
NODE_NAME     U25 DC6
 '@T6G_MB_LIB.T6G(SCH_1):PAGE33_I4@PURE_QUANTA.GENOA_SP5(CHIPS)':
 'VSS_DC6': CDS_PINID='VSS_DC6';
NODE_NAME     U25 DC8
 '@T6G_MB_LIB.T6G(SCH_1):PAGE33_I4@PURE_QUANTA.GENOA_SP5(CHIPS)':
 'VSS_DC8': CDS_PINID='VSS_DC8';
NODE_NAME     U25 DC11
 '@T6G_MB_LIB.T6G(SCH_1):PAGE33_I4@PURE_QUANTA.GENOA_SP5(CHIPS)':
 'VSS_DC11': CDS_PINID='VSS_DC11';
NODE_NAME     U25 DC13
 '@T6G_MB_LIB.T6G(SCH_1):PAGE33_I4@PURE_QUANTA.GENOA_SP5(CHIPS)':
 'VSS_DC13': CDS_PINID='VSS_DC13';
NODE_NAME     U25 DC15
 '@T6G_MB_LIB.T6G(SCH_1):PAGE33_I4@PURE_QUANTA.GENOA_SP5(CHIPS)':
 'VSS_DC15': CDS_PINID='VSS_DC15';
NODE_NAME     U25 DC18
 '@T6G_MB_LIB.T6G(SCH_1):PAGE33_I4@PURE_QUANTA.GENOA_SP5(CHIPS)':
 'VSS_DC18': CDS_PINID='VSS_DC18';
NODE_NAME     U25 DC20
 '@T6G_MB_LIB.T6G(SCH_1):PAGE33_I4@PURE_QUANTA.GENOA_SP5(CHIPS)':
 'VSS_DC20': CDS_PINID='VSS_DC20';
NODE_NAME     U25 DC22
 '@T6G_MB_LIB.T6G(SCH_1):PAGE33_I4@PURE_QUANTA.GENOA_SP5(CHIPS)':
 'VSS_DC22': CDS_PINID='VSS_DC22';
NODE_NAME     U25 DC25
 '@T6G_MB_LIB.T6G(SCH_1):PAGE33_I4@PURE_QUANTA.GENOA_SP5(CHIPS)':
 'VSS_DC25': CDS_PINID='VSS_DC25';
NODE_NAME     U25 DC28
 '@T6G_MB_LIB.T6G(SCH_1):PAGE33_I4@PURE_QUANTA.GENOA_SP5(CHIPS)':
 'VSS_DC28': CDS_PINID='VSS_DC28';
NODE_NAME     U25 DC31
 '@T6G_MB_LIB.T6G(SCH_1):PAGE33_I4@PURE_QUANTA.GENOA_SP5(CHIPS)':
 'VSS_DC31': CDS_PINID='VSS_DC31';
NODE_NAME     U25 DC34
 '@T6G_MB_LIB.T6G(SCH_1):PAGE33_I4@PURE_QUANTA.GENOA_SP5(CHIPS)':
 'VSS_DC34': CDS_PINID='VSS_DC34';
NODE_NAME     U25 DC42
 '@T6G_MB_LIB.T6G(SCH_1):PAGE33_I4@PURE_QUANTA.GENOA_SP5(CHIPS)':
 'VSS_DC42': CDS_PINID='VSS_DC42';
NODE_NAME     U25 DC45
 '@T6G_MB_LIB.T6G(SCH_1):PAGE33_I4@PURE_QUANTA.GENOA_SP5(CHIPS)':
 'VSS_DC45': CDS_PINID='VSS_DC45';
NODE_NAME     U25 DC48
 '@T6G_MB_LIB.T6G(SCH_1):PAGE33_I4@PURE_QUANTA.GENOA_SP5(CHIPS)':
 'VSS_DC48': CDS_PINID='VSS_DC48';
NODE_NAME     U25 DC51
 '@T6G_MB_LIB.T6G(SCH_1):PAGE33_I4@PURE_QUANTA.GENOA_SP5(CHIPS)':
 'VSS_DC51': CDS_PINID='VSS_DC51';
NODE_NAME     U25 DC54
 '@T6G_MB_LIB.T6G(SCH_1):PAGE33_I4@PURE_QUANTA.GENOA_SP5(CHIPS)':
 'VSS_DC54': CDS_PINID='VSS_DC54';
NODE_NAME     U25 DC56
 '@T6G_MB_LIB.T6G(SCH_1):PAGE33_I4@PURE_QUANTA.GENOA_SP5(CHIPS)':
 'VSS_DC56': CDS_PINID='VSS_DC56';
NODE_NAME     U25 DC58
 '@T6G_MB_LIB.T6G(SCH_1):PAGE33_I4@PURE_QUANTA.GENOA_SP5(CHIPS)':
 'VSS_DC58': CDS_PINID='VSS_DC58';
NODE_NAME     U25 DC61
 '@T6G_MB_LIB.T6G(SCH_1):PAGE33_I4@PURE_QUANTA.GENOA_SP5(CHIPS)':
 'VSS_DC61': CDS_PINID='VSS_DC61';
NODE_NAME     U25 DC63
 '@T6G_MB_LIB.T6G(SCH_1):PAGE33_I4@PURE_QUANTA.GENOA_SP5(CHIPS)':
 'VSS_DC63': CDS_PINID='VSS_DC63';
NODE_NAME     U25 DC65
 '@T6G_MB_LIB.T6G(SCH_1):PAGE33_I4@PURE_QUANTA.GENOA_SP5(CHIPS)':
 'VSS_DC65': CDS_PINID='VSS_DC65';
NODE_NAME     U25 DC68
 '@T6G_MB_LIB.T6G(SCH_1):PAGE33_I4@PURE_QUANTA.GENOA_SP5(CHIPS)':
 'VSS_DC68': CDS_PINID='VSS_DC68';
NODE_NAME     U25 DC70
 '@T6G_MB_LIB.T6G(SCH_1):PAGE33_I4@PURE_QUANTA.GENOA_SP5(CHIPS)':
 'VSS_DC70': CDS_PINID='VSS_DC70';
NODE_NAME     U25 DC72
 '@T6G_MB_LIB.T6G(SCH_1):PAGE33_I4@PURE_QUANTA.GENOA_SP5(CHIPS)':
 'VSS_DC72': CDS_PINID='VSS_DC72';
NODE_NAME     U25 DC75
 '@T6G_MB_LIB.T6G(SCH_1):PAGE33_I4@PURE_QUANTA.GENOA_SP5(CHIPS)':
 'VSS_DC75': CDS_PINID='VSS_DC75';
NODE_NAME     U25 DD3
 '@T6G_MB_LIB.T6G(SCH_1):PAGE33_I4@PURE_QUANTA.GENOA_SP5(CHIPS)':
 'VSS_DD3': CDS_PINID='VSS_DD3';
NODE_NAME     U25 DD5
 '@T6G_MB_LIB.T6G(SCH_1):PAGE33_I4@PURE_QUANTA.GENOA_SP5(CHIPS)':
 'VSS_DD5': CDS_PINID='VSS_DD5';
NODE_NAME     U25 DD8
 '@T6G_MB_LIB.T6G(SCH_1):PAGE33_I4@PURE_QUANTA.GENOA_SP5(CHIPS)':
 'VSS_DD8': CDS_PINID='VSS_DD8';
NODE_NAME     U25 DD10
 '@T6G_MB_LIB.T6G(SCH_1):PAGE33_I4@PURE_QUANTA.GENOA_SP5(CHIPS)':
 'VSS_DD10': CDS_PINID='VSS_DD10';
NODE_NAME     U25 DD12
 '@T6G_MB_LIB.T6G(SCH_1):PAGE33_I4@PURE_QUANTA.GENOA_SP5(CHIPS)':
 'VSS_DD12': CDS_PINID='VSS_DD12';
NODE_NAME     U25 DD15
 '@T6G_MB_LIB.T6G(SCH_1):PAGE33_I4@PURE_QUANTA.GENOA_SP5(CHIPS)':
 'VSS_DD15': CDS_PINID='VSS_DD15';
NODE_NAME     U25 DD17
 '@T6G_MB_LIB.T6G(SCH_1):PAGE33_I4@PURE_QUANTA.GENOA_SP5(CHIPS)':
 'VSS_DD17': CDS_PINID='VSS_DD17';
NODE_NAME     U25 DD19
 '@T6G_MB_LIB.T6G(SCH_1):PAGE33_I4@PURE_QUANTA.GENOA_SP5(CHIPS)':
 'VSS_DD19': CDS_PINID='VSS_DD19';
NODE_NAME     U25 DD23
 '@T6G_MB_LIB.T6G(SCH_1):PAGE33_I4@PURE_QUANTA.GENOA_SP5(CHIPS)':
 'VSS_DD23': CDS_PINID='VSS_DD23';
NODE_NAME     U25 DD24
 '@T6G_MB_LIB.T6G(SCH_1):PAGE33_I4@PURE_QUANTA.GENOA_SP5(CHIPS)':
 'VSS_DD24': CDS_PINID='VSS_DD24';
NODE_NAME     U25 DD26
 '@T6G_MB_LIB.T6G(SCH_1):PAGE33_I4@PURE_QUANTA.GENOA_SP5(CHIPS)':
 'VSS_DD26': CDS_PINID='VSS_DD26';
NODE_NAME     U25 DD27
 '@T6G_MB_LIB.T6G(SCH_1):PAGE33_I4@PURE_QUANTA.GENOA_SP5(CHIPS)':
 'VSS_DD27': CDS_PINID='VSS_DD27';
NODE_NAME     U25 DD29
 '@T6G_MB_LIB.T6G(SCH_1):PAGE33_I4@PURE_QUANTA.GENOA_SP5(CHIPS)':
 'VSS_DD29': CDS_PINID='VSS_DD29';
NODE_NAME     U25 DD30
 '@T6G_MB_LIB.T6G(SCH_1):PAGE33_I4@PURE_QUANTA.GENOA_SP5(CHIPS)':
 'VSS_DD30': CDS_PINID='VSS_DD30';
NODE_NAME     U25 DD32
 '@T6G_MB_LIB.T6G(SCH_1):PAGE33_I4@PURE_QUANTA.GENOA_SP5(CHIPS)':
 'VSS_DD32': CDS_PINID='VSS_DD32';
NODE_NAME     U25 DD33
 '@T6G_MB_LIB.T6G(SCH_1):PAGE33_I4@PURE_QUANTA.GENOA_SP5(CHIPS)':
 'VSS_DD33': CDS_PINID='VSS_DD33';
NODE_NAME     U25 DD35
 '@T6G_MB_LIB.T6G(SCH_1):PAGE33_I4@PURE_QUANTA.GENOA_SP5(CHIPS)':
 'VSS_DD35': CDS_PINID='VSS_DD35';
NODE_NAME     U25 DD36
 '@T6G_MB_LIB.T6G(SCH_1):PAGE33_I4@PURE_QUANTA.GENOA_SP5(CHIPS)':
 'VSS_DD36': CDS_PINID='VSS_DD36';
NODE_NAME     U25 DD37
 '@T6G_MB_LIB.T6G(SCH_1):PAGE33_I4@PURE_QUANTA.GENOA_SP5(CHIPS)':
 'VSS_DD37': CDS_PINID='VSS_DD37';
NODE_NAME     U25 DD39
 '@T6G_MB_LIB.T6G(SCH_1):PAGE33_I4@PURE_QUANTA.GENOA_SP5(CHIPS)':
 'VSS_DD39': CDS_PINID='VSS_DD39';
NODE_NAME     U25 DD40
 '@T6G_MB_LIB.T6G(SCH_1):PAGE33_I4@PURE_QUANTA.GENOA_SP5(CHIPS)':
 'VSS_DD40': CDS_PINID='VSS_DD40';
NODE_NAME     U25 DD41
 '@T6G_MB_LIB.T6G(SCH_1):PAGE33_I4@PURE_QUANTA.GENOA_SP5(CHIPS)':
 'VSS_DD41': CDS_PINID='VSS_DD41';
NODE_NAME     U25 DD43
 '@T6G_MB_LIB.T6G(SCH_1):PAGE33_I4@PURE_QUANTA.GENOA_SP5(CHIPS)':
 'VSS_DD43': CDS_PINID='VSS_DD43';
NODE_NAME     U25 DD44
 '@T6G_MB_LIB.T6G(SCH_1):PAGE33_I4@PURE_QUANTA.GENOA_SP5(CHIPS)':
 'VSS_DD44': CDS_PINID='VSS_DD44';
NODE_NAME     U25 DD46
 '@T6G_MB_LIB.T6G(SCH_1):PAGE33_I4@PURE_QUANTA.GENOA_SP5(CHIPS)':
 'VSS_DD46': CDS_PINID='VSS_DD46';
NODE_NAME     U25 DD47
 '@T6G_MB_LIB.T6G(SCH_1):PAGE33_I4@PURE_QUANTA.GENOA_SP5(CHIPS)':
 'VSS_DD47': CDS_PINID='VSS_DD47';
NODE_NAME     U25 DD49
 '@T6G_MB_LIB.T6G(SCH_1):PAGE33_I4@PURE_QUANTA.GENOA_SP5(CHIPS)':
 'VSS_DD49': CDS_PINID='VSS_DD49';
NODE_NAME     U25 DD50
 '@T6G_MB_LIB.T6G(SCH_1):PAGE33_I4@PURE_QUANTA.GENOA_SP5(CHIPS)':
 'VSS_DD50': CDS_PINID='VSS_DD50';
NODE_NAME     U25 DD52
 '@T6G_MB_LIB.T6G(SCH_1):PAGE33_I4@PURE_QUANTA.GENOA_SP5(CHIPS)':
 'VSS_DD52': CDS_PINID='VSS_DD52';
NODE_NAME     U25 DD53
 '@T6G_MB_LIB.T6G(SCH_1):PAGE33_I4@PURE_QUANTA.GENOA_SP5(CHIPS)':
 'VSS_DD53': CDS_PINID='VSS_DD53';
NODE_NAME     U25 DD57
 '@T6G_MB_LIB.T6G(SCH_1):PAGE33_I4@PURE_QUANTA.GENOA_SP5(CHIPS)':
 'VSS_DD57': CDS_PINID='VSS_DD57';
NODE_NAME     U25 DD59
 '@T6G_MB_LIB.T6G(SCH_1):PAGE33_I4@PURE_QUANTA.GENOA_SP5(CHIPS)':
 'VSS_DD59': CDS_PINID='VSS_DD59';
NODE_NAME     U25 DD61
 '@T6G_MB_LIB.T6G(SCH_1):PAGE33_I4@PURE_QUANTA.GENOA_SP5(CHIPS)':
 'VSS_DD61': CDS_PINID='VSS_DD61';
NODE_NAME     U25 DD64
 '@T6G_MB_LIB.T6G(SCH_1):PAGE33_I4@PURE_QUANTA.GENOA_SP5(CHIPS)':
 'VSS_DD64': CDS_PINID='VSS_DD64';
NODE_NAME     U25 DD66
 '@T6G_MB_LIB.T6G(SCH_1):PAGE33_I4@PURE_QUANTA.GENOA_SP5(CHIPS)':
 'VSS_DD66': CDS_PINID='VSS_DD66';
NODE_NAME     U25 DD68
 '@T6G_MB_LIB.T6G(SCH_1):PAGE33_I4@PURE_QUANTA.GENOA_SP5(CHIPS)':
 'VSS_DD68': CDS_PINID='VSS_DD68';
NODE_NAME     U25 DD71
 '@T6G_MB_LIB.T6G(SCH_1):PAGE33_I4@PURE_QUANTA.GENOA_SP5(CHIPS)':
 'VSS_DD71': CDS_PINID='VSS_DD71';
NODE_NAME     U25 DD73
 '@T6G_MB_LIB.T6G(SCH_1):PAGE33_I4@PURE_QUANTA.GENOA_SP5(CHIPS)':
 'VSS_DD73': CDS_PINID='VSS_DD73';
NODE_NAME     U25 DE1
 '@T6G_MB_LIB.T6G(SCH_1):PAGE33_I4@PURE_QUANTA.GENOA_SP5(CHIPS)':
 'VSS_DE1': CDS_PINID='VSS_DE1';
NODE_NAME     U25 DE6
 '@T6G_MB_LIB.T6G(SCH_1):PAGE33_I4@PURE_QUANTA.GENOA_SP5(CHIPS)':
 'VSS_DE6': CDS_PINID='VSS_DE6';
NODE_NAME     U25 DE8
 '@T6G_MB_LIB.T6G(SCH_1):PAGE33_I4@PURE_QUANTA.GENOA_SP5(CHIPS)':
 'VSS_DE8': CDS_PINID='VSS_DE8';
NODE_NAME     U25 DE13
 '@T6G_MB_LIB.T6G(SCH_1):PAGE33_I4@PURE_QUANTA.GENOA_SP5(CHIPS)':
 'VSS_DE13': CDS_PINID='VSS_DE13';
NODE_NAME     U25 DE15
 '@T6G_MB_LIB.T6G(SCH_1):PAGE33_I4@PURE_QUANTA.GENOA_SP5(CHIPS)':
 'VSS_DE15': CDS_PINID='VSS_DE15';
NODE_NAME     U25 DE20
 '@T6G_MB_LIB.T6G(SCH_1):PAGE33_I4@PURE_QUANTA.GENOA_SP5(CHIPS)':
 'VSS_DE20': CDS_PINID='VSS_DE20';
NODE_NAME     U25 DE23
 '@T6G_MB_LIB.T6G(SCH_1):PAGE33_I4@PURE_QUANTA.GENOA_SP5(CHIPS)':
 'VSS_DE23': CDS_PINID='VSS_DE23';
NODE_NAME     U25 DE26
 '@T6G_MB_LIB.T6G(SCH_1):PAGE33_I4@PURE_QUANTA.GENOA_SP5(CHIPS)':
 'VSS_DE26': CDS_PINID='VSS_DE26';
NODE_NAME     U25 DE29
 '@T6G_MB_LIB.T6G(SCH_1):PAGE33_I4@PURE_QUANTA.GENOA_SP5(CHIPS)':
 'VSS_DE29': CDS_PINID='VSS_DE29';
NODE_NAME     U25 DE33
 '@T6G_MB_LIB.T6G(SCH_1):PAGE33_I4@PURE_QUANTA.GENOA_SP5(CHIPS)':
 'VSS_DE33': CDS_PINID='VSS_DE33';
NODE_NAME     U25 DE56
 '@T6G_MB_LIB.T6G(SCH_1):PAGE33_I4@PURE_QUANTA.GENOA_SP5(CHIPS)':
 'VSS_DE56': CDS_PINID='VSS_DE56';
NODE_NAME     U25 DE61
 '@T6G_MB_LIB.T6G(SCH_1):PAGE33_I4@PURE_QUANTA.GENOA_SP5(CHIPS)':
 'VSS_DE61': CDS_PINID='VSS_DE61';
NODE_NAME     U25 DE63
 '@T6G_MB_LIB.T6G(SCH_1):PAGE33_I4@PURE_QUANTA.GENOA_SP5(CHIPS)':
 'VSS_DE63': CDS_PINID='VSS_DE63';
NODE_NAME     U25 DE68
 '@T6G_MB_LIB.T6G(SCH_1):PAGE33_I4@PURE_QUANTA.GENOA_SP5(CHIPS)':
 'VSS_DE68': CDS_PINID='VSS_DE68';
NODE_NAME     U25 DE70
 '@T6G_MB_LIB.T6G(SCH_1):PAGE33_I4@PURE_QUANTA.GENOA_SP5(CHIPS)':
 'VSS_DE70': CDS_PINID='VSS_DE70';
NODE_NAME     U25 DE75
 '@T6G_MB_LIB.T6G(SCH_1):PAGE33_I4@PURE_QUANTA.GENOA_SP5(CHIPS)':
 'VSS_DE75': CDS_PINID='VSS_DE75';
NODE_NAME     U25 DF3
 '@T6G_MB_LIB.T6G(SCH_1):PAGE33_I4@PURE_QUANTA.GENOA_SP5(CHIPS)':
 'VSS_DF3': CDS_PINID='VSS_DF3';
NODE_NAME     U25 DF4
 '@T6G_MB_LIB.T6G(SCH_1):PAGE33_I4@PURE_QUANTA.GENOA_SP5(CHIPS)':
 'VSS_DF4': CDS_PINID='VSS_DF4';
NODE_NAME     U25 DF5
 '@T6G_MB_LIB.T6G(SCH_1):PAGE33_I4@PURE_QUANTA.GENOA_SP5(CHIPS)':
 'VSS_DF5': CDS_PINID='VSS_DF5';
NODE_NAME     U25 DF6
 '@T6G_MB_LIB.T6G(SCH_1):PAGE33_I4@PURE_QUANTA.GENOA_SP5(CHIPS)':
 'VSS_DF6': CDS_PINID='VSS_DF6';
NODE_NAME     U25 DF8
 '@T6G_MB_LIB.T6G(SCH_1):PAGE33_I4@PURE_QUANTA.GENOA_SP5(CHIPS)':
 'VSS_DF8': CDS_PINID='VSS_DF8';
NODE_NAME     U25 DF10
 '@T6G_MB_LIB.T6G(SCH_1):PAGE33_I4@PURE_QUANTA.GENOA_SP5(CHIPS)':
 'VSS_DF10': CDS_PINID='VSS_DF10';
NODE_NAME     U25 DF11
 '@T6G_MB_LIB.T6G(SCH_1):PAGE33_I4@PURE_QUANTA.GENOA_SP5(CHIPS)':
 'VSS_DF11': CDS_PINID='VSS_DF11';
NODE_NAME     U25 DF12
 '@T6G_MB_LIB.T6G(SCH_1):PAGE33_I4@PURE_QUANTA.GENOA_SP5(CHIPS)':
 'VSS_DF12': CDS_PINID='VSS_DF12';
NODE_NAME     U25 DF13
 '@T6G_MB_LIB.T6G(SCH_1):PAGE33_I4@PURE_QUANTA.GENOA_SP5(CHIPS)':
 'VSS_DF13': CDS_PINID='VSS_DF13';
NODE_NAME     U25 DF15
 '@T6G_MB_LIB.T6G(SCH_1):PAGE33_I4@PURE_QUANTA.GENOA_SP5(CHIPS)':
 'VSS_DF15': CDS_PINID='VSS_DF15';
NODE_NAME     U25 DF17
 '@T6G_MB_LIB.T6G(SCH_1):PAGE33_I4@PURE_QUANTA.GENOA_SP5(CHIPS)':
 'VSS_DF17': CDS_PINID='VSS_DF17';
NODE_NAME     U25 DF18
 '@T6G_MB_LIB.T6G(SCH_1):PAGE33_I4@PURE_QUANTA.GENOA_SP5(CHIPS)':
 'VSS_DF18': CDS_PINID='VSS_DF18';
NODE_NAME     U25 DF19
 '@T6G_MB_LIB.T6G(SCH_1):PAGE33_I4@PURE_QUANTA.GENOA_SP5(CHIPS)':
 'VSS_DF19': CDS_PINID='VSS_DF19';
NODE_NAME     U25 DF20
 '@T6G_MB_LIB.T6G(SCH_1):PAGE33_I4@PURE_QUANTA.GENOA_SP5(CHIPS)':
 'VSS_DF20': CDS_PINID='VSS_DF20';
NODE_NAME     U25 DF22
 '@T6G_MB_LIB.T6G(SCH_1):PAGE33_I4@PURE_QUANTA.GENOA_SP5(CHIPS)':
 'VSS_DF22': CDS_PINID='VSS_DF22';
NODE_NAME     U25 DF23
 '@T6G_MB_LIB.T6G(SCH_1):PAGE33_I4@PURE_QUANTA.GENOA_SP5(CHIPS)':
 'VSS_DF23': CDS_PINID='VSS_DF23';
NODE_NAME     U25 DF26
 '@T6G_MB_LIB.T6G(SCH_1):PAGE33_I4@PURE_QUANTA.GENOA_SP5(CHIPS)':
 'VSS_DF26': CDS_PINID='VSS_DF26';
NODE_NAME     U25 DF29
 '@T6G_MB_LIB.T6G(SCH_1):PAGE33_I4@PURE_QUANTA.GENOA_SP5(CHIPS)':
 'VSS_DF29': CDS_PINID='VSS_DF29';
NODE_NAME     U25 DF32
 '@T6G_MB_LIB.T6G(SCH_1):PAGE33_I4@PURE_QUANTA.GENOA_SP5(CHIPS)':
 'VSS_DF32': CDS_PINID='VSS_DF32';
NODE_NAME     U25 DF35
 '@T6G_MB_LIB.T6G(SCH_1):PAGE33_I4@PURE_QUANTA.GENOA_SP5(CHIPS)':
 'VSS_DF35': CDS_PINID='VSS_DF35';
NODE_NAME     U25 DF37
 '@T6G_MB_LIB.T6G(SCH_1):PAGE33_I4@PURE_QUANTA.GENOA_SP5(CHIPS)':
 'VSS_DF37': CDS_PINID='VSS_DF37';
NODE_NAME     U25 DF39
 '@T6G_MB_LIB.T6G(SCH_1):PAGE33_I4@PURE_QUANTA.GENOA_SP5(CHIPS)':
 'VSS_DF39': CDS_PINID='VSS_DF39';
NODE_NAME     U25 DF42
 '@T6G_MB_LIB.T6G(SCH_1):PAGE33_I4@PURE_QUANTA.GENOA_SP5(CHIPS)':
 'VSS_DF42': CDS_PINID='VSS_DF42';
NODE_NAME     U25 DF43
 '@T6G_MB_LIB.T6G(SCH_1):PAGE33_I4@PURE_QUANTA.GENOA_SP5(CHIPS)':
 'VSS_DF43': CDS_PINID='VSS_DF43';
NODE_NAME     U25 DF44
 '@T6G_MB_LIB.T6G(SCH_1):PAGE33_I4@PURE_QUANTA.GENOA_SP5(CHIPS)':
 'VSS_DF44': CDS_PINID='VSS_DF44';
NODE_NAME     U25 DF45
 '@T6G_MB_LIB.T6G(SCH_1):PAGE33_I4@PURE_QUANTA.GENOA_SP5(CHIPS)':
 'VSS_DF45': CDS_PINID='VSS_DF45';
NODE_NAME     U25 DF46
 '@T6G_MB_LIB.T6G(SCH_1):PAGE33_I4@PURE_QUANTA.GENOA_SP5(CHIPS)':
 'VSS_DF46': CDS_PINID='VSS_DF46';
NODE_NAME     U25 DF47
 '@T6G_MB_LIB.T6G(SCH_1):PAGE33_I4@PURE_QUANTA.GENOA_SP5(CHIPS)':
 'VSS_DF47': CDS_PINID='VSS_DF47';
NODE_NAME     U25 DF48
 '@T6G_MB_LIB.T6G(SCH_1):PAGE33_I4@PURE_QUANTA.GENOA_SP5(CHIPS)':
 'VSS_DF48': CDS_PINID='VSS_DF48';
NODE_NAME     U25 DF49
 '@T6G_MB_LIB.T6G(SCH_1):PAGE33_I4@PURE_QUANTA.GENOA_SP5(CHIPS)':
 'VSS_DF49': CDS_PINID='VSS_DF49';
NODE_NAME     U25 DF50
 '@T6G_MB_LIB.T6G(SCH_1):PAGE33_I4@PURE_QUANTA.GENOA_SP5(CHIPS)':
 'VSS_DF50': CDS_PINID='VSS_DF50';
NODE_NAME     U25 DF51
 '@T6G_MB_LIB.T6G(SCH_1):PAGE33_I4@PURE_QUANTA.GENOA_SP5(CHIPS)':
 'VSS_DF51': CDS_PINID='VSS_DF51';
NODE_NAME     U25 DF52
 '@T6G_MB_LIB.T6G(SCH_1):PAGE33_I4@PURE_QUANTA.GENOA_SP5(CHIPS)':
 'VSS_DF52': CDS_PINID='VSS_DF52';
NODE_NAME     U25 DF53
 '@T6G_MB_LIB.T6G(SCH_1):PAGE33_I4@PURE_QUANTA.GENOA_SP5(CHIPS)':
 'VSS_DF53': CDS_PINID='VSS_DF53';
NODE_NAME     U25 DF54
 '@T6G_MB_LIB.T6G(SCH_1):PAGE33_I4@PURE_QUANTA.GENOA_SP5(CHIPS)':
 'VSS_DF54': CDS_PINID='VSS_DF54';
NODE_NAME     U25 DF56
 '@T6G_MB_LIB.T6G(SCH_1):PAGE33_I4@PURE_QUANTA.GENOA_SP5(CHIPS)':
 'VSS_DF56': CDS_PINID='VSS_DF56';
NODE_NAME     U25 DF57
 '@T6G_MB_LIB.T6G(SCH_1):PAGE33_I4@PURE_QUANTA.GENOA_SP5(CHIPS)':
 'VSS_DF57': CDS_PINID='VSS_DF57';
NODE_NAME     U25 DF58
 '@T6G_MB_LIB.T6G(SCH_1):PAGE33_I4@PURE_QUANTA.GENOA_SP5(CHIPS)':
 'VSS_DF58': CDS_PINID='VSS_DF58';
NODE_NAME     U25 DF59
 '@T6G_MB_LIB.T6G(SCH_1):PAGE33_I4@PURE_QUANTA.GENOA_SP5(CHIPS)':
 'VSS_DF59': CDS_PINID='VSS_DF59';
NODE_NAME     U25 DF61
 '@T6G_MB_LIB.T6G(SCH_1):PAGE33_I4@PURE_QUANTA.GENOA_SP5(CHIPS)':
 'VSS_DF61': CDS_PINID='VSS_DF61';
NODE_NAME     U25 DF63
 '@T6G_MB_LIB.T6G(SCH_1):PAGE33_I4@PURE_QUANTA.GENOA_SP5(CHIPS)':
 'VSS_DF63': CDS_PINID='VSS_DF63';
NODE_NAME     U25 DF64
 '@T6G_MB_LIB.T6G(SCH_1):PAGE33_I4@PURE_QUANTA.GENOA_SP5(CHIPS)':
 'VSS_DF64': CDS_PINID='VSS_DF64';
NODE_NAME     U25 DF65
 '@T6G_MB_LIB.T6G(SCH_1):PAGE33_I4@PURE_QUANTA.GENOA_SP5(CHIPS)':
 'VSS_DF65': CDS_PINID='VSS_DF65';
NODE_NAME     U25 DF66
 '@T6G_MB_LIB.T6G(SCH_1):PAGE33_I4@PURE_QUANTA.GENOA_SP5(CHIPS)':
 'VSS_DF66': CDS_PINID='VSS_DF66';
NODE_NAME     U25 DF68
 '@T6G_MB_LIB.T6G(SCH_1):PAGE33_I4@PURE_QUANTA.GENOA_SP5(CHIPS)':
 'VSS_DF68': CDS_PINID='VSS_DF68';
NODE_NAME     U25 DF70
 '@T6G_MB_LIB.T6G(SCH_1):PAGE33_I4@PURE_QUANTA.GENOA_SP5(CHIPS)':
 'VSS_DF70': CDS_PINID='VSS_DF70';
NODE_NAME     U25 DF71
 '@T6G_MB_LIB.T6G(SCH_1):PAGE33_I4@PURE_QUANTA.GENOA_SP5(CHIPS)':
 'VSS_DF71': CDS_PINID='VSS_DF71';
NODE_NAME     U25 DF72
 '@T6G_MB_LIB.T6G(SCH_1):PAGE33_I4@PURE_QUANTA.GENOA_SP5(CHIPS)':
 'VSS_DF72': CDS_PINID='VSS_DF72';
NODE_NAME     U25 DF73
 '@T6G_MB_LIB.T6G(SCH_1):PAGE33_I4@PURE_QUANTA.GENOA_SP5(CHIPS)':
 'VSS_DF73': CDS_PINID='VSS_DF73';
NODE_NAME     U25 DG1
 '@T6G_MB_LIB.T6G(SCH_1):PAGE33_I4@PURE_QUANTA.GENOA_SP5(CHIPS)':
 'VSS_DG1': CDS_PINID='VSS_DG1';
NODE_NAME     U25 DG2
 '@T6G_MB_LIB.T6G(SCH_1):PAGE33_I4@PURE_QUANTA.GENOA_SP5(CHIPS)':
 'VSS_DG2': CDS_PINID='VSS_DG2';
NODE_NAME     U25 DG6
 '@T6G_MB_LIB.T6G(SCH_1):PAGE33_I4@PURE_QUANTA.GENOA_SP5(CHIPS)':
 'VSS_DG6': CDS_PINID='VSS_DG6';
NODE_NAME     U25 DG7
 '@T6G_MB_LIB.T6G(SCH_1):PAGE33_I4@PURE_QUANTA.GENOA_SP5(CHIPS)':
 'VSS_DG7': CDS_PINID='VSS_DG7';
NODE_NAME     U25 DG8
 '@T6G_MB_LIB.T6G(SCH_1):PAGE33_I4@PURE_QUANTA.GENOA_SP5(CHIPS)':
 'VSS_DG8': CDS_PINID='VSS_DG8';
NODE_NAME     U25 DG9
 '@T6G_MB_LIB.T6G(SCH_1):PAGE33_I4@PURE_QUANTA.GENOA_SP5(CHIPS)':
 'VSS_DG9': CDS_PINID='VSS_DG9';
NODE_NAME     U25 DG13
 '@T6G_MB_LIB.T6G(SCH_1):PAGE33_I4@PURE_QUANTA.GENOA_SP5(CHIPS)':
 'VSS_DG13': CDS_PINID='VSS_DG13';
NODE_NAME     U25 DG14
 '@T6G_MB_LIB.T6G(SCH_1):PAGE33_I4@PURE_QUANTA.GENOA_SP5(CHIPS)':
 'VSS_DG14': CDS_PINID='VSS_DG14';
NODE_NAME     U25 DG15
 '@T6G_MB_LIB.T6G(SCH_1):PAGE33_I4@PURE_QUANTA.GENOA_SP5(CHIPS)':
 'VSS_DG15': CDS_PINID='VSS_DG15';
NODE_NAME     U25 DG16
 '@T6G_MB_LIB.T6G(SCH_1):PAGE33_I4@PURE_QUANTA.GENOA_SP5(CHIPS)':
 'VSS_DG16': CDS_PINID='VSS_DG16';
NODE_NAME     U25 DG18
 '@T6G_MB_LIB.T6G(SCH_1):PAGE33_I4@PURE_QUANTA.GENOA_SP5(CHIPS)':
 'VSS_DG18': CDS_PINID='VSS_DG18';
NODE_NAME     U25 DG20
 '@T6G_MB_LIB.T6G(SCH_1):PAGE33_I4@PURE_QUANTA.GENOA_SP5(CHIPS)':
 'VSS_DG20': CDS_PINID='VSS_DG20';
NODE_NAME     U25 DG21
 '@T6G_MB_LIB.T6G(SCH_1):PAGE33_I4@PURE_QUANTA.GENOA_SP5(CHIPS)':
 'VSS_DG21': CDS_PINID='VSS_DG21';
NODE_NAME     U25 DG24
 '@T6G_MB_LIB.T6G(SCH_1):PAGE33_I4@PURE_QUANTA.GENOA_SP5(CHIPS)':
 'VSS_DG24': CDS_PINID='VSS_DG24';
NODE_NAME     U25 DG27
 '@T6G_MB_LIB.T6G(SCH_1):PAGE33_I4@PURE_QUANTA.GENOA_SP5(CHIPS)':
 'VSS_DG27': CDS_PINID='VSS_DG27';
NODE_NAME     U25 DG30
 '@T6G_MB_LIB.T6G(SCH_1):PAGE33_I4@PURE_QUANTA.GENOA_SP5(CHIPS)':
 'VSS_DG30': CDS_PINID='VSS_DG30';
NODE_NAME     U25 DG33
 '@T6G_MB_LIB.T6G(SCH_1):PAGE33_I4@PURE_QUANTA.GENOA_SP5(CHIPS)':
 'VSS_DG33': CDS_PINID='VSS_DG33';
NODE_NAME     U25 DG41
 '@T6G_MB_LIB.T6G(SCH_1):PAGE33_I4@PURE_QUANTA.GENOA_SP5(CHIPS)':
 'VSS_DG41': CDS_PINID='VSS_DG41';
NODE_NAME     U25 DG43
 '@T6G_MB_LIB.T6G(SCH_1):PAGE33_I4@PURE_QUANTA.GENOA_SP5(CHIPS)':
 'VSS_DG43': CDS_PINID='VSS_DG43';
NODE_NAME     U25 DG46
 '@T6G_MB_LIB.T6G(SCH_1):PAGE33_I4@PURE_QUANTA.GENOA_SP5(CHIPS)':
 'VSS_DG46': CDS_PINID='VSS_DG46';
NODE_NAME     U25 DG49
 '@T6G_MB_LIB.T6G(SCH_1):PAGE33_I4@PURE_QUANTA.GENOA_SP5(CHIPS)':
 'VSS_DG49': CDS_PINID='VSS_DG49';
NODE_NAME     U25 DG52
 '@T6G_MB_LIB.T6G(SCH_1):PAGE33_I4@PURE_QUANTA.GENOA_SP5(CHIPS)':
 'VSS_DG52': CDS_PINID='VSS_DG52';
NODE_NAME     U25 DG55
 '@T6G_MB_LIB.T6G(SCH_1):PAGE33_I4@PURE_QUANTA.GENOA_SP5(CHIPS)':
 'VSS_DG55': CDS_PINID='VSS_DG55';
NODE_NAME     U25 DG56
 '@T6G_MB_LIB.T6G(SCH_1):PAGE33_I4@PURE_QUANTA.GENOA_SP5(CHIPS)':
 'VSS_DG56': CDS_PINID='VSS_DG56';
NODE_NAME     U25 DG59
 '@T6G_MB_LIB.T6G(SCH_1):PAGE33_I4@PURE_QUANTA.GENOA_SP5(CHIPS)':
 'VSS_DG59': CDS_PINID='VSS_DG59';
NODE_NAME     U25 DG60
 '@T6G_MB_LIB.T6G(SCH_1):PAGE33_I4@PURE_QUANTA.GENOA_SP5(CHIPS)':
 'VSS_DG60': CDS_PINID='VSS_DG60';
NODE_NAME     U25 DG61
 '@T6G_MB_LIB.T6G(SCH_1):PAGE33_I4@PURE_QUANTA.GENOA_SP5(CHIPS)':
 'VSS_DG61': CDS_PINID='VSS_DG61';
NODE_NAME     U25 DG62
 '@T6G_MB_LIB.T6G(SCH_1):PAGE33_I4@PURE_QUANTA.GENOA_SP5(CHIPS)':
 'VSS_DG62': CDS_PINID='VSS_DG62';
NODE_NAME     U25 DG63
 '@T6G_MB_LIB.T6G(SCH_1):PAGE33_I4@PURE_QUANTA.GENOA_SP5(CHIPS)':
 'VSS_DG63': CDS_PINID='VSS_DG63';
NODE_NAME     U25 DG65
 '@T6G_MB_LIB.T6G(SCH_1):PAGE33_I4@PURE_QUANTA.GENOA_SP5(CHIPS)':
 'VSS_DG65': CDS_PINID='VSS_DG65';
NODE_NAME     U25 DG66
 '@T6G_MB_LIB.T6G(SCH_1):PAGE33_I4@PURE_QUANTA.GENOA_SP5(CHIPS)':
 'VSS_DG66': CDS_PINID='VSS_DG66';
NODE_NAME     U25 DG67
 '@T6G_MB_LIB.T6G(SCH_1):PAGE33_I4@PURE_QUANTA.GENOA_SP5(CHIPS)':
 'VSS_DG67': CDS_PINID='VSS_DG67';
NODE_NAME     U25 DG68
 '@T6G_MB_LIB.T6G(SCH_1):PAGE33_I4@PURE_QUANTA.GENOA_SP5(CHIPS)':
 'VSS_DG68': CDS_PINID='VSS_DG68';
NODE_NAME     U25 DG69
 '@T6G_MB_LIB.T6G(SCH_1):PAGE33_I4@PURE_QUANTA.GENOA_SP5(CHIPS)':
 'VSS_DG69': CDS_PINID='VSS_DG69';
NODE_NAME     U25 DG70
 '@T6G_MB_LIB.T6G(SCH_1):PAGE33_I4@PURE_QUANTA.GENOA_SP5(CHIPS)':
 'VSS_DG70': CDS_PINID='VSS_DG70';
NODE_NAME     U25 DG74
 '@T6G_MB_LIB.T6G(SCH_1):PAGE33_I4@PURE_QUANTA.GENOA_SP5(CHIPS)':
 'VSS_DG74': CDS_PINID='VSS_DG74';
NODE_NAME     U25 DG75
 '@T6G_MB_LIB.T6G(SCH_1):PAGE33_I4@PURE_QUANTA.GENOA_SP5(CHIPS)':
 'VSS_DG75': CDS_PINID='VSS_DG75';
NODE_NAME     U25 DH5
 '@T6G_MB_LIB.T6G(SCH_1):PAGE33_I4@PURE_QUANTA.GENOA_SP5(CHIPS)':
 'VSS_DH5': CDS_PINID='VSS_DH5';
NODE_NAME     U25 DH11
 '@T6G_MB_LIB.T6G(SCH_1):PAGE33_I4@PURE_QUANTA.GENOA_SP5(CHIPS)':
 'VSS_DH11': CDS_PINID='VSS_DH11';
NODE_NAME     U25 DH18
 '@T6G_MB_LIB.T6G(SCH_1):PAGE33_I4@PURE_QUANTA.GENOA_SP5(CHIPS)':
 'VSS_DH18': CDS_PINID='VSS_DH18';
NODE_NAME     U25 DH37
 '@T6G_MB_LIB.T6G(SCH_1):PAGE33_I4@PURE_QUANTA.GENOA_SP5(CHIPS)':
 'VSS_DH37': CDS_PINID='VSS_DH37';
NODE_NAME     U25 DH39
 '@T6G_MB_LIB.T6G(SCH_1):PAGE33_I4@PURE_QUANTA.GENOA_SP5(CHIPS)':
 'VSS_DH39': CDS_PINID='VSS_DH39';
NODE_NAME     U25 DH43
 '@T6G_MB_LIB.T6G(SCH_1):PAGE33_I4@PURE_QUANTA.GENOA_SP5(CHIPS)':
 'VSS_DH43': CDS_PINID='VSS_DH43';
NODE_NAME     U25 DH46
 '@T6G_MB_LIB.T6G(SCH_1):PAGE33_I4@PURE_QUANTA.GENOA_SP5(CHIPS)':
 'VSS_DH46': CDS_PINID='VSS_DH46';
NODE_NAME     U25 DH49
 '@T6G_MB_LIB.T6G(SCH_1):PAGE33_I4@PURE_QUANTA.GENOA_SP5(CHIPS)':
 'VSS_DH49': CDS_PINID='VSS_DH49';
NODE_NAME     U25 DH52
 '@T6G_MB_LIB.T6G(SCH_1):PAGE33_I4@PURE_QUANTA.GENOA_SP5(CHIPS)':
 'VSS_DH52': CDS_PINID='VSS_DH52';
NODE_NAME     U25 DH55
 '@T6G_MB_LIB.T6G(SCH_1):PAGE33_I4@PURE_QUANTA.GENOA_SP5(CHIPS)':
 'VSS_DH55': CDS_PINID='VSS_DH55';
NODE_NAME     U25 DH59
 '@T6G_MB_LIB.T6G(SCH_1):PAGE33_I4@PURE_QUANTA.GENOA_SP5(CHIPS)':
 'VSS_DH59': CDS_PINID='VSS_DH59';
NODE_NAME     U25 DH61
 '@T6G_MB_LIB.T6G(SCH_1):PAGE33_I4@PURE_QUANTA.GENOA_SP5(CHIPS)':
 'VSS_DH61': CDS_PINID='VSS_DH61';
NODE_NAME     U25 DH63
 '@T6G_MB_LIB.T6G(SCH_1):PAGE33_I4@PURE_QUANTA.GENOA_SP5(CHIPS)':
 'VSS_DH63': CDS_PINID='VSS_DH63';
NODE_NAME     U25 DH64
 '@T6G_MB_LIB.T6G(SCH_1):PAGE33_I4@PURE_QUANTA.GENOA_SP5(CHIPS)':
 'VSS_DH64': CDS_PINID='VSS_DH64';
NODE_NAME     U25 DH66
 '@T6G_MB_LIB.T6G(SCH_1):PAGE33_I4@PURE_QUANTA.GENOA_SP5(CHIPS)':
 'VSS_DH66': CDS_PINID='VSS_DH66';
NODE_NAME     U25 DH68
 '@T6G_MB_LIB.T6G(SCH_1):PAGE33_I4@PURE_QUANTA.GENOA_SP5(CHIPS)':
 'VSS_DH68': CDS_PINID='VSS_DH68';
NODE_NAME     U25 DH70
 '@T6G_MB_LIB.T6G(SCH_1):PAGE33_I4@PURE_QUANTA.GENOA_SP5(CHIPS)':
 'VSS_DH70': CDS_PINID='VSS_DH70';
NODE_NAME     U25 DJ7
 '@T6G_MB_LIB.T6G(SCH_1):PAGE33_I4@PURE_QUANTA.GENOA_SP5(CHIPS)':
 'VSS_DJ7': CDS_PINID='VSS_DJ7';
NODE_NAME     U25 DJ15
 '@T6G_MB_LIB.T6G(SCH_1):PAGE33_I4@PURE_QUANTA.GENOA_SP5(CHIPS)':
 'VSS_DJ15': CDS_PINID='VSS_DJ15';
NODE_NAME     U25 DJ19
 '@T6G_MB_LIB.T6G(SCH_1):PAGE33_I4@PURE_QUANTA.GENOA_SP5(CHIPS)':
 'VSS_DJ19': CDS_PINID='VSS_DJ19';
NODE_NAME     U25 DJ43
 '@T6G_MB_LIB.T6G(SCH_1):PAGE33_I4@PURE_QUANTA.GENOA_SP5(CHIPS)':
 'VSS_DJ43': CDS_PINID='VSS_DJ43';
NODE_NAME     U25 DJ49
 '@T6G_MB_LIB.T6G(SCH_1):PAGE33_I4@PURE_QUANTA.GENOA_SP5(CHIPS)':
 'VSS_DJ49': CDS_PINID='VSS_DJ49';
NODE_NAME     U25 DJ59
 '@T6G_MB_LIB.T6G(SCH_1):PAGE33_I4@PURE_QUANTA.GENOA_SP5(CHIPS)':
 'VSS_DJ59': CDS_PINID='VSS_DJ59';
NODE_NAME     U25 DJ61
 '@T6G_MB_LIB.T6G(SCH_1):PAGE33_I4@PURE_QUANTA.GENOA_SP5(CHIPS)':
 'VSS_DJ61': CDS_PINID='VSS_DJ61';
NODE_NAME     U25 DJ63
 '@T6G_MB_LIB.T6G(SCH_1):PAGE33_I4@PURE_QUANTA.GENOA_SP5(CHIPS)':
 'VSS_DJ63': CDS_PINID='VSS_DJ63';
NODE_NAME     U25 DJ66
 '@T6G_MB_LIB.T6G(SCH_1):PAGE33_I4@PURE_QUANTA.GENOA_SP5(CHIPS)':
 'VSS_DJ66': CDS_PINID='VSS_DJ66';
NODE_NAME     U25 DJ68
 '@T6G_MB_LIB.T6G(SCH_1):PAGE33_I4@PURE_QUANTA.GENOA_SP5(CHIPS)':
 'VSS_DJ68': CDS_PINID='VSS_DJ68';
NODE_NAME     U25 DJ73
 '@T6G_MB_LIB.T6G(SCH_1):PAGE33_I4@PURE_QUANTA.GENOA_SP5(CHIPS)':
 'VSS_DJ73': CDS_PINID='VSS_DJ73';
NODE_NAME     U25 K23
 '@T6G_MB_LIB.T6G(SCH_1):PAGE33_I4@PURE_QUANTA.GENOA_SP5(CHIPS)':
 'VSS_K23': CDS_PINID='VSS_K23';
NODE_NAME     U25 K59
 '@T6G_MB_LIB.T6G(SCH_1):PAGE33_I4@PURE_QUANTA.GENOA_SP5(CHIPS)':
 'VSS_K59': CDS_PINID='VSS_K59';
NODE_NAME     U25 P25
 '@T6G_MB_LIB.T6G(SCH_1):PAGE33_I4@PURE_QUANTA.GENOA_SP5(CHIPS)':
 'VSS_P25': CDS_PINID='VSS_P25';
NODE_NAME     U25 P68
 '@T6G_MB_LIB.T6G(SCH_1):PAGE33_I4@PURE_QUANTA.GENOA_SP5(CHIPS)':
 'VSS_P68': CDS_PINID='VSS_P68';
NODE_NAME     U25 V27
 '@T6G_MB_LIB.T6G(SCH_1):PAGE33_I4@PURE_QUANTA.GENOA_SP5(CHIPS)':
 'VSS_V27': CDS_PINID='VSS_V27';
NODE_NAME     U25 V68
 '@T6G_MB_LIB.T6G(SCH_1):PAGE33_I4@PURE_QUANTA.GENOA_SP5(CHIPS)':
 'VSS_V68': CDS_PINID='VSS_V68';
NODE_NAME     U27 4
 '@T6G_MB_LIB.T6G(SCH_1):PAGE34_I18@PURE_QUANTA.PCA9617ADP(CHIPS)':
 'GND': CDS_PINID='GND';
NODE_NAME     C42 2
 '@T6G_MB_LIB.T6G(SCH_1):PAGE34_I44@PURE_QUANTA.Q_CAP(CHIPS)':
 'B': CDS_PINID='B';
NODE_NAME     C43 2
 '@T6G_MB_LIB.T6G(SCH_1):PAGE34_I47@PURE_QUANTA.Q_CAP(CHIPS)':
 'B': CDS_PINID='B';
NODE_NAME     U101 3
 '@T6G_MB_LIB.T6G(SCH_1):PAGE34_I55@PURE_QUANTA.SN74LVC1G07DBVR(CHIPS)':
 'GND': CDS_PINID='GND';
NODE_NAME     C226 2
 '@T6G_MB_LIB.T6G(SCH_1):PAGE34_I59@PURE_QUANTA.Q_CAP(CHIPS)':
 'B': CDS_PINID='B';
NODE_NAME     U26 DH8
 '@T6G_MB_LIB.T6G(SCH_1):PAGE54_I190@PURE_QUANTA.GENOA_SP5(CHIPS)':
 'RTC_LDO_SELECT': CDS_PINID='RTC_LDO_SELECT';
NODE_NAME     C235 2
 '@T6G_MB_LIB.T6G(SCH_1):PAGE54_I310@PURE_QUANTA.Q_CAP(CHIPS)':
 'B': CDS_PINID='B';
NODE_NAME     C234 2
 '@T6G_MB_LIB.T6G(SCH_1):PAGE54_I311@PURE_QUANTA.Q_CAP(CHIPS)':
 'B': CDS_PINID='B';
NODE_NAME     C233 2
 '@T6G_MB_LIB.T6G(SCH_1):PAGE54_I315@PURE_QUANTA.Q_CAP(CHIPS)':
 'B': CDS_PINID='B';
NODE_NAME     C232 2
 '@T6G_MB_LIB.T6G(SCH_1):PAGE54_I318@PURE_QUANTA.Q_CAP(CHIPS)':
 'B': CDS_PINID='B';
NODE_NAME     C231 2
 '@T6G_MB_LIB.T6G(SCH_1):PAGE54_I319@PURE_QUANTA.Q_CAP(CHIPS)':
 'B': CDS_PINID='B';
NODE_NAME     C230 2
 '@T6G_MB_LIB.T6G(SCH_1):PAGE54_I325@PURE_QUANTA.Q_CAP(CHIPS)':
 'B': CDS_PINID='B';
NODE_NAME     R519 2
 '@T6G_MB_LIB.T6G(SCH_1):PAGE54_I404@PURE_QUANTA.Q_RES(CHIPS)':
 'B': CDS_PINID='B';
NODE_NAME     R521 2
 '@T6G_MB_LIB.T6G(SCH_1):PAGE54_I405@PURE_QUANTA.Q_RES(CHIPS)':
 'B': CDS_PINID='B';
NODE_NAME     C236 2
 '@T6G_MB_LIB.T6G(SCH_1):PAGE55_I3@PURE_QUANTA.Q_CAP(CHIPS)':
 'B': CDS_PINID='B';
NODE_NAME     C238 2
 '@T6G_MB_LIB.T6G(SCH_1):PAGE55_I5@PURE_QUANTA.Q_CAP(CHIPS)':
 'B': CDS_PINID='B';
NODE_NAME     C239 2
 '@T6G_MB_LIB.T6G(SCH_1):PAGE55_I9@PURE_QUANTA.Q_CAP(CHIPS)':
 'B': CDS_PINID='B';
NODE_NAME     Y4 2
 '@T6G_MB_LIB.T6G(SCH_1):PAGE55_I12@PURE_QUANTA.Q_XTAL_4P_13BI_24GND(CHIPS)':
 'G1': CDS_PINID='G1';
NODE_NAME     Y4 4
 '@T6G_MB_LIB.T6G(SCH_1):PAGE55_I12@PURE_QUANTA.Q_XTAL_4P_13BI_24GND(CHIPS)':
 'G2': CDS_PINID='G2';
NODE_NAME     C237 2
 '@T6G_MB_LIB.T6G(SCH_1):PAGE55_I15@PURE_QUANTA.Q_CAP(CHIPS)':
 'B': CDS_PINID='B';
NODE_NAME     U26 A3
 '@T6G_MB_LIB.T6G(SCH_1):PAGE58_I1@PURE_QUANTA.GENOA_SP5(CHIPS)':
 'VSS_A3': CDS_PINID='VSS_A3';
NODE_NAME     U26 A9
 '@T6G_MB_LIB.T6G(SCH_1):PAGE58_I1@PURE_QUANTA.GENOA_SP5(CHIPS)':
 'VSS_A9': CDS_PINID='VSS_A9';
NODE_NAME     U26 A15
 '@T6G_MB_LIB.T6G(SCH_1):PAGE58_I1@PURE_QUANTA.GENOA_SP5(CHIPS)':
 'VSS_A15': CDS_PINID='VSS_A15';
NODE_NAME     U26 A21
 '@T6G_MB_LIB.T6G(SCH_1):PAGE58_I1@PURE_QUANTA.GENOA_SP5(CHIPS)':
 'VSS_A21': CDS_PINID='VSS_A21';
NODE_NAME     U26 A27
 '@T6G_MB_LIB.T6G(SCH_1):PAGE58_I1@PURE_QUANTA.GENOA_SP5(CHIPS)':
 'VSS_A27': CDS_PINID='VSS_A27';
NODE_NAME     U26 A43
 '@T6G_MB_LIB.T6G(SCH_1):PAGE58_I1@PURE_QUANTA.GENOA_SP5(CHIPS)':
 'VSS_A43': CDS_PINID='VSS_A43';
NODE_NAME     U26 A44
 '@T6G_MB_LIB.T6G(SCH_1):PAGE58_I1@PURE_QUANTA.GENOA_SP5(CHIPS)':
 'VSS_A44': CDS_PINID='VSS_A44';
NODE_NAME     U26 A47
 '@T6G_MB_LIB.T6G(SCH_1):PAGE58_I1@PURE_QUANTA.GENOA_SP5(CHIPS)':
 'VSS_A47': CDS_PINID='VSS_A47';
NODE_NAME     U26 A49
 '@T6G_MB_LIB.T6G(SCH_1):PAGE58_I1@PURE_QUANTA.GENOA_SP5(CHIPS)':
 'VSS_A49': CDS_PINID='VSS_A49';
NODE_NAME     U26 A53
 '@T6G_MB_LIB.T6G(SCH_1):PAGE58_I1@PURE_QUANTA.GENOA_SP5(CHIPS)':
 'VSS_A53': CDS_PINID='VSS_A53';
NODE_NAME     U26 A61
 '@T6G_MB_LIB.T6G(SCH_1):PAGE58_I1@PURE_QUANTA.GENOA_SP5(CHIPS)':
 'VSS_A61': CDS_PINID='VSS_A61';
NODE_NAME     U26 A67
 '@T6G_MB_LIB.T6G(SCH_1):PAGE58_I1@PURE_QUANTA.GENOA_SP5(CHIPS)':
 'VSS_A67': CDS_PINID='VSS_A67';
NODE_NAME     U26 A72
 '@T6G_MB_LIB.T6G(SCH_1):PAGE58_I1@PURE_QUANTA.GENOA_SP5(CHIPS)':
 'VSS_A72': CDS_PINID='VSS_A72';
NODE_NAME     U26 A73
 '@T6G_MB_LIB.T6G(SCH_1):PAGE58_I1@PURE_QUANTA.GENOA_SP5(CHIPS)':
 'VSS_A73': CDS_PINID='VSS_A73';
NODE_NAME     U26 B7
 '@T6G_MB_LIB.T6G(SCH_1):PAGE58_I1@PURE_QUANTA.GENOA_SP5(CHIPS)':
 'VSS_B7': CDS_PINID='VSS_B7';
NODE_NAME     U26 B8
 '@T6G_MB_LIB.T6G(SCH_1):PAGE58_I1@PURE_QUANTA.GENOA_SP5(CHIPS)':
 'VSS_B8': CDS_PINID='VSS_B8';
NODE_NAME     U26 B10
 '@T6G_MB_LIB.T6G(SCH_1):PAGE58_I1@PURE_QUANTA.GENOA_SP5(CHIPS)':
 'VSS_B10': CDS_PINID='VSS_B10';
NODE_NAME     U26 B11
 '@T6G_MB_LIB.T6G(SCH_1):PAGE58_I1@PURE_QUANTA.GENOA_SP5(CHIPS)':
 'VSS_B11': CDS_PINID='VSS_B11';
NODE_NAME     U26 B13
 '@T6G_MB_LIB.T6G(SCH_1):PAGE58_I1@PURE_QUANTA.GENOA_SP5(CHIPS)':
 'VSS_B13': CDS_PINID='VSS_B13';
NODE_NAME     U26 B18
 '@T6G_MB_LIB.T6G(SCH_1):PAGE58_I1@PURE_QUANTA.GENOA_SP5(CHIPS)':
 'VSS_B18': CDS_PINID='VSS_B18';
NODE_NAME     U26 B24
 '@T6G_MB_LIB.T6G(SCH_1):PAGE58_I1@PURE_QUANTA.GENOA_SP5(CHIPS)':
 'VSS_B24': CDS_PINID='VSS_B24';
NODE_NAME     U26 B27
 '@T6G_MB_LIB.T6G(SCH_1):PAGE58_I1@PURE_QUANTA.GENOA_SP5(CHIPS)':
 'VSS_B27': CDS_PINID='VSS_B27';
NODE_NAME     U26 B30
 '@T6G_MB_LIB.T6G(SCH_1):PAGE58_I1@PURE_QUANTA.GENOA_SP5(CHIPS)':
 'VSS_B30': CDS_PINID='VSS_B30';
NODE_NAME     U26 B33
 '@T6G_MB_LIB.T6G(SCH_1):PAGE58_I1@PURE_QUANTA.GENOA_SP5(CHIPS)':
 'VSS_B33': CDS_PINID='VSS_B33';
NODE_NAME     U26 B37
 '@T6G_MB_LIB.T6G(SCH_1):PAGE58_I1@PURE_QUANTA.GENOA_SP5(CHIPS)':
 'VSS_B37': CDS_PINID='VSS_B37';
NODE_NAME     U26 B39
 '@T6G_MB_LIB.T6G(SCH_1):PAGE58_I1@PURE_QUANTA.GENOA_SP5(CHIPS)':
 'VSS_B39': CDS_PINID='VSS_B39';
NODE_NAME     U26 B43
 '@T6G_MB_LIB.T6G(SCH_1):PAGE58_I1@PURE_QUANTA.GENOA_SP5(CHIPS)':
 'VSS_B43': CDS_PINID='VSS_B43';
NODE_NAME     U26 B46
 '@T6G_MB_LIB.T6G(SCH_1):PAGE58_I1@PURE_QUANTA.GENOA_SP5(CHIPS)':
 'VSS_B46': CDS_PINID='VSS_B46';
NODE_NAME     U26 B49
 '@T6G_MB_LIB.T6G(SCH_1):PAGE58_I1@PURE_QUANTA.GENOA_SP5(CHIPS)':
 'VSS_B49': CDS_PINID='VSS_B49';
NODE_NAME     U26 B52
 '@T6G_MB_LIB.T6G(SCH_1):PAGE58_I1@PURE_QUANTA.GENOA_SP5(CHIPS)':
 'VSS_B52': CDS_PINID='VSS_B52';
NODE_NAME     U26 B55
 '@T6G_MB_LIB.T6G(SCH_1):PAGE58_I1@PURE_QUANTA.GENOA_SP5(CHIPS)':
 'VSS_B55': CDS_PINID='VSS_B55';
NODE_NAME     U26 B59
 '@T6G_MB_LIB.T6G(SCH_1):PAGE58_I1@PURE_QUANTA.GENOA_SP5(CHIPS)':
 'VSS_B59': CDS_PINID='VSS_B59';
NODE_NAME     U26 B62
 '@T6G_MB_LIB.T6G(SCH_1):PAGE58_I1@PURE_QUANTA.GENOA_SP5(CHIPS)':
 'VSS_B62': CDS_PINID='VSS_B62';
NODE_NAME     U26 B65
 '@T6G_MB_LIB.T6G(SCH_1):PAGE58_I1@PURE_QUANTA.GENOA_SP5(CHIPS)':
 'VSS_B65': CDS_PINID='VSS_B65';
NODE_NAME     U26 B68
 '@T6G_MB_LIB.T6G(SCH_1):PAGE58_I1@PURE_QUANTA.GENOA_SP5(CHIPS)':
 'VSS_B68': CDS_PINID='VSS_B68';
NODE_NAME     U26 B70
 '@T6G_MB_LIB.T6G(SCH_1):PAGE58_I1@PURE_QUANTA.GENOA_SP5(CHIPS)':
 'VSS_B70': CDS_PINID='VSS_B70';
NODE_NAME     U26 C1
 '@T6G_MB_LIB.T6G(SCH_1):PAGE58_I1@PURE_QUANTA.GENOA_SP5(CHIPS)':
 'VSS_C1': CDS_PINID='VSS_C1';
NODE_NAME     U26 C5
 '@T6G_MB_LIB.T6G(SCH_1):PAGE58_I1@PURE_QUANTA.GENOA_SP5(CHIPS)':
 'VSS_C5': CDS_PINID='VSS_C5';
NODE_NAME     U26 C8
 '@T6G_MB_LIB.T6G(SCH_1):PAGE58_I1@PURE_QUANTA.GENOA_SP5(CHIPS)':
 'VSS_C8': CDS_PINID='VSS_C8';
NODE_NAME     U26 C10
 '@T6G_MB_LIB.T6G(SCH_1):PAGE58_I1@PURE_QUANTA.GENOA_SP5(CHIPS)':
 'VSS_C10': CDS_PINID='VSS_C10';
NODE_NAME     U26 C11
 '@T6G_MB_LIB.T6G(SCH_1):PAGE58_I1@PURE_QUANTA.GENOA_SP5(CHIPS)':
 'VSS_C11': CDS_PINID='VSS_C11';
NODE_NAME     U26 C13
 '@T6G_MB_LIB.T6G(SCH_1):PAGE58_I1@PURE_QUANTA.GENOA_SP5(CHIPS)':
 'VSS_C13': CDS_PINID='VSS_C13';
NODE_NAME     U26 C15
 '@T6G_MB_LIB.T6G(SCH_1):PAGE58_I1@PURE_QUANTA.GENOA_SP5(CHIPS)':
 'VSS_C15': CDS_PINID='VSS_C15';
NODE_NAME     U26 C21
 '@T6G_MB_LIB.T6G(SCH_1):PAGE58_I1@PURE_QUANTA.GENOA_SP5(CHIPS)':
 'VSS_C21': CDS_PINID='VSS_C21';
NODE_NAME     U26 C24
 '@T6G_MB_LIB.T6G(SCH_1):PAGE58_I1@PURE_QUANTA.GENOA_SP5(CHIPS)':
 'VSS_C24': CDS_PINID='VSS_C24';
NODE_NAME     U26 C27
 '@T6G_MB_LIB.T6G(SCH_1):PAGE58_I1@PURE_QUANTA.GENOA_SP5(CHIPS)':
 'VSS_C27': CDS_PINID='VSS_C27';
NODE_NAME     U26 C30
 '@T6G_MB_LIB.T6G(SCH_1):PAGE58_I1@PURE_QUANTA.GENOA_SP5(CHIPS)':
 'VSS_C30': CDS_PINID='VSS_C30';
NODE_NAME     U26 C36
 '@T6G_MB_LIB.T6G(SCH_1):PAGE58_I1@PURE_QUANTA.GENOA_SP5(CHIPS)':
 'VSS_C36': CDS_PINID='VSS_C36';
NODE_NAME     U26 C40
 '@T6G_MB_LIB.T6G(SCH_1):PAGE58_I1@PURE_QUANTA.GENOA_SP5(CHIPS)':
 'VSS_C40': CDS_PINID='VSS_C40';
NODE_NAME     U26 C43
 '@T6G_MB_LIB.T6G(SCH_1):PAGE58_I1@PURE_QUANTA.GENOA_SP5(CHIPS)':
 'VSS_C43': CDS_PINID='VSS_C43';
NODE_NAME     U26 C46
 '@T6G_MB_LIB.T6G(SCH_1):PAGE58_I1@PURE_QUANTA.GENOA_SP5(CHIPS)':
 'VSS_C46': CDS_PINID='VSS_C46';
NODE_NAME     U26 C49
 '@T6G_MB_LIB.T6G(SCH_1):PAGE58_I1@PURE_QUANTA.GENOA_SP5(CHIPS)':
 'VSS_C49': CDS_PINID='VSS_C49';
NODE_NAME     U26 C52
 '@T6G_MB_LIB.T6G(SCH_1):PAGE58_I1@PURE_QUANTA.GENOA_SP5(CHIPS)':
 'VSS_C52': CDS_PINID='VSS_C52';
NODE_NAME     U26 C55
 '@T6G_MB_LIB.T6G(SCH_1):PAGE58_I1@PURE_QUANTA.GENOA_SP5(CHIPS)':
 'VSS_C55': CDS_PINID='VSS_C55';
NODE_NAME     U26 C56
 '@T6G_MB_LIB.T6G(SCH_1):PAGE58_I1@PURE_QUANTA.GENOA_SP5(CHIPS)':
 'VSS_C56': CDS_PINID='VSS_C56';
NODE_NAME     U26 C57
 '@T6G_MB_LIB.T6G(SCH_1):PAGE58_I1@PURE_QUANTA.GENOA_SP5(CHIPS)':
 'VSS_C57': CDS_PINID='VSS_C57';
NODE_NAME     U26 C61
 '@T6G_MB_LIB.T6G(SCH_1):PAGE58_I1@PURE_QUANTA.GENOA_SP5(CHIPS)':
 'VSS_C61': CDS_PINID='VSS_C61';
NODE_NAME     U26 C64
 '@T6G_MB_LIB.T6G(SCH_1):PAGE58_I1@PURE_QUANTA.GENOA_SP5(CHIPS)':
 'VSS_C64': CDS_PINID='VSS_C64';
NODE_NAME     U26 C67
 '@T6G_MB_LIB.T6G(SCH_1):PAGE58_I1@PURE_QUANTA.GENOA_SP5(CHIPS)':
 'VSS_C67': CDS_PINID='VSS_C67';
NODE_NAME     U26 C69
 '@T6G_MB_LIB.T6G(SCH_1):PAGE58_I1@PURE_QUANTA.GENOA_SP5(CHIPS)':
 'VSS_C69': CDS_PINID='VSS_C69';
NODE_NAME     U26 C71
 '@T6G_MB_LIB.T6G(SCH_1):PAGE58_I1@PURE_QUANTA.GENOA_SP5(CHIPS)':
 'VSS_C71': CDS_PINID='VSS_C71';
NODE_NAME     U26 C73
 '@T6G_MB_LIB.T6G(SCH_1):PAGE58_I1@PURE_QUANTA.GENOA_SP5(CHIPS)':
 'VSS_C73': CDS_PINID='VSS_C73';
NODE_NAME     U26 C75
 '@T6G_MB_LIB.T6G(SCH_1):PAGE58_I1@PURE_QUANTA.GENOA_SP5(CHIPS)':
 'VSS_C75': CDS_PINID='VSS_C75';
NODE_NAME     U26 D2
 '@T6G_MB_LIB.T6G(SCH_1):PAGE58_I1@PURE_QUANTA.GENOA_SP5(CHIPS)':
 'VSS_D2': CDS_PINID='VSS_D2';
NODE_NAME     U26 D3
 '@T6G_MB_LIB.T6G(SCH_1):PAGE58_I1@PURE_QUANTA.GENOA_SP5(CHIPS)':
 'VSS_D3': CDS_PINID='VSS_D3';
NODE_NAME     U26 D5
 '@T6G_MB_LIB.T6G(SCH_1):PAGE58_I1@PURE_QUANTA.GENOA_SP5(CHIPS)':
 'VSS_D5': CDS_PINID='VSS_D5';
NODE_NAME     U26 D6
 '@T6G_MB_LIB.T6G(SCH_1):PAGE58_I1@PURE_QUANTA.GENOA_SP5(CHIPS)':
 'VSS_D6': CDS_PINID='VSS_D6';
NODE_NAME     U26 D9
 '@T6G_MB_LIB.T6G(SCH_1):PAGE58_I1@PURE_QUANTA.GENOA_SP5(CHIPS)':
 'VSS_D9': CDS_PINID='VSS_D9';
NODE_NAME     U26 D10
 '@T6G_MB_LIB.T6G(SCH_1):PAGE58_I1@PURE_QUANTA.GENOA_SP5(CHIPS)':
 'VSS_D10': CDS_PINID='VSS_D10';
NODE_NAME     U26 D12
 '@T6G_MB_LIB.T6G(SCH_1):PAGE58_I1@PURE_QUANTA.GENOA_SP5(CHIPS)':
 'VSS_D12': CDS_PINID='VSS_D12';
NODE_NAME     U26 D13
 '@T6G_MB_LIB.T6G(SCH_1):PAGE58_I1@PURE_QUANTA.GENOA_SP5(CHIPS)':
 'VSS_D13': CDS_PINID='VSS_D13';
NODE_NAME     U26 D16
 '@T6G_MB_LIB.T6G(SCH_1):PAGE58_I1@PURE_QUANTA.GENOA_SP5(CHIPS)':
 'VSS_D16': CDS_PINID='VSS_D16';
NODE_NAME     U26 D17
 '@T6G_MB_LIB.T6G(SCH_1):PAGE58_I1@PURE_QUANTA.GENOA_SP5(CHIPS)':
 'VSS_D17': CDS_PINID='VSS_D17';
NODE_NAME     U26 D19
 '@T6G_MB_LIB.T6G(SCH_1):PAGE58_I1@PURE_QUANTA.GENOA_SP5(CHIPS)':
 'VSS_D19': CDS_PINID='VSS_D19';
NODE_NAME     U26 D20
 '@T6G_MB_LIB.T6G(SCH_1):PAGE58_I1@PURE_QUANTA.GENOA_SP5(CHIPS)':
 'VSS_D20': CDS_PINID='VSS_D20';
NODE_NAME     U26 D21
 '@T6G_MB_LIB.T6G(SCH_1):PAGE58_I1@PURE_QUANTA.GENOA_SP5(CHIPS)':
 'VSS_D21': CDS_PINID='VSS_D21';
NODE_NAME     U26 D24
 '@T6G_MB_LIB.T6G(SCH_1):PAGE58_I1@PURE_QUANTA.GENOA_SP5(CHIPS)':
 'VSS_D24': CDS_PINID='VSS_D24';
NODE_NAME     U26 D25
 '@T6G_MB_LIB.T6G(SCH_1):PAGE58_I1@PURE_QUANTA.GENOA_SP5(CHIPS)':
 'VSS_D25': CDS_PINID='VSS_D25';
NODE_NAME     U26 D26
 '@T6G_MB_LIB.T6G(SCH_1):PAGE58_I1@PURE_QUANTA.GENOA_SP5(CHIPS)':
 'VSS_D26': CDS_PINID='VSS_D26';
NODE_NAME     U26 D27
 '@T6G_MB_LIB.T6G(SCH_1):PAGE58_I1@PURE_QUANTA.GENOA_SP5(CHIPS)':
 'VSS_D27': CDS_PINID='VSS_D27';
NODE_NAME     U26 D28
 '@T6G_MB_LIB.T6G(SCH_1):PAGE58_I1@PURE_QUANTA.GENOA_SP5(CHIPS)':
 'VSS_D28': CDS_PINID='VSS_D28';
NODE_NAME     U26 D29
 '@T6G_MB_LIB.T6G(SCH_1):PAGE58_I1@PURE_QUANTA.GENOA_SP5(CHIPS)':
 'VSS_D29': CDS_PINID='VSS_D29';
NODE_NAME     U26 D30
 '@T6G_MB_LIB.T6G(SCH_1):PAGE58_I1@PURE_QUANTA.GENOA_SP5(CHIPS)':
 'VSS_D30': CDS_PINID='VSS_D30';
NODE_NAME     U26 D31
 '@T6G_MB_LIB.T6G(SCH_1):PAGE58_I1@PURE_QUANTA.GENOA_SP5(CHIPS)':
 'VSS_D31': CDS_PINID='VSS_D31';
NODE_NAME     U26 D35
 '@T6G_MB_LIB.T6G(SCH_1):PAGE58_I1@PURE_QUANTA.GENOA_SP5(CHIPS)':
 'VSS_D35': CDS_PINID='VSS_D35';
NODE_NAME     U26 D37
 '@T6G_MB_LIB.T6G(SCH_1):PAGE58_I1@PURE_QUANTA.GENOA_SP5(CHIPS)':
 'VSS_D37': CDS_PINID='VSS_D37';
NODE_NAME     U26 D39
 '@T6G_MB_LIB.T6G(SCH_1):PAGE58_I1@PURE_QUANTA.GENOA_SP5(CHIPS)':
 'VSS_D39': CDS_PINID='VSS_D39';
NODE_NAME     U26 D40
 '@T6G_MB_LIB.T6G(SCH_1):PAGE58_I1@PURE_QUANTA.GENOA_SP5(CHIPS)':
 'VSS_D40': CDS_PINID='VSS_D40';
NODE_NAME     U26 D41
 '@T6G_MB_LIB.T6G(SCH_1):PAGE58_I1@PURE_QUANTA.GENOA_SP5(CHIPS)':
 'VSS_D41': CDS_PINID='VSS_D41';
NODE_NAME     U26 D42
 '@T6G_MB_LIB.T6G(SCH_1):PAGE58_I1@PURE_QUANTA.GENOA_SP5(CHIPS)':
 'VSS_D42': CDS_PINID='VSS_D42';
NODE_NAME     U26 D43
 '@T6G_MB_LIB.T6G(SCH_1):PAGE58_I1@PURE_QUANTA.GENOA_SP5(CHIPS)':
 'VSS_D43': CDS_PINID='VSS_D43';
NODE_NAME     U26 D44
 '@T6G_MB_LIB.T6G(SCH_1):PAGE58_I1@PURE_QUANTA.GENOA_SP5(CHIPS)':
 'VSS_D44': CDS_PINID='VSS_D44';
NODE_NAME     U26 D45
 '@T6G_MB_LIB.T6G(SCH_1):PAGE58_I1@PURE_QUANTA.GENOA_SP5(CHIPS)':
 'VSS_D45': CDS_PINID='VSS_D45';
NODE_NAME     U26 D46
 '@T6G_MB_LIB.T6G(SCH_1):PAGE58_I1@PURE_QUANTA.GENOA_SP5(CHIPS)':
 'VSS_D46': CDS_PINID='VSS_D46';
NODE_NAME     U26 D47
 '@T6G_MB_LIB.T6G(SCH_1):PAGE58_I1@PURE_QUANTA.GENOA_SP5(CHIPS)':
 'VSS_D47': CDS_PINID='VSS_D47';
NODE_NAME     U26 D48
 '@T6G_MB_LIB.T6G(SCH_1):PAGE58_I1@PURE_QUANTA.GENOA_SP5(CHIPS)':
 'VSS_D48': CDS_PINID='VSS_D48';
NODE_NAME     U26 D49
 '@T6G_MB_LIB.T6G(SCH_1):PAGE58_I1@PURE_QUANTA.GENOA_SP5(CHIPS)':
 'VSS_D49': CDS_PINID='VSS_D49';
NODE_NAME     U26 D50
 '@T6G_MB_LIB.T6G(SCH_1):PAGE58_I1@PURE_QUANTA.GENOA_SP5(CHIPS)':
 'VSS_D50': CDS_PINID='VSS_D50';
NODE_NAME     U26 D51
 '@T6G_MB_LIB.T6G(SCH_1):PAGE58_I1@PURE_QUANTA.GENOA_SP5(CHIPS)':
 'VSS_D51': CDS_PINID='VSS_D51';
NODE_NAME     U26 D52
 '@T6G_MB_LIB.T6G(SCH_1):PAGE58_I1@PURE_QUANTA.GENOA_SP5(CHIPS)':
 'VSS_D52': CDS_PINID='VSS_D52';
NODE_NAME     U26 D53
 '@T6G_MB_LIB.T6G(SCH_1):PAGE58_I1@PURE_QUANTA.GENOA_SP5(CHIPS)':
 'VSS_D53': CDS_PINID='VSS_D53';
NODE_NAME     U26 D54
 '@T6G_MB_LIB.T6G(SCH_1):PAGE58_I1@PURE_QUANTA.GENOA_SP5(CHIPS)':
 'VSS_D54': CDS_PINID='VSS_D54';
NODE_NAME     U26 D57
 '@T6G_MB_LIB.T6G(SCH_1):PAGE58_I1@PURE_QUANTA.GENOA_SP5(CHIPS)':
 'VSS_D57': CDS_PINID='VSS_D57';
NODE_NAME     U26 D59
 '@T6G_MB_LIB.T6G(SCH_1):PAGE58_I1@PURE_QUANTA.GENOA_SP5(CHIPS)':
 'VSS_D59': CDS_PINID='VSS_D59';
NODE_NAME     U26 D60
 '@T6G_MB_LIB.T6G(SCH_1):PAGE58_I1@PURE_QUANTA.GENOA_SP5(CHIPS)':
 'VSS_D60': CDS_PINID='VSS_D60';
NODE_NAME     U26 D61
 '@T6G_MB_LIB.T6G(SCH_1):PAGE58_I1@PURE_QUANTA.GENOA_SP5(CHIPS)':
 'VSS_D61': CDS_PINID='VSS_D61';
NODE_NAME     U26 D63
 '@T6G_MB_LIB.T6G(SCH_1):PAGE58_I1@PURE_QUANTA.GENOA_SP5(CHIPS)':
 'VSS_D63': CDS_PINID='VSS_D63';
NODE_NAME     U26 D64
 '@T6G_MB_LIB.T6G(SCH_1):PAGE58_I1@PURE_QUANTA.GENOA_SP5(CHIPS)':
 'VSS_D64': CDS_PINID='VSS_D64';
NODE_NAME     U26 D66
 '@T6G_MB_LIB.T6G(SCH_1):PAGE58_I1@PURE_QUANTA.GENOA_SP5(CHIPS)':
 'VSS_D66': CDS_PINID='VSS_D66';
NODE_NAME     U26 D67
 '@T6G_MB_LIB.T6G(SCH_1):PAGE58_I1@PURE_QUANTA.GENOA_SP5(CHIPS)':
 'VSS_D67': CDS_PINID='VSS_D67';
NODE_NAME     U26 D70
 '@T6G_MB_LIB.T6G(SCH_1):PAGE58_I1@PURE_QUANTA.GENOA_SP5(CHIPS)':
 'VSS_D70': CDS_PINID='VSS_D70';
NODE_NAME     U26 D71
 '@T6G_MB_LIB.T6G(SCH_1):PAGE58_I1@PURE_QUANTA.GENOA_SP5(CHIPS)':
 'VSS_D71': CDS_PINID='VSS_D71';
NODE_NAME     U26 D73
 '@T6G_MB_LIB.T6G(SCH_1):PAGE58_I1@PURE_QUANTA.GENOA_SP5(CHIPS)':
 'VSS_D73': CDS_PINID='VSS_D73';
NODE_NAME     U26 D74
 '@T6G_MB_LIB.T6G(SCH_1):PAGE58_I1@PURE_QUANTA.GENOA_SP5(CHIPS)':
 'VSS_D74': CDS_PINID='VSS_D74';
NODE_NAME     U26 E1
 '@T6G_MB_LIB.T6G(SCH_1):PAGE58_I1@PURE_QUANTA.GENOA_SP5(CHIPS)':
 'VSS_E1': CDS_PINID='VSS_E1';
NODE_NAME     U26 E3
 '@T6G_MB_LIB.T6G(SCH_1):PAGE58_I1@PURE_QUANTA.GENOA_SP5(CHIPS)':
 'VSS_E3': CDS_PINID='VSS_E3';
NODE_NAME     U26 E6
 '@T6G_MB_LIB.T6G(SCH_1):PAGE58_I1@PURE_QUANTA.GENOA_SP5(CHIPS)':
 'VSS_E6': CDS_PINID='VSS_E6';
NODE_NAME     U26 E7
 '@T6G_MB_LIB.T6G(SCH_1):PAGE58_I1@PURE_QUANTA.GENOA_SP5(CHIPS)':
 'VSS_E7': CDS_PINID='VSS_E7';
NODE_NAME     U26 E8
 '@T6G_MB_LIB.T6G(SCH_1):PAGE58_I1@PURE_QUANTA.GENOA_SP5(CHIPS)':
 'VSS_E8': CDS_PINID='VSS_E8';
NODE_NAME     U26 E10
 '@T6G_MB_LIB.T6G(SCH_1):PAGE58_I1@PURE_QUANTA.GENOA_SP5(CHIPS)':
 'VSS_E10': CDS_PINID='VSS_E10';
NODE_NAME     U26 E13
 '@T6G_MB_LIB.T6G(SCH_1):PAGE58_I1@PURE_QUANTA.GENOA_SP5(CHIPS)':
 'VSS_E13': CDS_PINID='VSS_E13';
NODE_NAME     U26 E14
 '@T6G_MB_LIB.T6G(SCH_1):PAGE58_I1@PURE_QUANTA.GENOA_SP5(CHIPS)':
 'VSS_E14': CDS_PINID='VSS_E14';
NODE_NAME     U26 E15
 '@T6G_MB_LIB.T6G(SCH_1):PAGE58_I1@PURE_QUANTA.GENOA_SP5(CHIPS)':
 'VSS_E15': CDS_PINID='VSS_E15';
NODE_NAME     U26 E17
 '@T6G_MB_LIB.T6G(SCH_1):PAGE58_I1@PURE_QUANTA.GENOA_SP5(CHIPS)':
 'VSS_E17': CDS_PINID='VSS_E17';
NODE_NAME     U26 E18
 '@T6G_MB_LIB.T6G(SCH_1):PAGE58_I1@PURE_QUANTA.GENOA_SP5(CHIPS)':
 'VSS_E18': CDS_PINID='VSS_E18';
NODE_NAME     U26 E20
 '@T6G_MB_LIB.T6G(SCH_1):PAGE58_I1@PURE_QUANTA.GENOA_SP5(CHIPS)':
 'VSS_E20': CDS_PINID='VSS_E20';
NODE_NAME     U26 E21
 '@T6G_MB_LIB.T6G(SCH_1):PAGE58_I1@PURE_QUANTA.GENOA_SP5(CHIPS)':
 'VSS_E21': CDS_PINID='VSS_E21';
NODE_NAME     U26 E52
 '@T6G_MB_LIB.T6G(SCH_1):PAGE58_I1@PURE_QUANTA.GENOA_SP5(CHIPS)':
 'VSS_E52': CDS_PINID='VSS_E52';
NODE_NAME     U26 E53
 '@T6G_MB_LIB.T6G(SCH_1):PAGE58_I1@PURE_QUANTA.GENOA_SP5(CHIPS)':
 'VSS_E53': CDS_PINID='VSS_E53';
NODE_NAME     U26 E55
 '@T6G_MB_LIB.T6G(SCH_1):PAGE58_I1@PURE_QUANTA.GENOA_SP5(CHIPS)':
 'VSS_E55': CDS_PINID='VSS_E55';
NODE_NAME     U26 E56
 '@T6G_MB_LIB.T6G(SCH_1):PAGE58_I1@PURE_QUANTA.GENOA_SP5(CHIPS)':
 'VSS_E56': CDS_PINID='VSS_E56';
NODE_NAME     U26 E58
 '@T6G_MB_LIB.T6G(SCH_1):PAGE58_I1@PURE_QUANTA.GENOA_SP5(CHIPS)':
 'VSS_E58': CDS_PINID='VSS_E58';
NODE_NAME     U26 E59
 '@T6G_MB_LIB.T6G(SCH_1):PAGE58_I1@PURE_QUANTA.GENOA_SP5(CHIPS)':
 'VSS_E59': CDS_PINID='VSS_E59';
NODE_NAME     U26 E61
 '@T6G_MB_LIB.T6G(SCH_1):PAGE58_I1@PURE_QUANTA.GENOA_SP5(CHIPS)':
 'VSS_E61': CDS_PINID='VSS_E61';
NODE_NAME     U26 E62
 '@T6G_MB_LIB.T6G(SCH_1):PAGE58_I1@PURE_QUANTA.GENOA_SP5(CHIPS)':
 'VSS_E62': CDS_PINID='VSS_E62';
NODE_NAME     U26 E63
 '@T6G_MB_LIB.T6G(SCH_1):PAGE58_I1@PURE_QUANTA.GENOA_SP5(CHIPS)':
 'VSS_E63': CDS_PINID='VSS_E63';
NODE_NAME     U26 E65
 '@T6G_MB_LIB.T6G(SCH_1):PAGE58_I1@PURE_QUANTA.GENOA_SP5(CHIPS)':
 'VSS_E65': CDS_PINID='VSS_E65';
NODE_NAME     U26 E66
 '@T6G_MB_LIB.T6G(SCH_1):PAGE58_I1@PURE_QUANTA.GENOA_SP5(CHIPS)':
 'VSS_E66': CDS_PINID='VSS_E66';
NODE_NAME     U26 E68
 '@T6G_MB_LIB.T6G(SCH_1):PAGE58_I1@PURE_QUANTA.GENOA_SP5(CHIPS)':
 'VSS_E68': CDS_PINID='VSS_E68';
NODE_NAME     U26 E69
 '@T6G_MB_LIB.T6G(SCH_1):PAGE58_I1@PURE_QUANTA.GENOA_SP5(CHIPS)':
 'VSS_E69': CDS_PINID='VSS_E69';
NODE_NAME     U26 E70
 '@T6G_MB_LIB.T6G(SCH_1):PAGE58_I1@PURE_QUANTA.GENOA_SP5(CHIPS)':
 'VSS_E70': CDS_PINID='VSS_E70';
NODE_NAME     U26 E72
 '@T6G_MB_LIB.T6G(SCH_1):PAGE58_I1@PURE_QUANTA.GENOA_SP5(CHIPS)':
 'VSS_E72': CDS_PINID='VSS_E72';
NODE_NAME     U26 E73
 '@T6G_MB_LIB.T6G(SCH_1):PAGE58_I1@PURE_QUANTA.GENOA_SP5(CHIPS)':
 'VSS_E73': CDS_PINID='VSS_E73';
NODE_NAME     U26 E75
 '@T6G_MB_LIB.T6G(SCH_1):PAGE58_I1@PURE_QUANTA.GENOA_SP5(CHIPS)':
 'VSS_E75': CDS_PINID='VSS_E75';
NODE_NAME     U26 F3
 '@T6G_MB_LIB.T6G(SCH_1):PAGE58_I1@PURE_QUANTA.GENOA_SP5(CHIPS)':
 'VSS_F3': CDS_PINID='VSS_F3';
NODE_NAME     U26 F5
 '@T6G_MB_LIB.T6G(SCH_1):PAGE58_I1@PURE_QUANTA.GENOA_SP5(CHIPS)':
 'VSS_F5': CDS_PINID='VSS_F5';
NODE_NAME     U26 F8
 '@T6G_MB_LIB.T6G(SCH_1):PAGE58_I1@PURE_QUANTA.GENOA_SP5(CHIPS)':
 'VSS_F8': CDS_PINID='VSS_F8';
NODE_NAME     U26 F10
 '@T6G_MB_LIB.T6G(SCH_1):PAGE58_I1@PURE_QUANTA.GENOA_SP5(CHIPS)':
 'VSS_F10': CDS_PINID='VSS_F10';
NODE_NAME     U26 F12
 '@T6G_MB_LIB.T6G(SCH_1):PAGE58_I1@PURE_QUANTA.GENOA_SP5(CHIPS)':
 'VSS_F12': CDS_PINID='VSS_F12';
NODE_NAME     U26 F15
 '@T6G_MB_LIB.T6G(SCH_1):PAGE58_I1@PURE_QUANTA.GENOA_SP5(CHIPS)':
 'VSS_F15': CDS_PINID='VSS_F15';
NODE_NAME     U26 F17
 '@T6G_MB_LIB.T6G(SCH_1):PAGE58_I1@PURE_QUANTA.GENOA_SP5(CHIPS)':
 'VSS_F17': CDS_PINID='VSS_F17';
NODE_NAME     U26 F19
 '@T6G_MB_LIB.T6G(SCH_1):PAGE58_I1@PURE_QUANTA.GENOA_SP5(CHIPS)':
 'VSS_F19': CDS_PINID='VSS_F19';
NODE_NAME     U26 F23
 '@T6G_MB_LIB.T6G(SCH_1):PAGE58_I1@PURE_QUANTA.GENOA_SP5(CHIPS)':
 'VSS_F23': CDS_PINID='VSS_F23';
NODE_NAME     U26 F24
 '@T6G_MB_LIB.T6G(SCH_1):PAGE58_I1@PURE_QUANTA.GENOA_SP5(CHIPS)':
 'VSS_F24': CDS_PINID='VSS_F24';
NODE_NAME     U26 F26
 '@T6G_MB_LIB.T6G(SCH_1):PAGE58_I1@PURE_QUANTA.GENOA_SP5(CHIPS)':
 'VSS_F26': CDS_PINID='VSS_F26';
NODE_NAME     U26 F27
 '@T6G_MB_LIB.T6G(SCH_1):PAGE58_I1@PURE_QUANTA.GENOA_SP5(CHIPS)':
 'VSS_F27': CDS_PINID='VSS_F27';
NODE_NAME     U26 F29
 '@T6G_MB_LIB.T6G(SCH_1):PAGE58_I1@PURE_QUANTA.GENOA_SP5(CHIPS)':
 'VSS_F29': CDS_PINID='VSS_F29';
NODE_NAME     U26 F30
 '@T6G_MB_LIB.T6G(SCH_1):PAGE58_I1@PURE_QUANTA.GENOA_SP5(CHIPS)':
 'VSS_F30': CDS_PINID='VSS_F30';
NODE_NAME     U26 F32
 '@T6G_MB_LIB.T6G(SCH_1):PAGE58_I1@PURE_QUANTA.GENOA_SP5(CHIPS)':
 'VSS_F32': CDS_PINID='VSS_F32';
NODE_NAME     U26 F33
 '@T6G_MB_LIB.T6G(SCH_1):PAGE58_I1@PURE_QUANTA.GENOA_SP5(CHIPS)':
 'VSS_F33': CDS_PINID='VSS_F33';
NODE_NAME     U26 F35
 '@T6G_MB_LIB.T6G(SCH_1):PAGE58_I1@PURE_QUANTA.GENOA_SP5(CHIPS)':
 'VSS_F35': CDS_PINID='VSS_F35';
NODE_NAME     U26 F36
 '@T6G_MB_LIB.T6G(SCH_1):PAGE58_I1@PURE_QUANTA.GENOA_SP5(CHIPS)':
 'VSS_F36': CDS_PINID='VSS_F36';
NODE_NAME     U26 F37
 '@T6G_MB_LIB.T6G(SCH_1):PAGE58_I1@PURE_QUANTA.GENOA_SP5(CHIPS)':
 'VSS_F37': CDS_PINID='VSS_F37';
NODE_NAME     U26 F39
 '@T6G_MB_LIB.T6G(SCH_1):PAGE58_I1@PURE_QUANTA.GENOA_SP5(CHIPS)':
 'VSS_F39': CDS_PINID='VSS_F39';
NODE_NAME     U26 F40
 '@T6G_MB_LIB.T6G(SCH_1):PAGE58_I1@PURE_QUANTA.GENOA_SP5(CHIPS)':
 'VSS_F40': CDS_PINID='VSS_F40';
NODE_NAME     U26 F41
 '@T6G_MB_LIB.T6G(SCH_1):PAGE58_I1@PURE_QUANTA.GENOA_SP5(CHIPS)':
 'VSS_F41': CDS_PINID='VSS_F41';
NODE_NAME     U26 F43
 '@T6G_MB_LIB.T6G(SCH_1):PAGE58_I1@PURE_QUANTA.GENOA_SP5(CHIPS)':
 'VSS_F43': CDS_PINID='VSS_F43';
NODE_NAME     U26 F44
 '@T6G_MB_LIB.T6G(SCH_1):PAGE58_I1@PURE_QUANTA.GENOA_SP5(CHIPS)':
 'VSS_F44': CDS_PINID='VSS_F44';
NODE_NAME     U26 F46
 '@T6G_MB_LIB.T6G(SCH_1):PAGE58_I1@PURE_QUANTA.GENOA_SP5(CHIPS)':
 'VSS_F46': CDS_PINID='VSS_F46';
NODE_NAME     U26 F47
 '@T6G_MB_LIB.T6G(SCH_1):PAGE58_I1@PURE_QUANTA.GENOA_SP5(CHIPS)':
 'VSS_F47': CDS_PINID='VSS_F47';
NODE_NAME     U26 F49
 '@T6G_MB_LIB.T6G(SCH_1):PAGE58_I1@PURE_QUANTA.GENOA_SP5(CHIPS)':
 'VSS_F49': CDS_PINID='VSS_F49';
NODE_NAME     U26 F50
 '@T6G_MB_LIB.T6G(SCH_1):PAGE58_I1@PURE_QUANTA.GENOA_SP5(CHIPS)':
 'VSS_F50': CDS_PINID='VSS_F50';
NODE_NAME     U26 F52
 '@T6G_MB_LIB.T6G(SCH_1):PAGE58_I1@PURE_QUANTA.GENOA_SP5(CHIPS)':
 'VSS_F52': CDS_PINID='VSS_F52';
NODE_NAME     U26 F53
 '@T6G_MB_LIB.T6G(SCH_1):PAGE58_I1@PURE_QUANTA.GENOA_SP5(CHIPS)':
 'VSS_F53': CDS_PINID='VSS_F53';
NODE_NAME     U26 F57
 '@T6G_MB_LIB.T6G(SCH_1):PAGE58_I1@PURE_QUANTA.GENOA_SP5(CHIPS)':
 'VSS_F57': CDS_PINID='VSS_F57';
NODE_NAME     U26 F59
 '@T6G_MB_LIB.T6G(SCH_1):PAGE58_I1@PURE_QUANTA.GENOA_SP5(CHIPS)':
 'VSS_F59': CDS_PINID='VSS_F59';
NODE_NAME     U26 F61
 '@T6G_MB_LIB.T6G(SCH_1):PAGE58_I1@PURE_QUANTA.GENOA_SP5(CHIPS)':
 'VSS_F61': CDS_PINID='VSS_F61';
NODE_NAME     U26 F64
 '@T6G_MB_LIB.T6G(SCH_1):PAGE58_I1@PURE_QUANTA.GENOA_SP5(CHIPS)':
 'VSS_F64': CDS_PINID='VSS_F64';
NODE_NAME     U26 F66
 '@T6G_MB_LIB.T6G(SCH_1):PAGE58_I1@PURE_QUANTA.GENOA_SP5(CHIPS)':
 'VSS_F66': CDS_PINID='VSS_F66';
NODE_NAME     U26 F68
 '@T6G_MB_LIB.T6G(SCH_1):PAGE58_I1@PURE_QUANTA.GENOA_SP5(CHIPS)':
 'VSS_F68': CDS_PINID='VSS_F68';
NODE_NAME     U26 F71
 '@T6G_MB_LIB.T6G(SCH_1):PAGE58_I1@PURE_QUANTA.GENOA_SP5(CHIPS)':
 'VSS_F71': CDS_PINID='VSS_F71';
NODE_NAME     U26 F73
 '@T6G_MB_LIB.T6G(SCH_1):PAGE58_I1@PURE_QUANTA.GENOA_SP5(CHIPS)':
 'VSS_F73': CDS_PINID='VSS_F73';
NODE_NAME     U26 G1
 '@T6G_MB_LIB.T6G(SCH_1):PAGE58_I1@PURE_QUANTA.GENOA_SP5(CHIPS)':
 'VSS_G1': CDS_PINID='VSS_G1';
NODE_NAME     U26 G4
 '@T6G_MB_LIB.T6G(SCH_1):PAGE58_I1@PURE_QUANTA.GENOA_SP5(CHIPS)':
 'VSS_G4': CDS_PINID='VSS_G4';
NODE_NAME     U26 G6
 '@T6G_MB_LIB.T6G(SCH_1):PAGE58_I1@PURE_QUANTA.GENOA_SP5(CHIPS)':
 'VSS_G6': CDS_PINID='VSS_G6';
NODE_NAME     U26 G8
 '@T6G_MB_LIB.T6G(SCH_1):PAGE58_I1@PURE_QUANTA.GENOA_SP5(CHIPS)':
 'VSS_G8': CDS_PINID='VSS_G8';
NODE_NAME     U26 G11
 '@T6G_MB_LIB.T6G(SCH_1):PAGE58_I1@PURE_QUANTA.GENOA_SP5(CHIPS)':
 'VSS_G11': CDS_PINID='VSS_G11';
NODE_NAME     U26 G13
 '@T6G_MB_LIB.T6G(SCH_1):PAGE58_I1@PURE_QUANTA.GENOA_SP5(CHIPS)':
 'VSS_G13': CDS_PINID='VSS_G13';
NODE_NAME     U26 G15
 '@T6G_MB_LIB.T6G(SCH_1):PAGE58_I1@PURE_QUANTA.GENOA_SP5(CHIPS)':
 'VSS_G15': CDS_PINID='VSS_G15';
NODE_NAME     U26 G18
 '@T6G_MB_LIB.T6G(SCH_1):PAGE58_I1@PURE_QUANTA.GENOA_SP5(CHIPS)':
 'VSS_G18': CDS_PINID='VSS_G18';
NODE_NAME     U26 G20
 '@T6G_MB_LIB.T6G(SCH_1):PAGE58_I1@PURE_QUANTA.GENOA_SP5(CHIPS)':
 'VSS_G20': CDS_PINID='VSS_G20';
NODE_NAME     U26 G22
 '@T6G_MB_LIB.T6G(SCH_1):PAGE58_I1@PURE_QUANTA.GENOA_SP5(CHIPS)':
 'VSS_G22': CDS_PINID='VSS_G22';
NODE_NAME     U26 G25
 '@T6G_MB_LIB.T6G(SCH_1):PAGE58_I1@PURE_QUANTA.GENOA_SP5(CHIPS)':
 'VSS_G25': CDS_PINID='VSS_G25';
NODE_NAME     U26 G28
 '@T6G_MB_LIB.T6G(SCH_1):PAGE58_I1@PURE_QUANTA.GENOA_SP5(CHIPS)':
 'VSS_G28': CDS_PINID='VSS_G28';
NODE_NAME     U26 G31
 '@T6G_MB_LIB.T6G(SCH_1):PAGE58_I1@PURE_QUANTA.GENOA_SP5(CHIPS)':
 'VSS_G31': CDS_PINID='VSS_G31';
NODE_NAME     U26 G34
 '@T6G_MB_LIB.T6G(SCH_1):PAGE58_I1@PURE_QUANTA.GENOA_SP5(CHIPS)':
 'VSS_G34': CDS_PINID='VSS_G34';
NODE_NAME     U26 G42
 '@T6G_MB_LIB.T6G(SCH_1):PAGE58_I1@PURE_QUANTA.GENOA_SP5(CHIPS)':
 'VSS_G42': CDS_PINID='VSS_G42';
NODE_NAME     U26 G45
 '@T6G_MB_LIB.T6G(SCH_1):PAGE58_I1@PURE_QUANTA.GENOA_SP5(CHIPS)':
 'VSS_G45': CDS_PINID='VSS_G45';
NODE_NAME     U26 G48
 '@T6G_MB_LIB.T6G(SCH_1):PAGE58_I1@PURE_QUANTA.GENOA_SP5(CHIPS)':
 'VSS_G48': CDS_PINID='VSS_G48';
NODE_NAME     U26 G51
 '@T6G_MB_LIB.T6G(SCH_1):PAGE58_I1@PURE_QUANTA.GENOA_SP5(CHIPS)':
 'VSS_G51': CDS_PINID='VSS_G51';
NODE_NAME     U26 G54
 '@T6G_MB_LIB.T6G(SCH_1):PAGE58_I1@PURE_QUANTA.GENOA_SP5(CHIPS)':
 'VSS_G54': CDS_PINID='VSS_G54';
NODE_NAME     U26 G56
 '@T6G_MB_LIB.T6G(SCH_1):PAGE58_I1@PURE_QUANTA.GENOA_SP5(CHIPS)':
 'VSS_G56': CDS_PINID='VSS_G56';
NODE_NAME     U26 G58
 '@T6G_MB_LIB.T6G(SCH_1):PAGE58_I1@PURE_QUANTA.GENOA_SP5(CHIPS)':
 'VSS_G58': CDS_PINID='VSS_G58';
NODE_NAME     U26 G61
 '@T6G_MB_LIB.T6G(SCH_1):PAGE58_I1@PURE_QUANTA.GENOA_SP5(CHIPS)':
 'VSS_G61': CDS_PINID='VSS_G61';
NODE_NAME     U26 G63
 '@T6G_MB_LIB.T6G(SCH_1):PAGE58_I1@PURE_QUANTA.GENOA_SP5(CHIPS)':
 'VSS_G63': CDS_PINID='VSS_G63';
NODE_NAME     U26 G65
 '@T6G_MB_LIB.T6G(SCH_1):PAGE58_I1@PURE_QUANTA.GENOA_SP5(CHIPS)':
 'VSS_G65': CDS_PINID='VSS_G65';
NODE_NAME     U26 G68
 '@T6G_MB_LIB.T6G(SCH_1):PAGE58_I1@PURE_QUANTA.GENOA_SP5(CHIPS)':
 'VSS_G68': CDS_PINID='VSS_G68';
NODE_NAME     U26 G70
 '@T6G_MB_LIB.T6G(SCH_1):PAGE58_I1@PURE_QUANTA.GENOA_SP5(CHIPS)':
 'VSS_G70': CDS_PINID='VSS_G70';
NODE_NAME     U26 G72
 '@T6G_MB_LIB.T6G(SCH_1):PAGE58_I1@PURE_QUANTA.GENOA_SP5(CHIPS)':
 'VSS_G72': CDS_PINID='VSS_G72';
NODE_NAME     U26 G75
 '@T6G_MB_LIB.T6G(SCH_1):PAGE58_I1@PURE_QUANTA.GENOA_SP5(CHIPS)':
 'VSS_G75': CDS_PINID='VSS_G75';
NODE_NAME     U26 H3
 '@T6G_MB_LIB.T6G(SCH_1):PAGE58_I1@PURE_QUANTA.GENOA_SP5(CHIPS)':
 'VSS_H3': CDS_PINID='VSS_H3';
NODE_NAME     U26 H8
 '@T6G_MB_LIB.T6G(SCH_1):PAGE58_I1@PURE_QUANTA.GENOA_SP5(CHIPS)':
 'VSS_H8': CDS_PINID='VSS_H8';
NODE_NAME     U26 H10
 '@T6G_MB_LIB.T6G(SCH_1):PAGE58_I1@PURE_QUANTA.GENOA_SP5(CHIPS)':
 'VSS_H10': CDS_PINID='VSS_H10';
NODE_NAME     U26 H15
 '@T6G_MB_LIB.T6G(SCH_1):PAGE58_I1@PURE_QUANTA.GENOA_SP5(CHIPS)':
 'VSS_H15': CDS_PINID='VSS_H15';
NODE_NAME     U26 H17
 '@T6G_MB_LIB.T6G(SCH_1):PAGE58_I1@PURE_QUANTA.GENOA_SP5(CHIPS)':
 'VSS_H17': CDS_PINID='VSS_H17';
NODE_NAME     U26 H22
 '@T6G_MB_LIB.T6G(SCH_1):PAGE58_I1@PURE_QUANTA.GENOA_SP5(CHIPS)':
 'VSS_H22': CDS_PINID='VSS_H22';
NODE_NAME     U26 H25
 '@T6G_MB_LIB.T6G(SCH_1):PAGE58_I1@PURE_QUANTA.GENOA_SP5(CHIPS)':
 'VSS_H25': CDS_PINID='VSS_H25';
NODE_NAME     U26 H28
 '@T6G_MB_LIB.T6G(SCH_1):PAGE58_I1@PURE_QUANTA.GENOA_SP5(CHIPS)':
 'VSS_H28': CDS_PINID='VSS_H28';
NODE_NAME     U26 H31
 '@T6G_MB_LIB.T6G(SCH_1):PAGE58_I1@PURE_QUANTA.GENOA_SP5(CHIPS)':
 'VSS_H31': CDS_PINID='VSS_H31';
NODE_NAME     U26 H34
 '@T6G_MB_LIB.T6G(SCH_1):PAGE58_I1@PURE_QUANTA.GENOA_SP5(CHIPS)':
 'VSS_H34': CDS_PINID='VSS_H34';
NODE_NAME     U26 H37
 '@T6G_MB_LIB.T6G(SCH_1):PAGE58_I1@PURE_QUANTA.GENOA_SP5(CHIPS)':
 'VSS_H37': CDS_PINID='VSS_H37';
NODE_NAME     U26 H39
 '@T6G_MB_LIB.T6G(SCH_1):PAGE58_I1@PURE_QUANTA.GENOA_SP5(CHIPS)':
 'VSS_H39': CDS_PINID='VSS_H39';
NODE_NAME     U26 H42
 '@T6G_MB_LIB.T6G(SCH_1):PAGE58_I1@PURE_QUANTA.GENOA_SP5(CHIPS)':
 'VSS_H42': CDS_PINID='VSS_H42';
NODE_NAME     U26 H45
 '@T6G_MB_LIB.T6G(SCH_1):PAGE58_I1@PURE_QUANTA.GENOA_SP5(CHIPS)':
 'VSS_H45': CDS_PINID='VSS_H45';
NODE_NAME     U26 H48
 '@T6G_MB_LIB.T6G(SCH_1):PAGE58_I1@PURE_QUANTA.GENOA_SP5(CHIPS)':
 'VSS_H48': CDS_PINID='VSS_H48';
NODE_NAME     U26 H51
 '@T6G_MB_LIB.T6G(SCH_1):PAGE58_I1@PURE_QUANTA.GENOA_SP5(CHIPS)':
 'VSS_H51': CDS_PINID='VSS_H51';
NODE_NAME     U26 H54
 '@T6G_MB_LIB.T6G(SCH_1):PAGE58_I1@PURE_QUANTA.GENOA_SP5(CHIPS)':
 'VSS_H54': CDS_PINID='VSS_H54';
NODE_NAME     U26 H59
 '@T6G_MB_LIB.T6G(SCH_1):PAGE58_I1@PURE_QUANTA.GENOA_SP5(CHIPS)':
 'VSS_H59': CDS_PINID='VSS_H59';
NODE_NAME     U26 H61
 '@T6G_MB_LIB.T6G(SCH_1):PAGE58_I1@PURE_QUANTA.GENOA_SP5(CHIPS)':
 'VSS_H61': CDS_PINID='VSS_H61';
NODE_NAME     U26 H66
 '@T6G_MB_LIB.T6G(SCH_1):PAGE58_I1@PURE_QUANTA.GENOA_SP5(CHIPS)':
 'VSS_H66': CDS_PINID='VSS_H66';
NODE_NAME     U26 H68
 '@T6G_MB_LIB.T6G(SCH_1):PAGE58_I1@PURE_QUANTA.GENOA_SP5(CHIPS)':
 'VSS_H68': CDS_PINID='VSS_H68';
NODE_NAME     U26 H73
 '@T6G_MB_LIB.T6G(SCH_1):PAGE58_I1@PURE_QUANTA.GENOA_SP5(CHIPS)':
 'VSS_H73': CDS_PINID='VSS_H73';
NODE_NAME     U26 J1
 '@T6G_MB_LIB.T6G(SCH_1):PAGE58_I1@PURE_QUANTA.GENOA_SP5(CHIPS)':
 'VSS_J1': CDS_PINID='VSS_J1';
NODE_NAME     U26 J4
 '@T6G_MB_LIB.T6G(SCH_1):PAGE58_I1@PURE_QUANTA.GENOA_SP5(CHIPS)':
 'VSS_J4': CDS_PINID='VSS_J4';
NODE_NAME     U26 J6
 '@T6G_MB_LIB.T6G(SCH_1):PAGE58_I1@PURE_QUANTA.GENOA_SP5(CHIPS)':
 'VSS_J6': CDS_PINID='VSS_J6';
NODE_NAME     U26 J8
 '@T6G_MB_LIB.T6G(SCH_1):PAGE58_I1@PURE_QUANTA.GENOA_SP5(CHIPS)':
 'VSS_J8': CDS_PINID='VSS_J8';
NODE_NAME     U26 J11
 '@T6G_MB_LIB.T6G(SCH_1):PAGE58_I1@PURE_QUANTA.GENOA_SP5(CHIPS)':
 'VSS_J11': CDS_PINID='VSS_J11';
NODE_NAME     U26 J13
 '@T6G_MB_LIB.T6G(SCH_1):PAGE58_I1@PURE_QUANTA.GENOA_SP5(CHIPS)':
 'VSS_J13': CDS_PINID='VSS_J13';
NODE_NAME     U26 AW63
 '@T6G_MB_LIB.T6G(SCH_1):PAGE58_I3@PURE_QUANTA.GENOA_SP5(CHIPS)':
 'VSS_AW63': CDS_PINID='VSS_AW63';
NODE_NAME     U26 AW65
 '@T6G_MB_LIB.T6G(SCH_1):PAGE58_I3@PURE_QUANTA.GENOA_SP5(CHIPS)':
 'VSS_AW65': CDS_PINID='VSS_AW65';
NODE_NAME     U26 AW68
 '@T6G_MB_LIB.T6G(SCH_1):PAGE58_I3@PURE_QUANTA.GENOA_SP5(CHIPS)':
 'VSS_AW68': CDS_PINID='VSS_AW68';
NODE_NAME     U26 AW70
 '@T6G_MB_LIB.T6G(SCH_1):PAGE58_I3@PURE_QUANTA.GENOA_SP5(CHIPS)':
 'VSS_AW70': CDS_PINID='VSS_AW70';
NODE_NAME     U26 AW72
 '@T6G_MB_LIB.T6G(SCH_1):PAGE58_I3@PURE_QUANTA.GENOA_SP5(CHIPS)':
 'VSS_AW72': CDS_PINID='VSS_AW72';
NODE_NAME     U26 AW75
 '@T6G_MB_LIB.T6G(SCH_1):PAGE58_I3@PURE_QUANTA.GENOA_SP5(CHIPS)':
 'VSS_AW75': CDS_PINID='VSS_AW75';
NODE_NAME     U26 AY3
 '@T6G_MB_LIB.T6G(SCH_1):PAGE58_I3@PURE_QUANTA.GENOA_SP5(CHIPS)':
 'VSS_AY3': CDS_PINID='VSS_AY3';
NODE_NAME     U26 AY5
 '@T6G_MB_LIB.T6G(SCH_1):PAGE58_I3@PURE_QUANTA.GENOA_SP5(CHIPS)':
 'VSS_AY5': CDS_PINID='VSS_AY5';
NODE_NAME     U26 AY8
 '@T6G_MB_LIB.T6G(SCH_1):PAGE58_I3@PURE_QUANTA.GENOA_SP5(CHIPS)':
 'VSS_AY8': CDS_PINID='VSS_AY8';
NODE_NAME     U26 AY10
 '@T6G_MB_LIB.T6G(SCH_1):PAGE58_I3@PURE_QUANTA.GENOA_SP5(CHIPS)':
 'VSS_AY10': CDS_PINID='VSS_AY10';
NODE_NAME     U26 AY12
 '@T6G_MB_LIB.T6G(SCH_1):PAGE58_I3@PURE_QUANTA.GENOA_SP5(CHIPS)':
 'VSS_AY12': CDS_PINID='VSS_AY12';
NODE_NAME     U26 AY15
 '@T6G_MB_LIB.T6G(SCH_1):PAGE58_I3@PURE_QUANTA.GENOA_SP5(CHIPS)':
 'VSS_AY15': CDS_PINID='VSS_AY15';
NODE_NAME     U26 AY17
 '@T6G_MB_LIB.T6G(SCH_1):PAGE58_I3@PURE_QUANTA.GENOA_SP5(CHIPS)':
 'VSS_AY17': CDS_PINID='VSS_AY17';
NODE_NAME     U26 AY19
 '@T6G_MB_LIB.T6G(SCH_1):PAGE58_I3@PURE_QUANTA.GENOA_SP5(CHIPS)':
 'VSS_AY19': CDS_PINID='VSS_AY19';
NODE_NAME     U26 AY23
 '@T6G_MB_LIB.T6G(SCH_1):PAGE58_I3@PURE_QUANTA.GENOA_SP5(CHIPS)':
 'VSS_AY23': CDS_PINID='VSS_AY23';
NODE_NAME     U26 AY25
 '@T6G_MB_LIB.T6G(SCH_1):PAGE58_I3@PURE_QUANTA.GENOA_SP5(CHIPS)':
 'VSS_AY25': CDS_PINID='VSS_AY25';
NODE_NAME     U26 AY27
 '@T6G_MB_LIB.T6G(SCH_1):PAGE58_I3@PURE_QUANTA.GENOA_SP5(CHIPS)':
 'VSS_AY27': CDS_PINID='VSS_AY27';
NODE_NAME     U26 AY48
 '@T6G_MB_LIB.T6G(SCH_1):PAGE58_I3@PURE_QUANTA.GENOA_SP5(CHIPS)':
 'VSS_AY48': CDS_PINID='VSS_AY48';
NODE_NAME     U26 AY50
 '@T6G_MB_LIB.T6G(SCH_1):PAGE58_I3@PURE_QUANTA.GENOA_SP5(CHIPS)':
 'VSS_AY50': CDS_PINID='VSS_AY50';
NODE_NAME     U26 AY52
 '@T6G_MB_LIB.T6G(SCH_1):PAGE58_I3@PURE_QUANTA.GENOA_SP5(CHIPS)':
 'VSS_AY52': CDS_PINID='VSS_AY52';
NODE_NAME     U26 AY54
 '@T6G_MB_LIB.T6G(SCH_1):PAGE58_I3@PURE_QUANTA.GENOA_SP5(CHIPS)':
 'VSS_AY54': CDS_PINID='VSS_AY54';
NODE_NAME     U26 AY57
 '@T6G_MB_LIB.T6G(SCH_1):PAGE58_I3@PURE_QUANTA.GENOA_SP5(CHIPS)':
 'VSS_AY57': CDS_PINID='VSS_AY57';
NODE_NAME     U26 AY59
 '@T6G_MB_LIB.T6G(SCH_1):PAGE58_I3@PURE_QUANTA.GENOA_SP5(CHIPS)':
 'VSS_AY59': CDS_PINID='VSS_AY59';
NODE_NAME     U26 AY61
 '@T6G_MB_LIB.T6G(SCH_1):PAGE58_I3@PURE_QUANTA.GENOA_SP5(CHIPS)':
 'VSS_AY61': CDS_PINID='VSS_AY61';
NODE_NAME     U26 AY64
 '@T6G_MB_LIB.T6G(SCH_1):PAGE58_I3@PURE_QUANTA.GENOA_SP5(CHIPS)':
 'VSS_AY64': CDS_PINID='VSS_AY64';
NODE_NAME     U26 AY66
 '@T6G_MB_LIB.T6G(SCH_1):PAGE58_I3@PURE_QUANTA.GENOA_SP5(CHIPS)':
 'VSS_AY66': CDS_PINID='VSS_AY66';
NODE_NAME     U26 AY68
 '@T6G_MB_LIB.T6G(SCH_1):PAGE58_I3@PURE_QUANTA.GENOA_SP5(CHIPS)':
 'VSS_AY68': CDS_PINID='VSS_AY68';
NODE_NAME     U26 AY71
 '@T6G_MB_LIB.T6G(SCH_1):PAGE58_I3@PURE_QUANTA.GENOA_SP5(CHIPS)':
 'VSS_AY71': CDS_PINID='VSS_AY71';
NODE_NAME     U26 AY73
 '@T6G_MB_LIB.T6G(SCH_1):PAGE58_I3@PURE_QUANTA.GENOA_SP5(CHIPS)':
 'VSS_AY73': CDS_PINID='VSS_AY73';
NODE_NAME     U26 BA1
 '@T6G_MB_LIB.T6G(SCH_1):PAGE58_I3@PURE_QUANTA.GENOA_SP5(CHIPS)':
 'VSS_BA1': CDS_PINID='VSS_BA1';
NODE_NAME     U26 BA6
 '@T6G_MB_LIB.T6G(SCH_1):PAGE58_I3@PURE_QUANTA.GENOA_SP5(CHIPS)':
 'VSS_BA6': CDS_PINID='VSS_BA6';
NODE_NAME     U26 BA8
 '@T6G_MB_LIB.T6G(SCH_1):PAGE58_I3@PURE_QUANTA.GENOA_SP5(CHIPS)':
 'VSS_BA8': CDS_PINID='VSS_BA8';
NODE_NAME     U26 BA13
 '@T6G_MB_LIB.T6G(SCH_1):PAGE58_I3@PURE_QUANTA.GENOA_SP5(CHIPS)':
 'VSS_BA13': CDS_PINID='VSS_BA13';
NODE_NAME     U26 BA15
 '@T6G_MB_LIB.T6G(SCH_1):PAGE58_I3@PURE_QUANTA.GENOA_SP5(CHIPS)':
 'VSS_BA15': CDS_PINID='VSS_BA15';
NODE_NAME     U26 BA20
 '@T6G_MB_LIB.T6G(SCH_1):PAGE58_I3@PURE_QUANTA.GENOA_SP5(CHIPS)':
 'VSS_BA20': CDS_PINID='VSS_BA20';
NODE_NAME     U26 BA22
 '@T6G_MB_LIB.T6G(SCH_1):PAGE58_I3@PURE_QUANTA.GENOA_SP5(CHIPS)':
 'VSS_BA22': CDS_PINID='VSS_BA22';
NODE_NAME     U26 BA24
 '@T6G_MB_LIB.T6G(SCH_1):PAGE58_I3@PURE_QUANTA.GENOA_SP5(CHIPS)':
 'VSS_BA24': CDS_PINID='VSS_BA24';
NODE_NAME     U26 BA26
 '@T6G_MB_LIB.T6G(SCH_1):PAGE58_I3@PURE_QUANTA.GENOA_SP5(CHIPS)':
 'VSS_BA26': CDS_PINID='VSS_BA26';
NODE_NAME     U26 BA28
 '@T6G_MB_LIB.T6G(SCH_1):PAGE58_I3@PURE_QUANTA.GENOA_SP5(CHIPS)':
 'VSS_BA28': CDS_PINID='VSS_BA28';
NODE_NAME     U26 BA49
 '@T6G_MB_LIB.T6G(SCH_1):PAGE58_I3@PURE_QUANTA.GENOA_SP5(CHIPS)':
 'VSS_BA49': CDS_PINID='VSS_BA49';
NODE_NAME     U26 BA51
 '@T6G_MB_LIB.T6G(SCH_1):PAGE58_I3@PURE_QUANTA.GENOA_SP5(CHIPS)':
 'VSS_BA51': CDS_PINID='VSS_BA51';
NODE_NAME     U26 BA53
 '@T6G_MB_LIB.T6G(SCH_1):PAGE58_I3@PURE_QUANTA.GENOA_SP5(CHIPS)':
 'VSS_BA53': CDS_PINID='VSS_BA53';
NODE_NAME     U26 BA56
 '@T6G_MB_LIB.T6G(SCH_1):PAGE58_I3@PURE_QUANTA.GENOA_SP5(CHIPS)':
 'VSS_BA56': CDS_PINID='VSS_BA56';
NODE_NAME     U26 BA61
 '@T6G_MB_LIB.T6G(SCH_1):PAGE58_I3@PURE_QUANTA.GENOA_SP5(CHIPS)':
 'VSS_BA61': CDS_PINID='VSS_BA61';
NODE_NAME     U26 BA63
 '@T6G_MB_LIB.T6G(SCH_1):PAGE58_I3@PURE_QUANTA.GENOA_SP5(CHIPS)':
 'VSS_BA63': CDS_PINID='VSS_BA63';
NODE_NAME     U26 BA68
 '@T6G_MB_LIB.T6G(SCH_1):PAGE58_I3@PURE_QUANTA.GENOA_SP5(CHIPS)':
 'VSS_BA68': CDS_PINID='VSS_BA68';
NODE_NAME     U26 BA70
 '@T6G_MB_LIB.T6G(SCH_1):PAGE58_I3@PURE_QUANTA.GENOA_SP5(CHIPS)':
 'VSS_BA70': CDS_PINID='VSS_BA70';
NODE_NAME     U26 BA75
 '@T6G_MB_LIB.T6G(SCH_1):PAGE58_I3@PURE_QUANTA.GENOA_SP5(CHIPS)':
 'VSS_BA75': CDS_PINID='VSS_BA75';
NODE_NAME     U26 BB3
 '@T6G_MB_LIB.T6G(SCH_1):PAGE58_I3@PURE_QUANTA.GENOA_SP5(CHIPS)':
 'VSS_BB3': CDS_PINID='VSS_BB3';
NODE_NAME     U26 BB5
 '@T6G_MB_LIB.T6G(SCH_1):PAGE58_I3@PURE_QUANTA.GENOA_SP5(CHIPS)':
 'VSS_BB5': CDS_PINID='VSS_BB5';
NODE_NAME     U26 BB8
 '@T6G_MB_LIB.T6G(SCH_1):PAGE58_I3@PURE_QUANTA.GENOA_SP5(CHIPS)':
 'VSS_BB8': CDS_PINID='VSS_BB8';
NODE_NAME     U26 BB10
 '@T6G_MB_LIB.T6G(SCH_1):PAGE58_I3@PURE_QUANTA.GENOA_SP5(CHIPS)':
 'VSS_BB10': CDS_PINID='VSS_BB10';
NODE_NAME     U26 BB12
 '@T6G_MB_LIB.T6G(SCH_1):PAGE58_I3@PURE_QUANTA.GENOA_SP5(CHIPS)':
 'VSS_BB12': CDS_PINID='VSS_BB12';
NODE_NAME     U26 BB15
 '@T6G_MB_LIB.T6G(SCH_1):PAGE58_I3@PURE_QUANTA.GENOA_SP5(CHIPS)':
 'VSS_BB15': CDS_PINID='VSS_BB15';
NODE_NAME     U26 BB17
 '@T6G_MB_LIB.T6G(SCH_1):PAGE58_I3@PURE_QUANTA.GENOA_SP5(CHIPS)':
 'VSS_BB17': CDS_PINID='VSS_BB17';
NODE_NAME     U26 BB19
 '@T6G_MB_LIB.T6G(SCH_1):PAGE58_I3@PURE_QUANTA.GENOA_SP5(CHIPS)':
 'VSS_BB19': CDS_PINID='VSS_BB19';
NODE_NAME     U26 BB23
 '@T6G_MB_LIB.T6G(SCH_1):PAGE58_I3@PURE_QUANTA.GENOA_SP5(CHIPS)':
 'VSS_BB23': CDS_PINID='VSS_BB23';
NODE_NAME     U26 BB25
 '@T6G_MB_LIB.T6G(SCH_1):PAGE58_I3@PURE_QUANTA.GENOA_SP5(CHIPS)':
 'VSS_BB25': CDS_PINID='VSS_BB25';
NODE_NAME     U26 BB27
 '@T6G_MB_LIB.T6G(SCH_1):PAGE58_I3@PURE_QUANTA.GENOA_SP5(CHIPS)':
 'VSS_BB27': CDS_PINID='VSS_BB27';
NODE_NAME     U26 BB48
 '@T6G_MB_LIB.T6G(SCH_1):PAGE58_I3@PURE_QUANTA.GENOA_SP5(CHIPS)':
 'VSS_BB48': CDS_PINID='VSS_BB48';
NODE_NAME     U26 BB50
 '@T6G_MB_LIB.T6G(SCH_1):PAGE58_I3@PURE_QUANTA.GENOA_SP5(CHIPS)':
 'VSS_BB50': CDS_PINID='VSS_BB50';
NODE_NAME     U26 BB52
 '@T6G_MB_LIB.T6G(SCH_1):PAGE58_I3@PURE_QUANTA.GENOA_SP5(CHIPS)':
 'VSS_BB52': CDS_PINID='VSS_BB52';
NODE_NAME     U26 BB54
 '@T6G_MB_LIB.T6G(SCH_1):PAGE58_I3@PURE_QUANTA.GENOA_SP5(CHIPS)':
 'VSS_BB54': CDS_PINID='VSS_BB54';
NODE_NAME     U26 BB57
 '@T6G_MB_LIB.T6G(SCH_1):PAGE58_I3@PURE_QUANTA.GENOA_SP5(CHIPS)':
 'VSS_BB57': CDS_PINID='VSS_BB57';
NODE_NAME     U26 BB59
 '@T6G_MB_LIB.T6G(SCH_1):PAGE58_I3@PURE_QUANTA.GENOA_SP5(CHIPS)':
 'VSS_BB59': CDS_PINID='VSS_BB59';
NODE_NAME     U26 BB61
 '@T6G_MB_LIB.T6G(SCH_1):PAGE58_I3@PURE_QUANTA.GENOA_SP5(CHIPS)':
 'VSS_BB61': CDS_PINID='VSS_BB61';
NODE_NAME     U26 BB64
 '@T6G_MB_LIB.T6G(SCH_1):PAGE58_I3@PURE_QUANTA.GENOA_SP5(CHIPS)':
 'VSS_BB64': CDS_PINID='VSS_BB64';
NODE_NAME     U26 BB66
 '@T6G_MB_LIB.T6G(SCH_1):PAGE58_I3@PURE_QUANTA.GENOA_SP5(CHIPS)':
 'VSS_BB66': CDS_PINID='VSS_BB66';
NODE_NAME     U26 BB68
 '@T6G_MB_LIB.T6G(SCH_1):PAGE58_I3@PURE_QUANTA.GENOA_SP5(CHIPS)':
 'VSS_BB68': CDS_PINID='VSS_BB68';
NODE_NAME     U26 BB71
 '@T6G_MB_LIB.T6G(SCH_1):PAGE58_I3@PURE_QUANTA.GENOA_SP5(CHIPS)':
 'VSS_BB71': CDS_PINID='VSS_BB71';
NODE_NAME     U26 BB73
 '@T6G_MB_LIB.T6G(SCH_1):PAGE58_I3@PURE_QUANTA.GENOA_SP5(CHIPS)':
 'VSS_BB73': CDS_PINID='VSS_BB73';
NODE_NAME     U26 BC1
 '@T6G_MB_LIB.T6G(SCH_1):PAGE58_I3@PURE_QUANTA.GENOA_SP5(CHIPS)':
 'VSS_BC1': CDS_PINID='VSS_BC1';
NODE_NAME     U26 BC4
 '@T6G_MB_LIB.T6G(SCH_1):PAGE58_I3@PURE_QUANTA.GENOA_SP5(CHIPS)':
 'VSS_BC4': CDS_PINID='VSS_BC4';
NODE_NAME     U26 BC6
 '@T6G_MB_LIB.T6G(SCH_1):PAGE58_I3@PURE_QUANTA.GENOA_SP5(CHIPS)':
 'VSS_BC6': CDS_PINID='VSS_BC6';
NODE_NAME     U26 BC8
 '@T6G_MB_LIB.T6G(SCH_1):PAGE58_I3@PURE_QUANTA.GENOA_SP5(CHIPS)':
 'VSS_BC8': CDS_PINID='VSS_BC8';
NODE_NAME     U26 BC11
 '@T6G_MB_LIB.T6G(SCH_1):PAGE58_I3@PURE_QUANTA.GENOA_SP5(CHIPS)':
 'VSS_BC11': CDS_PINID='VSS_BC11';
NODE_NAME     U26 BC13
 '@T6G_MB_LIB.T6G(SCH_1):PAGE58_I3@PURE_QUANTA.GENOA_SP5(CHIPS)':
 'VSS_BC13': CDS_PINID='VSS_BC13';
NODE_NAME     U26 BC15
 '@T6G_MB_LIB.T6G(SCH_1):PAGE58_I3@PURE_QUANTA.GENOA_SP5(CHIPS)':
 'VSS_BC15': CDS_PINID='VSS_BC15';
NODE_NAME     U26 BC18
 '@T6G_MB_LIB.T6G(SCH_1):PAGE58_I3@PURE_QUANTA.GENOA_SP5(CHIPS)':
 'VSS_BC18': CDS_PINID='VSS_BC18';
NODE_NAME     U26 BC20
 '@T6G_MB_LIB.T6G(SCH_1):PAGE58_I3@PURE_QUANTA.GENOA_SP5(CHIPS)':
 'VSS_BC20': CDS_PINID='VSS_BC20';
NODE_NAME     U26 BC22
 '@T6G_MB_LIB.T6G(SCH_1):PAGE58_I3@PURE_QUANTA.GENOA_SP5(CHIPS)':
 'VSS_BC22': CDS_PINID='VSS_BC22';
NODE_NAME     U26 BC24
 '@T6G_MB_LIB.T6G(SCH_1):PAGE58_I3@PURE_QUANTA.GENOA_SP5(CHIPS)':
 'VSS_BC24': CDS_PINID='VSS_BC24';
NODE_NAME     U26 BC26
 '@T6G_MB_LIB.T6G(SCH_1):PAGE58_I3@PURE_QUANTA.GENOA_SP5(CHIPS)':
 'VSS_BC26': CDS_PINID='VSS_BC26';
NODE_NAME     U26 BC28
 '@T6G_MB_LIB.T6G(SCH_1):PAGE58_I3@PURE_QUANTA.GENOA_SP5(CHIPS)':
 'VSS_BC28': CDS_PINID='VSS_BC28';
NODE_NAME     U26 BC49
 '@T6G_MB_LIB.T6G(SCH_1):PAGE58_I3@PURE_QUANTA.GENOA_SP5(CHIPS)':
 'VSS_BC49': CDS_PINID='VSS_BC49';
NODE_NAME     U26 BC50
 '@T6G_MB_LIB.T6G(SCH_1):PAGE58_I3@PURE_QUANTA.GENOA_SP5(CHIPS)':
 'VSS_BC50': CDS_PINID='VSS_BC50';
NODE_NAME     U26 BC51
 '@T6G_MB_LIB.T6G(SCH_1):PAGE58_I3@PURE_QUANTA.GENOA_SP5(CHIPS)':
 'VSS_BC51': CDS_PINID='VSS_BC51';
NODE_NAME     U26 BC53
 '@T6G_MB_LIB.T6G(SCH_1):PAGE58_I3@PURE_QUANTA.GENOA_SP5(CHIPS)':
 'VSS_BC53': CDS_PINID='VSS_BC53';
NODE_NAME     U26 BC56
 '@T6G_MB_LIB.T6G(SCH_1):PAGE58_I3@PURE_QUANTA.GENOA_SP5(CHIPS)':
 'VSS_BC56': CDS_PINID='VSS_BC56';
NODE_NAME     U26 BC58
 '@T6G_MB_LIB.T6G(SCH_1):PAGE58_I3@PURE_QUANTA.GENOA_SP5(CHIPS)':
 'VSS_BC58': CDS_PINID='VSS_BC58';
NODE_NAME     U26 BC61
 '@T6G_MB_LIB.T6G(SCH_1):PAGE58_I3@PURE_QUANTA.GENOA_SP5(CHIPS)':
 'VSS_BC61': CDS_PINID='VSS_BC61';
NODE_NAME     U26 BC63
 '@T6G_MB_LIB.T6G(SCH_1):PAGE58_I3@PURE_QUANTA.GENOA_SP5(CHIPS)':
 'VSS_BC63': CDS_PINID='VSS_BC63';
NODE_NAME     U26 BC65
 '@T6G_MB_LIB.T6G(SCH_1):PAGE58_I3@PURE_QUANTA.GENOA_SP5(CHIPS)':
 'VSS_BC65': CDS_PINID='VSS_BC65';
NODE_NAME     U26 BC68
 '@T6G_MB_LIB.T6G(SCH_1):PAGE58_I3@PURE_QUANTA.GENOA_SP5(CHIPS)':
 'VSS_BC68': CDS_PINID='VSS_BC68';
NODE_NAME     U26 BC70
 '@T6G_MB_LIB.T6G(SCH_1):PAGE58_I3@PURE_QUANTA.GENOA_SP5(CHIPS)':
 'VSS_BC70': CDS_PINID='VSS_BC70';
NODE_NAME     U26 BC72
 '@T6G_MB_LIB.T6G(SCH_1):PAGE58_I3@PURE_QUANTA.GENOA_SP5(CHIPS)':
 'VSS_BC72': CDS_PINID='VSS_BC72';
NODE_NAME     U26 BC75
 '@T6G_MB_LIB.T6G(SCH_1):PAGE58_I3@PURE_QUANTA.GENOA_SP5(CHIPS)':
 'VSS_BC75': CDS_PINID='VSS_BC75';
NODE_NAME     U26 BD3
 '@T6G_MB_LIB.T6G(SCH_1):PAGE58_I3@PURE_QUANTA.GENOA_SP5(CHIPS)':
 'VSS_BD3': CDS_PINID='VSS_BD3';
NODE_NAME     U26 BD8
 '@T6G_MB_LIB.T6G(SCH_1):PAGE58_I3@PURE_QUANTA.GENOA_SP5(CHIPS)':
 'VSS_BD8': CDS_PINID='VSS_BD8';
NODE_NAME     U26 BD10
 '@T6G_MB_LIB.T6G(SCH_1):PAGE58_I3@PURE_QUANTA.GENOA_SP5(CHIPS)':
 'VSS_BD10': CDS_PINID='VSS_BD10';
NODE_NAME     U26 BD15
 '@T6G_MB_LIB.T6G(SCH_1):PAGE58_I3@PURE_QUANTA.GENOA_SP5(CHIPS)':
 'VSS_BD15': CDS_PINID='VSS_BD15';
NODE_NAME     U26 BD17
 '@T6G_MB_LIB.T6G(SCH_1):PAGE58_I3@PURE_QUANTA.GENOA_SP5(CHIPS)':
 'VSS_BD17': CDS_PINID='VSS_BD17';
NODE_NAME     U26 BD23
 '@T6G_MB_LIB.T6G(SCH_1):PAGE58_I3@PURE_QUANTA.GENOA_SP5(CHIPS)':
 'VSS_BD23': CDS_PINID='VSS_BD23';
NODE_NAME     U26 BD25
 '@T6G_MB_LIB.T6G(SCH_1):PAGE58_I3@PURE_QUANTA.GENOA_SP5(CHIPS)':
 'VSS_BD25': CDS_PINID='VSS_BD25';
NODE_NAME     U26 BD27
 '@T6G_MB_LIB.T6G(SCH_1):PAGE58_I3@PURE_QUANTA.GENOA_SP5(CHIPS)':
 'VSS_BD27': CDS_PINID='VSS_BD27';
NODE_NAME     U26 BD49
 '@T6G_MB_LIB.T6G(SCH_1):PAGE58_I3@PURE_QUANTA.GENOA_SP5(CHIPS)':
 'VSS_BD49': CDS_PINID='VSS_BD49';
NODE_NAME     U26 BD51
 '@T6G_MB_LIB.T6G(SCH_1):PAGE58_I3@PURE_QUANTA.GENOA_SP5(CHIPS)':
 'VSS_BD51': CDS_PINID='VSS_BD51';
NODE_NAME     U26 BD53
 '@T6G_MB_LIB.T6G(SCH_1):PAGE58_I3@PURE_QUANTA.GENOA_SP5(CHIPS)':
 'VSS_BD53': CDS_PINID='VSS_BD53';
NODE_NAME     U26 BD57
 '@T6G_MB_LIB.T6G(SCH_1):PAGE58_I3@PURE_QUANTA.GENOA_SP5(CHIPS)':
 'VSS_BD57': CDS_PINID='VSS_BD57';
NODE_NAME     U26 BD59
 '@T6G_MB_LIB.T6G(SCH_1):PAGE58_I3@PURE_QUANTA.GENOA_SP5(CHIPS)':
 'VSS_BD59': CDS_PINID='VSS_BD59';
NODE_NAME     U26 BD61
 '@T6G_MB_LIB.T6G(SCH_1):PAGE58_I3@PURE_QUANTA.GENOA_SP5(CHIPS)':
 'VSS_BD61': CDS_PINID='VSS_BD61';
NODE_NAME     U26 BD64
 '@T6G_MB_LIB.T6G(SCH_1):PAGE58_I3@PURE_QUANTA.GENOA_SP5(CHIPS)':
 'VSS_BD64': CDS_PINID='VSS_BD64';
NODE_NAME     U26 BD66
 '@T6G_MB_LIB.T6G(SCH_1):PAGE58_I3@PURE_QUANTA.GENOA_SP5(CHIPS)':
 'VSS_BD66': CDS_PINID='VSS_BD66';
NODE_NAME     U26 BD68
 '@T6G_MB_LIB.T6G(SCH_1):PAGE58_I3@PURE_QUANTA.GENOA_SP5(CHIPS)':
 'VSS_BD68': CDS_PINID='VSS_BD68';
NODE_NAME     U26 BD71
 '@T6G_MB_LIB.T6G(SCH_1):PAGE58_I3@PURE_QUANTA.GENOA_SP5(CHIPS)':
 'VSS_BD71': CDS_PINID='VSS_BD71';
NODE_NAME     U26 BD73
 '@T6G_MB_LIB.T6G(SCH_1):PAGE58_I3@PURE_QUANTA.GENOA_SP5(CHIPS)':
 'VSS_BD73': CDS_PINID='VSS_BD73';
NODE_NAME     U26 BF3
 '@T6G_MB_LIB.T6G(SCH_1):PAGE58_I3@PURE_QUANTA.GENOA_SP5(CHIPS)':
 'VSS_BF3': CDS_PINID='VSS_BF3';
NODE_NAME     U26 BF5
 '@T6G_MB_LIB.T6G(SCH_1):PAGE58_I3@PURE_QUANTA.GENOA_SP5(CHIPS)':
 'VSS_BF5': CDS_PINID='VSS_BF5';
NODE_NAME     U26 BF8
 '@T6G_MB_LIB.T6G(SCH_1):PAGE58_I3@PURE_QUANTA.GENOA_SP5(CHIPS)':
 'VSS_BF8': CDS_PINID='VSS_BF8';
NODE_NAME     U26 BF10
 '@T6G_MB_LIB.T6G(SCH_1):PAGE58_I3@PURE_QUANTA.GENOA_SP5(CHIPS)':
 'VSS_BF10': CDS_PINID='VSS_BF10';
NODE_NAME     U26 BF12
 '@T6G_MB_LIB.T6G(SCH_1):PAGE58_I3@PURE_QUANTA.GENOA_SP5(CHIPS)':
 'VSS_BF12': CDS_PINID='VSS_BF12';
NODE_NAME     U26 BF15
 '@T6G_MB_LIB.T6G(SCH_1):PAGE58_I3@PURE_QUANTA.GENOA_SP5(CHIPS)':
 'VSS_BF15': CDS_PINID='VSS_BF15';
NODE_NAME     U26 BF17
 '@T6G_MB_LIB.T6G(SCH_1):PAGE58_I3@PURE_QUANTA.GENOA_SP5(CHIPS)':
 'VSS_BF17': CDS_PINID='VSS_BF17';
NODE_NAME     U26 BF19
 '@T6G_MB_LIB.T6G(SCH_1):PAGE58_I3@PURE_QUANTA.GENOA_SP5(CHIPS)':
 'VSS_BF19': CDS_PINID='VSS_BF19';
NODE_NAME     U26 BF22
 '@T6G_MB_LIB.T6G(SCH_1):PAGE58_I3@PURE_QUANTA.GENOA_SP5(CHIPS)':
 'VSS_BF22': CDS_PINID='VSS_BF22';
NODE_NAME     U26 BF24
 '@T6G_MB_LIB.T6G(SCH_1):PAGE58_I3@PURE_QUANTA.GENOA_SP5(CHIPS)':
 'VSS_BF24': CDS_PINID='VSS_BF24';
NODE_NAME     U26 BF26
 '@T6G_MB_LIB.T6G(SCH_1):PAGE58_I3@PURE_QUANTA.GENOA_SP5(CHIPS)':
 'VSS_BF26': CDS_PINID='VSS_BF26';
NODE_NAME     U26 BF28
 '@T6G_MB_LIB.T6G(SCH_1):PAGE58_I3@PURE_QUANTA.GENOA_SP5(CHIPS)':
 'VSS_BF28': CDS_PINID='VSS_BF28';
NODE_NAME     U26 BF49
 '@T6G_MB_LIB.T6G(SCH_1):PAGE58_I3@PURE_QUANTA.GENOA_SP5(CHIPS)':
 'VSS_BF49': CDS_PINID='VSS_BF49';
NODE_NAME     U26 BF50
 '@T6G_MB_LIB.T6G(SCH_1):PAGE58_I3@PURE_QUANTA.GENOA_SP5(CHIPS)':
 'VSS_BF50': CDS_PINID='VSS_BF50';
NODE_NAME     U26 BF52
 '@T6G_MB_LIB.T6G(SCH_1):PAGE58_I3@PURE_QUANTA.GENOA_SP5(CHIPS)':
 'VSS_BF52': CDS_PINID='VSS_BF52';
NODE_NAME     U26 BF54
 '@T6G_MB_LIB.T6G(SCH_1):PAGE58_I3@PURE_QUANTA.GENOA_SP5(CHIPS)':
 'VSS_BF54': CDS_PINID='VSS_BF54';
NODE_NAME     U26 BF59
 '@T6G_MB_LIB.T6G(SCH_1):PAGE58_I3@PURE_QUANTA.GENOA_SP5(CHIPS)':
 'VSS_BF59': CDS_PINID='VSS_BF59';
NODE_NAME     U26 BF61
 '@T6G_MB_LIB.T6G(SCH_1):PAGE58_I3@PURE_QUANTA.GENOA_SP5(CHIPS)':
 'VSS_BF61': CDS_PINID='VSS_BF61';
NODE_NAME     U26 BF66
 '@T6G_MB_LIB.T6G(SCH_1):PAGE58_I3@PURE_QUANTA.GENOA_SP5(CHIPS)':
 'VSS_BF66': CDS_PINID='VSS_BF66';
NODE_NAME     U26 BF68
 '@T6G_MB_LIB.T6G(SCH_1):PAGE58_I3@PURE_QUANTA.GENOA_SP5(CHIPS)':
 'VSS_BF68': CDS_PINID='VSS_BF68';
NODE_NAME     U26 BF73
 '@T6G_MB_LIB.T6G(SCH_1):PAGE58_I3@PURE_QUANTA.GENOA_SP5(CHIPS)':
 'VSS_BF73': CDS_PINID='VSS_BF73';
NODE_NAME     U26 BG1
 '@T6G_MB_LIB.T6G(SCH_1):PAGE58_I3@PURE_QUANTA.GENOA_SP5(CHIPS)':
 'VSS_BG1': CDS_PINID='VSS_BG1';
NODE_NAME     U26 BG4
 '@T6G_MB_LIB.T6G(SCH_1):PAGE58_I3@PURE_QUANTA.GENOA_SP5(CHIPS)':
 'VSS_BG4': CDS_PINID='VSS_BG4';
NODE_NAME     U26 BG6
 '@T6G_MB_LIB.T6G(SCH_1):PAGE58_I3@PURE_QUANTA.GENOA_SP5(CHIPS)':
 'VSS_BG6': CDS_PINID='VSS_BG6';
NODE_NAME     U26 BG8
 '@T6G_MB_LIB.T6G(SCH_1):PAGE58_I3@PURE_QUANTA.GENOA_SP5(CHIPS)':
 'VSS_BG8': CDS_PINID='VSS_BG8';
NODE_NAME     U26 BG11
 '@T6G_MB_LIB.T6G(SCH_1):PAGE58_I3@PURE_QUANTA.GENOA_SP5(CHIPS)':
 'VSS_BG11': CDS_PINID='VSS_BG11';
NODE_NAME     U26 BG13
 '@T6G_MB_LIB.T6G(SCH_1):PAGE58_I3@PURE_QUANTA.GENOA_SP5(CHIPS)':
 'VSS_BG13': CDS_PINID='VSS_BG13';
NODE_NAME     U26 BG15
 '@T6G_MB_LIB.T6G(SCH_1):PAGE58_I3@PURE_QUANTA.GENOA_SP5(CHIPS)':
 'VSS_BG15': CDS_PINID='VSS_BG15';
NODE_NAME     U26 BG18
 '@T6G_MB_LIB.T6G(SCH_1):PAGE58_I3@PURE_QUANTA.GENOA_SP5(CHIPS)':
 'VSS_BG18': CDS_PINID='VSS_BG18';
NODE_NAME     U26 BG20
 '@T6G_MB_LIB.T6G(SCH_1):PAGE58_I3@PURE_QUANTA.GENOA_SP5(CHIPS)':
 'VSS_BG20': CDS_PINID='VSS_BG20';
NODE_NAME     U26 BG23
 '@T6G_MB_LIB.T6G(SCH_1):PAGE58_I3@PURE_QUANTA.GENOA_SP5(CHIPS)':
 'VSS_BG23': CDS_PINID='VSS_BG23';
NODE_NAME     U26 BG25
 '@T6G_MB_LIB.T6G(SCH_1):PAGE58_I3@PURE_QUANTA.GENOA_SP5(CHIPS)':
 'VSS_BG25': CDS_PINID='VSS_BG25';
NODE_NAME     U26 BG27
 '@T6G_MB_LIB.T6G(SCH_1):PAGE58_I3@PURE_QUANTA.GENOA_SP5(CHIPS)':
 'VSS_BG27': CDS_PINID='VSS_BG27';
NODE_NAME     U26 BG49
 '@T6G_MB_LIB.T6G(SCH_1):PAGE58_I3@PURE_QUANTA.GENOA_SP5(CHIPS)':
 'VSS_BG49': CDS_PINID='VSS_BG49';
NODE_NAME     U26 BG51
 '@T6G_MB_LIB.T6G(SCH_1):PAGE58_I3@PURE_QUANTA.GENOA_SP5(CHIPS)':
 'VSS_BG51': CDS_PINID='VSS_BG51';
NODE_NAME     U26 BG53
 '@T6G_MB_LIB.T6G(SCH_1):PAGE58_I3@PURE_QUANTA.GENOA_SP5(CHIPS)':
 'VSS_BG53': CDS_PINID='VSS_BG53';
NODE_NAME     U26 BG56
 '@T6G_MB_LIB.T6G(SCH_1):PAGE58_I3@PURE_QUANTA.GENOA_SP5(CHIPS)':
 'VSS_BG56': CDS_PINID='VSS_BG56';
NODE_NAME     U26 BG58
 '@T6G_MB_LIB.T6G(SCH_1):PAGE58_I3@PURE_QUANTA.GENOA_SP5(CHIPS)':
 'VSS_BG58': CDS_PINID='VSS_BG58';
NODE_NAME     U26 BG61
 '@T6G_MB_LIB.T6G(SCH_1):PAGE58_I3@PURE_QUANTA.GENOA_SP5(CHIPS)':
 'VSS_BG61': CDS_PINID='VSS_BG61';
NODE_NAME     U26 BG63
 '@T6G_MB_LIB.T6G(SCH_1):PAGE58_I3@PURE_QUANTA.GENOA_SP5(CHIPS)':
 'VSS_BG63': CDS_PINID='VSS_BG63';
NODE_NAME     U26 BG65
 '@T6G_MB_LIB.T6G(SCH_1):PAGE58_I3@PURE_QUANTA.GENOA_SP5(CHIPS)':
 'VSS_BG65': CDS_PINID='VSS_BG65';
NODE_NAME     U26 BG68
 '@T6G_MB_LIB.T6G(SCH_1):PAGE58_I3@PURE_QUANTA.GENOA_SP5(CHIPS)':
 'VSS_BG68': CDS_PINID='VSS_BG68';
NODE_NAME     U26 BG70
 '@T6G_MB_LIB.T6G(SCH_1):PAGE58_I3@PURE_QUANTA.GENOA_SP5(CHIPS)':
 'VSS_BG70': CDS_PINID='VSS_BG70';
NODE_NAME     U26 BG72
 '@T6G_MB_LIB.T6G(SCH_1):PAGE58_I3@PURE_QUANTA.GENOA_SP5(CHIPS)':
 'VSS_BG72': CDS_PINID='VSS_BG72';
NODE_NAME     U26 BG75
 '@T6G_MB_LIB.T6G(SCH_1):PAGE58_I3@PURE_QUANTA.GENOA_SP5(CHIPS)':
 'VSS_BG75': CDS_PINID='VSS_BG75';
NODE_NAME     U26 BH3
 '@T6G_MB_LIB.T6G(SCH_1):PAGE58_I3@PURE_QUANTA.GENOA_SP5(CHIPS)':
 'VSS_BH3': CDS_PINID='VSS_BH3';
NODE_NAME     U26 BH5
 '@T6G_MB_LIB.T6G(SCH_1):PAGE58_I3@PURE_QUANTA.GENOA_SP5(CHIPS)':
 'VSS_BH5': CDS_PINID='VSS_BH5';
NODE_NAME     U26 BH8
 '@T6G_MB_LIB.T6G(SCH_1):PAGE58_I3@PURE_QUANTA.GENOA_SP5(CHIPS)':
 'VSS_BH8': CDS_PINID='VSS_BH8';
NODE_NAME     U26 BH10
 '@T6G_MB_LIB.T6G(SCH_1):PAGE58_I3@PURE_QUANTA.GENOA_SP5(CHIPS)':
 'VSS_BH10': CDS_PINID='VSS_BH10';
NODE_NAME     U26 BH12
 '@T6G_MB_LIB.T6G(SCH_1):PAGE58_I3@PURE_QUANTA.GENOA_SP5(CHIPS)':
 'VSS_BH12': CDS_PINID='VSS_BH12';
NODE_NAME     U26 BH15
 '@T6G_MB_LIB.T6G(SCH_1):PAGE58_I3@PURE_QUANTA.GENOA_SP5(CHIPS)':
 'VSS_BH15': CDS_PINID='VSS_BH15';
NODE_NAME     U26 BH17
 '@T6G_MB_LIB.T6G(SCH_1):PAGE58_I3@PURE_QUANTA.GENOA_SP5(CHIPS)':
 'VSS_BH17': CDS_PINID='VSS_BH17';
NODE_NAME     U26 BH19
 '@T6G_MB_LIB.T6G(SCH_1):PAGE58_I3@PURE_QUANTA.GENOA_SP5(CHIPS)':
 'VSS_BH19': CDS_PINID='VSS_BH19';
NODE_NAME     U26 BH22
 '@T6G_MB_LIB.T6G(SCH_1):PAGE58_I3@PURE_QUANTA.GENOA_SP5(CHIPS)':
 'VSS_BH22': CDS_PINID='VSS_BH22';
NODE_NAME     U26 BH24
 '@T6G_MB_LIB.T6G(SCH_1):PAGE58_I3@PURE_QUANTA.GENOA_SP5(CHIPS)':
 'VSS_BH24': CDS_PINID='VSS_BH24';
NODE_NAME     U26 BH26
 '@T6G_MB_LIB.T6G(SCH_1):PAGE58_I3@PURE_QUANTA.GENOA_SP5(CHIPS)':
 'VSS_BH26': CDS_PINID='VSS_BH26';
NODE_NAME     U26 BH28
 '@T6G_MB_LIB.T6G(SCH_1):PAGE58_I3@PURE_QUANTA.GENOA_SP5(CHIPS)':
 'VSS_BH28': CDS_PINID='VSS_BH28';
NODE_NAME     U26 BH49
 '@T6G_MB_LIB.T6G(SCH_1):PAGE58_I3@PURE_QUANTA.GENOA_SP5(CHIPS)':
 'VSS_BH49': CDS_PINID='VSS_BH49';
NODE_NAME     U26 BH50
 '@T6G_MB_LIB.T6G(SCH_1):PAGE58_I3@PURE_QUANTA.GENOA_SP5(CHIPS)':
 'VSS_BH50': CDS_PINID='VSS_BH50';
NODE_NAME     U26 BH52
 '@T6G_MB_LIB.T6G(SCH_1):PAGE58_I3@PURE_QUANTA.GENOA_SP5(CHIPS)':
 'VSS_BH52': CDS_PINID='VSS_BH52';
NODE_NAME     U26 BH54
 '@T6G_MB_LIB.T6G(SCH_1):PAGE58_I3@PURE_QUANTA.GENOA_SP5(CHIPS)':
 'VSS_BH54': CDS_PINID='VSS_BH54';
NODE_NAME     U26 BH57
 '@T6G_MB_LIB.T6G(SCH_1):PAGE58_I3@PURE_QUANTA.GENOA_SP5(CHIPS)':
 'VSS_BH57': CDS_PINID='VSS_BH57';
NODE_NAME     U26 BH59
 '@T6G_MB_LIB.T6G(SCH_1):PAGE58_I3@PURE_QUANTA.GENOA_SP5(CHIPS)':
 'VSS_BH59': CDS_PINID='VSS_BH59';
NODE_NAME     U26 BH61
 '@T6G_MB_LIB.T6G(SCH_1):PAGE58_I3@PURE_QUANTA.GENOA_SP5(CHIPS)':
 'VSS_BH61': CDS_PINID='VSS_BH61';
NODE_NAME     U26 BH64
 '@T6G_MB_LIB.T6G(SCH_1):PAGE58_I3@PURE_QUANTA.GENOA_SP5(CHIPS)':
 'VSS_BH64': CDS_PINID='VSS_BH64';
NODE_NAME     U26 BH66
 '@T6G_MB_LIB.T6G(SCH_1):PAGE58_I3@PURE_QUANTA.GENOA_SP5(CHIPS)':
 'VSS_BH66': CDS_PINID='VSS_BH66';
NODE_NAME     U26 BH68
 '@T6G_MB_LIB.T6G(SCH_1):PAGE58_I3@PURE_QUANTA.GENOA_SP5(CHIPS)':
 'VSS_BH68': CDS_PINID='VSS_BH68';
NODE_NAME     U26 BH71
 '@T6G_MB_LIB.T6G(SCH_1):PAGE58_I3@PURE_QUANTA.GENOA_SP5(CHIPS)':
 'VSS_BH71': CDS_PINID='VSS_BH71';
NODE_NAME     U26 BH73
 '@T6G_MB_LIB.T6G(SCH_1):PAGE58_I3@PURE_QUANTA.GENOA_SP5(CHIPS)':
 'VSS_BH73': CDS_PINID='VSS_BH73';
NODE_NAME     U26 BJ1
 '@T6G_MB_LIB.T6G(SCH_1):PAGE58_I3@PURE_QUANTA.GENOA_SP5(CHIPS)':
 'VSS_BJ1': CDS_PINID='VSS_BJ1';
NODE_NAME     U26 BJ6
 '@T6G_MB_LIB.T6G(SCH_1):PAGE58_I3@PURE_QUANTA.GENOA_SP5(CHIPS)':
 'VSS_BJ6': CDS_PINID='VSS_BJ6';
NODE_NAME     U26 BJ8
 '@T6G_MB_LIB.T6G(SCH_1):PAGE58_I3@PURE_QUANTA.GENOA_SP5(CHIPS)':
 'VSS_BJ8': CDS_PINID='VSS_BJ8';
NODE_NAME     U26 BJ13
 '@T6G_MB_LIB.T6G(SCH_1):PAGE58_I3@PURE_QUANTA.GENOA_SP5(CHIPS)':
 'VSS_BJ13': CDS_PINID='VSS_BJ13';
NODE_NAME     U26 BJ15
 '@T6G_MB_LIB.T6G(SCH_1):PAGE58_I3@PURE_QUANTA.GENOA_SP5(CHIPS)':
 'VSS_BJ15': CDS_PINID='VSS_BJ15';
NODE_NAME     U26 BJ20
 '@T6G_MB_LIB.T6G(SCH_1):PAGE58_I3@PURE_QUANTA.GENOA_SP5(CHIPS)':
 'VSS_BJ20': CDS_PINID='VSS_BJ20';
NODE_NAME     U26 BJ22
 '@T6G_MB_LIB.T6G(SCH_1):PAGE58_I3@PURE_QUANTA.GENOA_SP5(CHIPS)':
 'VSS_BJ22': CDS_PINID='VSS_BJ22';
NODE_NAME     U26 BJ24
 '@T6G_MB_LIB.T6G(SCH_1):PAGE58_I3@PURE_QUANTA.GENOA_SP5(CHIPS)':
 'VSS_BJ24': CDS_PINID='VSS_BJ24';
NODE_NAME     U26 BJ26
 '@T6G_MB_LIB.T6G(SCH_1):PAGE58_I3@PURE_QUANTA.GENOA_SP5(CHIPS)':
 'VSS_BJ26': CDS_PINID='VSS_BJ26';
NODE_NAME     U26 BJ28
 '@T6G_MB_LIB.T6G(SCH_1):PAGE58_I3@PURE_QUANTA.GENOA_SP5(CHIPS)':
 'VSS_BJ28': CDS_PINID='VSS_BJ28';
NODE_NAME     U26 BJ49
 '@T6G_MB_LIB.T6G(SCH_1):PAGE58_I3@PURE_QUANTA.GENOA_SP5(CHIPS)':
 'VSS_BJ49': CDS_PINID='VSS_BJ49';
NODE_NAME     U26 BJ51
 '@T6G_MB_LIB.T6G(SCH_1):PAGE58_I3@PURE_QUANTA.GENOA_SP5(CHIPS)':
 'VSS_BJ51': CDS_PINID='VSS_BJ51';
NODE_NAME     U26 BJ53
 '@T6G_MB_LIB.T6G(SCH_1):PAGE58_I3@PURE_QUANTA.GENOA_SP5(CHIPS)':
 'VSS_BJ53': CDS_PINID='VSS_BJ53';
NODE_NAME     U26 BJ56
 '@T6G_MB_LIB.T6G(SCH_1):PAGE58_I3@PURE_QUANTA.GENOA_SP5(CHIPS)':
 'VSS_BJ56': CDS_PINID='VSS_BJ56';
NODE_NAME     U26 BJ61
 '@T6G_MB_LIB.T6G(SCH_1):PAGE58_I3@PURE_QUANTA.GENOA_SP5(CHIPS)':
 'VSS_BJ61': CDS_PINID='VSS_BJ61';
NODE_NAME     U26 BJ63
 '@T6G_MB_LIB.T6G(SCH_1):PAGE58_I3@PURE_QUANTA.GENOA_SP5(CHIPS)':
 'VSS_BJ63': CDS_PINID='VSS_BJ63';
NODE_NAME     U26 BJ68
 '@T6G_MB_LIB.T6G(SCH_1):PAGE58_I3@PURE_QUANTA.GENOA_SP5(CHIPS)':
 'VSS_BJ68': CDS_PINID='VSS_BJ68';
NODE_NAME     U26 BJ70
 '@T6G_MB_LIB.T6G(SCH_1):PAGE58_I3@PURE_QUANTA.GENOA_SP5(CHIPS)':
 'VSS_BJ70': CDS_PINID='VSS_BJ70';
NODE_NAME     U26 BJ75
 '@T6G_MB_LIB.T6G(SCH_1):PAGE58_I3@PURE_QUANTA.GENOA_SP5(CHIPS)':
 'VSS_BJ75': CDS_PINID='VSS_BJ75';
NODE_NAME     U26 BK3
 '@T6G_MB_LIB.T6G(SCH_1):PAGE58_I3@PURE_QUANTA.GENOA_SP5(CHIPS)':
 'VSS_BK3': CDS_PINID='VSS_BK3';
NODE_NAME     U26 BK5
 '@T6G_MB_LIB.T6G(SCH_1):PAGE58_I3@PURE_QUANTA.GENOA_SP5(CHIPS)':
 'VSS_BK5': CDS_PINID='VSS_BK5';
NODE_NAME     U26 BK8
 '@T6G_MB_LIB.T6G(SCH_1):PAGE58_I3@PURE_QUANTA.GENOA_SP5(CHIPS)':
 'VSS_BK8': CDS_PINID='VSS_BK8';
NODE_NAME     U26 BK10
 '@T6G_MB_LIB.T6G(SCH_1):PAGE58_I3@PURE_QUANTA.GENOA_SP5(CHIPS)':
 'VSS_BK10': CDS_PINID='VSS_BK10';
NODE_NAME     U26 BK12
 '@T6G_MB_LIB.T6G(SCH_1):PAGE58_I3@PURE_QUANTA.GENOA_SP5(CHIPS)':
 'VSS_BK12': CDS_PINID='VSS_BK12';
NODE_NAME     U26 BK15
 '@T6G_MB_LIB.T6G(SCH_1):PAGE58_I3@PURE_QUANTA.GENOA_SP5(CHIPS)':
 'VSS_BK15': CDS_PINID='VSS_BK15';
NODE_NAME     U26 BK17
 '@T6G_MB_LIB.T6G(SCH_1):PAGE58_I3@PURE_QUANTA.GENOA_SP5(CHIPS)':
 'VSS_BK17': CDS_PINID='VSS_BK17';
NODE_NAME     U26 BK19
 '@T6G_MB_LIB.T6G(SCH_1):PAGE58_I3@PURE_QUANTA.GENOA_SP5(CHIPS)':
 'VSS_BK19': CDS_PINID='VSS_BK19';
NODE_NAME     U26 BK23
 '@T6G_MB_LIB.T6G(SCH_1):PAGE58_I3@PURE_QUANTA.GENOA_SP5(CHIPS)':
 'VSS_BK23': CDS_PINID='VSS_BK23';
NODE_NAME     U26 BK25
 '@T6G_MB_LIB.T6G(SCH_1):PAGE58_I3@PURE_QUANTA.GENOA_SP5(CHIPS)':
 'VSS_BK25': CDS_PINID='VSS_BK25';
NODE_NAME     U26 BK27
 '@T6G_MB_LIB.T6G(SCH_1):PAGE58_I3@PURE_QUANTA.GENOA_SP5(CHIPS)':
 'VSS_BK27': CDS_PINID='VSS_BK27';
NODE_NAME     U26 BK48
 '@T6G_MB_LIB.T6G(SCH_1):PAGE58_I3@PURE_QUANTA.GENOA_SP5(CHIPS)':
 'VSS_BK48': CDS_PINID='VSS_BK48';
NODE_NAME     U26 BK50
 '@T6G_MB_LIB.T6G(SCH_1):PAGE58_I3@PURE_QUANTA.GENOA_SP5(CHIPS)':
 'VSS_BK50': CDS_PINID='VSS_BK50';
NODE_NAME     U26 BK52
 '@T6G_MB_LIB.T6G(SCH_1):PAGE58_I3@PURE_QUANTA.GENOA_SP5(CHIPS)':
 'VSS_BK52': CDS_PINID='VSS_BK52';
NODE_NAME     U26 BK54
 '@T6G_MB_LIB.T6G(SCH_1):PAGE58_I3@PURE_QUANTA.GENOA_SP5(CHIPS)':
 'VSS_BK54': CDS_PINID='VSS_BK54';
NODE_NAME     U26 BK57
 '@T6G_MB_LIB.T6G(SCH_1):PAGE58_I3@PURE_QUANTA.GENOA_SP5(CHIPS)':
 'VSS_BK57': CDS_PINID='VSS_BK57';
NODE_NAME     U26 BK59
 '@T6G_MB_LIB.T6G(SCH_1):PAGE58_I3@PURE_QUANTA.GENOA_SP5(CHIPS)':
 'VSS_BK59': CDS_PINID='VSS_BK59';
NODE_NAME     U26 BK61
 '@T6G_MB_LIB.T6G(SCH_1):PAGE58_I3@PURE_QUANTA.GENOA_SP5(CHIPS)':
 'VSS_BK61': CDS_PINID='VSS_BK61';
NODE_NAME     U26 BK64
 '@T6G_MB_LIB.T6G(SCH_1):PAGE58_I3@PURE_QUANTA.GENOA_SP5(CHIPS)':
 'VSS_BK64': CDS_PINID='VSS_BK64';
NODE_NAME     U26 BK66
 '@T6G_MB_LIB.T6G(SCH_1):PAGE58_I3@PURE_QUANTA.GENOA_SP5(CHIPS)':
 'VSS_BK66': CDS_PINID='VSS_BK66';
NODE_NAME     U26 BK68
 '@T6G_MB_LIB.T6G(SCH_1):PAGE58_I3@PURE_QUANTA.GENOA_SP5(CHIPS)':
 'VSS_BK68': CDS_PINID='VSS_BK68';
NODE_NAME     U26 BK71
 '@T6G_MB_LIB.T6G(SCH_1):PAGE58_I3@PURE_QUANTA.GENOA_SP5(CHIPS)':
 'VSS_BK71': CDS_PINID='VSS_BK71';
NODE_NAME     U26 BK73
 '@T6G_MB_LIB.T6G(SCH_1):PAGE58_I3@PURE_QUANTA.GENOA_SP5(CHIPS)':
 'VSS_BK73': CDS_PINID='VSS_BK73';
NODE_NAME     U26 BL1
 '@T6G_MB_LIB.T6G(SCH_1):PAGE58_I3@PURE_QUANTA.GENOA_SP5(CHIPS)':
 'VSS_BL1': CDS_PINID='VSS_BL1';
NODE_NAME     U26 BL4
 '@T6G_MB_LIB.T6G(SCH_1):PAGE58_I3@PURE_QUANTA.GENOA_SP5(CHIPS)':
 'VSS_BL4': CDS_PINID='VSS_BL4';
NODE_NAME     U26 BL6
 '@T6G_MB_LIB.T6G(SCH_1):PAGE58_I3@PURE_QUANTA.GENOA_SP5(CHIPS)':
 'VSS_BL6': CDS_PINID='VSS_BL6';
NODE_NAME     U26 BL8
 '@T6G_MB_LIB.T6G(SCH_1):PAGE58_I3@PURE_QUANTA.GENOA_SP5(CHIPS)':
 'VSS_BL8': CDS_PINID='VSS_BL8';
NODE_NAME     U26 BL11
 '@T6G_MB_LIB.T6G(SCH_1):PAGE58_I3@PURE_QUANTA.GENOA_SP5(CHIPS)':
 'VSS_BL11': CDS_PINID='VSS_BL11';
NODE_NAME     U26 BL13
 '@T6G_MB_LIB.T6G(SCH_1):PAGE58_I3@PURE_QUANTA.GENOA_SP5(CHIPS)':
 'VSS_BL13': CDS_PINID='VSS_BL13';
NODE_NAME     U26 BL15
 '@T6G_MB_LIB.T6G(SCH_1):PAGE58_I3@PURE_QUANTA.GENOA_SP5(CHIPS)':
 'VSS_BL15': CDS_PINID='VSS_BL15';
NODE_NAME     U26 BL18
 '@T6G_MB_LIB.T6G(SCH_1):PAGE58_I3@PURE_QUANTA.GENOA_SP5(CHIPS)':
 'VSS_BL18': CDS_PINID='VSS_BL18';
NODE_NAME     U26 BL20
 '@T6G_MB_LIB.T6G(SCH_1):PAGE58_I3@PURE_QUANTA.GENOA_SP5(CHIPS)':
 'VSS_BL20': CDS_PINID='VSS_BL20';
NODE_NAME     U26 BL22
 '@T6G_MB_LIB.T6G(SCH_1):PAGE58_I3@PURE_QUANTA.GENOA_SP5(CHIPS)':
 'VSS_BL22': CDS_PINID='VSS_BL22';
NODE_NAME     U26 BL24
 '@T6G_MB_LIB.T6G(SCH_1):PAGE58_I3@PURE_QUANTA.GENOA_SP5(CHIPS)':
 'VSS_BL24': CDS_PINID='VSS_BL24';
NODE_NAME     U26 AM42
 '@T6G_MB_LIB.T6G(SCH_1):PAGE58_I6@PURE_QUANTA.GENOA_SP5(CHIPS)':
 'VSS_AM42': CDS_PINID='VSS_AM42';
NODE_NAME     U26 AM43
 '@T6G_MB_LIB.T6G(SCH_1):PAGE58_I6@PURE_QUANTA.GENOA_SP5(CHIPS)':
 'VSS_AM43': CDS_PINID='VSS_AM43';
NODE_NAME     U26 AM44
 '@T6G_MB_LIB.T6G(SCH_1):PAGE58_I6@PURE_QUANTA.GENOA_SP5(CHIPS)':
 'VSS_AM44': CDS_PINID='VSS_AM44';
NODE_NAME     U26 AM45
 '@T6G_MB_LIB.T6G(SCH_1):PAGE58_I6@PURE_QUANTA.GENOA_SP5(CHIPS)':
 'VSS_AM45': CDS_PINID='VSS_AM45';
NODE_NAME     U26 AM46
 '@T6G_MB_LIB.T6G(SCH_1):PAGE58_I6@PURE_QUANTA.GENOA_SP5(CHIPS)':
 'VSS_AM46': CDS_PINID='VSS_AM46';
NODE_NAME     U26 AM47
 '@T6G_MB_LIB.T6G(SCH_1):PAGE58_I6@PURE_QUANTA.GENOA_SP5(CHIPS)':
 'VSS_AM47': CDS_PINID='VSS_AM47';
NODE_NAME     U26 AM48
 '@T6G_MB_LIB.T6G(SCH_1):PAGE58_I6@PURE_QUANTA.GENOA_SP5(CHIPS)':
 'VSS_AM48': CDS_PINID='VSS_AM48';
NODE_NAME     U26 AM49
 '@T6G_MB_LIB.T6G(SCH_1):PAGE58_I6@PURE_QUANTA.GENOA_SP5(CHIPS)':
 'VSS_AM49': CDS_PINID='VSS_AM49';
NODE_NAME     U26 AM50
 '@T6G_MB_LIB.T6G(SCH_1):PAGE58_I6@PURE_QUANTA.GENOA_SP5(CHIPS)':
 'VSS_AM50': CDS_PINID='VSS_AM50';
NODE_NAME     U26 AM51
 '@T6G_MB_LIB.T6G(SCH_1):PAGE58_I6@PURE_QUANTA.GENOA_SP5(CHIPS)':
 'VSS_AM51': CDS_PINID='VSS_AM51';
NODE_NAME     U26 AM52
 '@T6G_MB_LIB.T6G(SCH_1):PAGE58_I6@PURE_QUANTA.GENOA_SP5(CHIPS)':
 'VSS_AM52': CDS_PINID='VSS_AM52';
NODE_NAME     U26 AM53
 '@T6G_MB_LIB.T6G(SCH_1):PAGE58_I6@PURE_QUANTA.GENOA_SP5(CHIPS)':
 'VSS_AM53': CDS_PINID='VSS_AM53';
NODE_NAME     U26 AM59
 '@T6G_MB_LIB.T6G(SCH_1):PAGE58_I6@PURE_QUANTA.GENOA_SP5(CHIPS)':
 'VSS_AM59': CDS_PINID='VSS_AM59';
NODE_NAME     U26 AM61
 '@T6G_MB_LIB.T6G(SCH_1):PAGE58_I6@PURE_QUANTA.GENOA_SP5(CHIPS)':
 'VSS_AM61': CDS_PINID='VSS_AM61';
NODE_NAME     U26 AM66
 '@T6G_MB_LIB.T6G(SCH_1):PAGE58_I6@PURE_QUANTA.GENOA_SP5(CHIPS)':
 'VSS_AM66': CDS_PINID='VSS_AM66';
NODE_NAME     U26 AM68
 '@T6G_MB_LIB.T6G(SCH_1):PAGE58_I6@PURE_QUANTA.GENOA_SP5(CHIPS)':
 'VSS_AM68': CDS_PINID='VSS_AM68';
NODE_NAME     U26 AM73
 '@T6G_MB_LIB.T6G(SCH_1):PAGE58_I6@PURE_QUANTA.GENOA_SP5(CHIPS)':
 'VSS_AM73': CDS_PINID='VSS_AM73';
NODE_NAME     U26 AN1
 '@T6G_MB_LIB.T6G(SCH_1):PAGE58_I6@PURE_QUANTA.GENOA_SP5(CHIPS)':
 'VSS_AN1': CDS_PINID='VSS_AN1';
NODE_NAME     U26 AN4
 '@T6G_MB_LIB.T6G(SCH_1):PAGE58_I6@PURE_QUANTA.GENOA_SP5(CHIPS)':
 'VSS_AN4': CDS_PINID='VSS_AN4';
NODE_NAME     U26 AN6
 '@T6G_MB_LIB.T6G(SCH_1):PAGE58_I6@PURE_QUANTA.GENOA_SP5(CHIPS)':
 'VSS_AN6': CDS_PINID='VSS_AN6';
NODE_NAME     U26 AN8
 '@T6G_MB_LIB.T6G(SCH_1):PAGE58_I6@PURE_QUANTA.GENOA_SP5(CHIPS)':
 'VSS_AN8': CDS_PINID='VSS_AN8';
NODE_NAME     U26 AN11
 '@T6G_MB_LIB.T6G(SCH_1):PAGE58_I6@PURE_QUANTA.GENOA_SP5(CHIPS)':
 'VSS_AN11': CDS_PINID='VSS_AN11';
NODE_NAME     U26 AN13
 '@T6G_MB_LIB.T6G(SCH_1):PAGE58_I6@PURE_QUANTA.GENOA_SP5(CHIPS)':
 'VSS_AN13': CDS_PINID='VSS_AN13';
NODE_NAME     U26 AN15
 '@T6G_MB_LIB.T6G(SCH_1):PAGE58_I6@PURE_QUANTA.GENOA_SP5(CHIPS)':
 'VSS_AN15': CDS_PINID='VSS_AN15';
NODE_NAME     U26 AN18
 '@T6G_MB_LIB.T6G(SCH_1):PAGE58_I6@PURE_QUANTA.GENOA_SP5(CHIPS)':
 'VSS_AN18': CDS_PINID='VSS_AN18';
NODE_NAME     U26 AN22
 '@T6G_MB_LIB.T6G(SCH_1):PAGE58_I6@PURE_QUANTA.GENOA_SP5(CHIPS)':
 'VSS_AN22': CDS_PINID='VSS_AN22';
NODE_NAME     U26 AN25
 '@T6G_MB_LIB.T6G(SCH_1):PAGE58_I6@PURE_QUANTA.GENOA_SP5(CHIPS)':
 'VSS_AN25': CDS_PINID='VSS_AN25';
NODE_NAME     U26 AN28
 '@T6G_MB_LIB.T6G(SCH_1):PAGE58_I6@PURE_QUANTA.GENOA_SP5(CHIPS)':
 'VSS_AN28': CDS_PINID='VSS_AN28';
NODE_NAME     U26 AN31
 '@T6G_MB_LIB.T6G(SCH_1):PAGE58_I6@PURE_QUANTA.GENOA_SP5(CHIPS)':
 'VSS_AN31': CDS_PINID='VSS_AN31';
NODE_NAME     U26 AN34
 '@T6G_MB_LIB.T6G(SCH_1):PAGE58_I6@PURE_QUANTA.GENOA_SP5(CHIPS)':
 'VSS_AN34': CDS_PINID='VSS_AN34';
NODE_NAME     U26 AN35
 '@T6G_MB_LIB.T6G(SCH_1):PAGE58_I6@PURE_QUANTA.GENOA_SP5(CHIPS)':
 'VSS_AN35': CDS_PINID='VSS_AN35';
NODE_NAME     U26 AN36
 '@T6G_MB_LIB.T6G(SCH_1):PAGE58_I6@PURE_QUANTA.GENOA_SP5(CHIPS)':
 'VSS_AN36': CDS_PINID='VSS_AN36';
NODE_NAME     U26 AN40
 '@T6G_MB_LIB.T6G(SCH_1):PAGE58_I6@PURE_QUANTA.GENOA_SP5(CHIPS)':
 'VSS_AN40': CDS_PINID='VSS_AN40';
NODE_NAME     U26 AN41
 '@T6G_MB_LIB.T6G(SCH_1):PAGE58_I6@PURE_QUANTA.GENOA_SP5(CHIPS)':
 'VSS_AN41': CDS_PINID='VSS_AN41';
NODE_NAME     U26 AN42
 '@T6G_MB_LIB.T6G(SCH_1):PAGE58_I6@PURE_QUANTA.GENOA_SP5(CHIPS)':
 'VSS_AN42': CDS_PINID='VSS_AN42';
NODE_NAME     U26 AN45
 '@T6G_MB_LIB.T6G(SCH_1):PAGE58_I6@PURE_QUANTA.GENOA_SP5(CHIPS)':
 'VSS_AN45': CDS_PINID='VSS_AN45';
NODE_NAME     U26 AN48
 '@T6G_MB_LIB.T6G(SCH_1):PAGE58_I6@PURE_QUANTA.GENOA_SP5(CHIPS)':
 'VSS_AN48': CDS_PINID='VSS_AN48';
NODE_NAME     U26 AN51
 '@T6G_MB_LIB.T6G(SCH_1):PAGE58_I6@PURE_QUANTA.GENOA_SP5(CHIPS)':
 'VSS_AN51': CDS_PINID='VSS_AN51';
NODE_NAME     U26 AN54
 '@T6G_MB_LIB.T6G(SCH_1):PAGE58_I6@PURE_QUANTA.GENOA_SP5(CHIPS)':
 'VSS_AN54': CDS_PINID='VSS_AN54';
NODE_NAME     U26 AN56
 '@T6G_MB_LIB.T6G(SCH_1):PAGE58_I6@PURE_QUANTA.GENOA_SP5(CHIPS)':
 'VSS_AN56': CDS_PINID='VSS_AN56';
NODE_NAME     U26 AN58
 '@T6G_MB_LIB.T6G(SCH_1):PAGE58_I6@PURE_QUANTA.GENOA_SP5(CHIPS)':
 'VSS_AN58': CDS_PINID='VSS_AN58';
NODE_NAME     U26 AN61
 '@T6G_MB_LIB.T6G(SCH_1):PAGE58_I6@PURE_QUANTA.GENOA_SP5(CHIPS)':
 'VSS_AN61': CDS_PINID='VSS_AN61';
NODE_NAME     U26 AN63
 '@T6G_MB_LIB.T6G(SCH_1):PAGE58_I6@PURE_QUANTA.GENOA_SP5(CHIPS)':
 'VSS_AN63': CDS_PINID='VSS_AN63';
NODE_NAME     U26 AN65
 '@T6G_MB_LIB.T6G(SCH_1):PAGE58_I6@PURE_QUANTA.GENOA_SP5(CHIPS)':
 'VSS_AN65': CDS_PINID='VSS_AN65';
NODE_NAME     U26 AN68
 '@T6G_MB_LIB.T6G(SCH_1):PAGE58_I6@PURE_QUANTA.GENOA_SP5(CHIPS)':
 'VSS_AN68': CDS_PINID='VSS_AN68';
NODE_NAME     U26 AN70
 '@T6G_MB_LIB.T6G(SCH_1):PAGE58_I6@PURE_QUANTA.GENOA_SP5(CHIPS)':
 'VSS_AN70': CDS_PINID='VSS_AN70';
NODE_NAME     U26 AN72
 '@T6G_MB_LIB.T6G(SCH_1):PAGE58_I6@PURE_QUANTA.GENOA_SP5(CHIPS)':
 'VSS_AN72': CDS_PINID='VSS_AN72';
NODE_NAME     U26 AN75
 '@T6G_MB_LIB.T6G(SCH_1):PAGE58_I6@PURE_QUANTA.GENOA_SP5(CHIPS)':
 'VSS_AN75': CDS_PINID='VSS_AN75';
NODE_NAME     U26 AP3
 '@T6G_MB_LIB.T6G(SCH_1):PAGE58_I6@PURE_QUANTA.GENOA_SP5(CHIPS)':
 'VSS_AP3': CDS_PINID='VSS_AP3';
NODE_NAME     U26 AP5
 '@T6G_MB_LIB.T6G(SCH_1):PAGE58_I6@PURE_QUANTA.GENOA_SP5(CHIPS)':
 'VSS_AP5': CDS_PINID='VSS_AP5';
NODE_NAME     U26 AP8
 '@T6G_MB_LIB.T6G(SCH_1):PAGE58_I6@PURE_QUANTA.GENOA_SP5(CHIPS)':
 'VSS_AP8': CDS_PINID='VSS_AP8';
NODE_NAME     U26 AP10
 '@T6G_MB_LIB.T6G(SCH_1):PAGE58_I6@PURE_QUANTA.GENOA_SP5(CHIPS)':
 'VSS_AP10': CDS_PINID='VSS_AP10';
NODE_NAME     U26 AP12
 '@T6G_MB_LIB.T6G(SCH_1):PAGE58_I6@PURE_QUANTA.GENOA_SP5(CHIPS)':
 'VSS_AP12': CDS_PINID='VSS_AP12';
NODE_NAME     U26 AP15
 '@T6G_MB_LIB.T6G(SCH_1):PAGE58_I6@PURE_QUANTA.GENOA_SP5(CHIPS)':
 'VSS_AP15': CDS_PINID='VSS_AP15';
NODE_NAME     U26 AP17
 '@T6G_MB_LIB.T6G(SCH_1):PAGE58_I6@PURE_QUANTA.GENOA_SP5(CHIPS)':
 'VSS_AP17': CDS_PINID='VSS_AP17';
NODE_NAME     U26 AP19
 '@T6G_MB_LIB.T6G(SCH_1):PAGE58_I6@PURE_QUANTA.GENOA_SP5(CHIPS)':
 'VSS_AP19': CDS_PINID='VSS_AP19';
NODE_NAME     U26 AP22
 '@T6G_MB_LIB.T6G(SCH_1):PAGE58_I6@PURE_QUANTA.GENOA_SP5(CHIPS)':
 'VSS_AP22': CDS_PINID='VSS_AP22';
NODE_NAME     U26 AP25
 '@T6G_MB_LIB.T6G(SCH_1):PAGE58_I6@PURE_QUANTA.GENOA_SP5(CHIPS)':
 'VSS_AP25': CDS_PINID='VSS_AP25';
NODE_NAME     U26 AP28
 '@T6G_MB_LIB.T6G(SCH_1):PAGE58_I6@PURE_QUANTA.GENOA_SP5(CHIPS)':
 'VSS_AP28': CDS_PINID='VSS_AP28';
NODE_NAME     U26 AP31
 '@T6G_MB_LIB.T6G(SCH_1):PAGE58_I6@PURE_QUANTA.GENOA_SP5(CHIPS)':
 'VSS_AP31': CDS_PINID='VSS_AP31';
NODE_NAME     U26 AP34
 '@T6G_MB_LIB.T6G(SCH_1):PAGE58_I6@PURE_QUANTA.GENOA_SP5(CHIPS)':
 'VSS_AP34': CDS_PINID='VSS_AP34';
NODE_NAME     U26 AP37
 '@T6G_MB_LIB.T6G(SCH_1):PAGE58_I6@PURE_QUANTA.GENOA_SP5(CHIPS)':
 'VSS_AP37': CDS_PINID='VSS_AP37';
NODE_NAME     U26 AP39
 '@T6G_MB_LIB.T6G(SCH_1):PAGE58_I6@PURE_QUANTA.GENOA_SP5(CHIPS)':
 'VSS_AP39': CDS_PINID='VSS_AP39';
NODE_NAME     U26 AP42
 '@T6G_MB_LIB.T6G(SCH_1):PAGE58_I6@PURE_QUANTA.GENOA_SP5(CHIPS)':
 'VSS_AP42': CDS_PINID='VSS_AP42';
NODE_NAME     U26 AP45
 '@T6G_MB_LIB.T6G(SCH_1):PAGE58_I6@PURE_QUANTA.GENOA_SP5(CHIPS)':
 'VSS_AP45': CDS_PINID='VSS_AP45';
NODE_NAME     U26 AP48
 '@T6G_MB_LIB.T6G(SCH_1):PAGE58_I6@PURE_QUANTA.GENOA_SP5(CHIPS)':
 'VSS_AP48': CDS_PINID='VSS_AP48';
NODE_NAME     U26 AP51
 '@T6G_MB_LIB.T6G(SCH_1):PAGE58_I6@PURE_QUANTA.GENOA_SP5(CHIPS)':
 'VSS_AP51': CDS_PINID='VSS_AP51';
NODE_NAME     U26 AP54
 '@T6G_MB_LIB.T6G(SCH_1):PAGE58_I6@PURE_QUANTA.GENOA_SP5(CHIPS)':
 'VSS_AP54': CDS_PINID='VSS_AP54';
NODE_NAME     U26 AP57
 '@T6G_MB_LIB.T6G(SCH_1):PAGE58_I6@PURE_QUANTA.GENOA_SP5(CHIPS)':
 'VSS_AP57': CDS_PINID='VSS_AP57';
NODE_NAME     U26 AP59
 '@T6G_MB_LIB.T6G(SCH_1):PAGE58_I6@PURE_QUANTA.GENOA_SP5(CHIPS)':
 'VSS_AP59': CDS_PINID='VSS_AP59';
NODE_NAME     U26 AP61
 '@T6G_MB_LIB.T6G(SCH_1):PAGE58_I6@PURE_QUANTA.GENOA_SP5(CHIPS)':
 'VSS_AP61': CDS_PINID='VSS_AP61';
NODE_NAME     U26 AP64
 '@T6G_MB_LIB.T6G(SCH_1):PAGE58_I6@PURE_QUANTA.GENOA_SP5(CHIPS)':
 'VSS_AP64': CDS_PINID='VSS_AP64';
NODE_NAME     U26 AP66
 '@T6G_MB_LIB.T6G(SCH_1):PAGE58_I6@PURE_QUANTA.GENOA_SP5(CHIPS)':
 'VSS_AP66': CDS_PINID='VSS_AP66';
NODE_NAME     U26 AP68
 '@T6G_MB_LIB.T6G(SCH_1):PAGE58_I6@PURE_QUANTA.GENOA_SP5(CHIPS)':
 'VSS_AP68': CDS_PINID='VSS_AP68';
NODE_NAME     U26 AP71
 '@T6G_MB_LIB.T6G(SCH_1):PAGE58_I6@PURE_QUANTA.GENOA_SP5(CHIPS)':
 'VSS_AP71': CDS_PINID='VSS_AP71';
NODE_NAME     U26 AP73
 '@T6G_MB_LIB.T6G(SCH_1):PAGE58_I6@PURE_QUANTA.GENOA_SP5(CHIPS)':
 'VSS_AP73': CDS_PINID='VSS_AP73';
NODE_NAME     U26 AR1
 '@T6G_MB_LIB.T6G(SCH_1):PAGE58_I6@PURE_QUANTA.GENOA_SP5(CHIPS)':
 'VSS_AR1': CDS_PINID='VSS_AR1';
NODE_NAME     U26 AR5
 '@T6G_MB_LIB.T6G(SCH_1):PAGE58_I6@PURE_QUANTA.GENOA_SP5(CHIPS)':
 'VSS_AR5': CDS_PINID='VSS_AR5';
NODE_NAME     U26 AR6
 '@T6G_MB_LIB.T6G(SCH_1):PAGE58_I6@PURE_QUANTA.GENOA_SP5(CHIPS)':
 'VSS_AR6': CDS_PINID='VSS_AR6';
NODE_NAME     U26 AR8
 '@T6G_MB_LIB.T6G(SCH_1):PAGE58_I6@PURE_QUANTA.GENOA_SP5(CHIPS)':
 'VSS_AR8': CDS_PINID='VSS_AR8';
NODE_NAME     U26 AR9
 '@T6G_MB_LIB.T6G(SCH_1):PAGE58_I6@PURE_QUANTA.GENOA_SP5(CHIPS)':
 'VSS_AR9': CDS_PINID='VSS_AR9';
NODE_NAME     U26 AR12
 '@T6G_MB_LIB.T6G(SCH_1):PAGE58_I6@PURE_QUANTA.GENOA_SP5(CHIPS)':
 'VSS_AR12': CDS_PINID='VSS_AR12';
NODE_NAME     U26 AR13
 '@T6G_MB_LIB.T6G(SCH_1):PAGE58_I6@PURE_QUANTA.GENOA_SP5(CHIPS)':
 'VSS_AR13': CDS_PINID='VSS_AR13';
NODE_NAME     U26 AR15
 '@T6G_MB_LIB.T6G(SCH_1):PAGE58_I6@PURE_QUANTA.GENOA_SP5(CHIPS)':
 'VSS_AR15': CDS_PINID='VSS_AR15';
NODE_NAME     U26 AR16
 '@T6G_MB_LIB.T6G(SCH_1):PAGE58_I6@PURE_QUANTA.GENOA_SP5(CHIPS)':
 'VSS_AR16': CDS_PINID='VSS_AR16';
NODE_NAME     U26 AR19
 '@T6G_MB_LIB.T6G(SCH_1):PAGE58_I6@PURE_QUANTA.GENOA_SP5(CHIPS)':
 'VSS_AR19': CDS_PINID='VSS_AR19';
NODE_NAME     U26 AR20
 '@T6G_MB_LIB.T6G(SCH_1):PAGE58_I6@PURE_QUANTA.GENOA_SP5(CHIPS)':
 'VSS_AR20': CDS_PINID='VSS_AR20';
NODE_NAME     U26 AR22
 '@T6G_MB_LIB.T6G(SCH_1):PAGE58_I6@PURE_QUANTA.GENOA_SP5(CHIPS)':
 'VSS_AR22': CDS_PINID='VSS_AR22';
NODE_NAME     U26 AR24
 '@T6G_MB_LIB.T6G(SCH_1):PAGE58_I6@PURE_QUANTA.GENOA_SP5(CHIPS)':
 'VSS_AR24': CDS_PINID='VSS_AR24';
NODE_NAME     U26 AR26
 '@T6G_MB_LIB.T6G(SCH_1):PAGE58_I6@PURE_QUANTA.GENOA_SP5(CHIPS)':
 'VSS_AR26': CDS_PINID='VSS_AR26';
NODE_NAME     U26 AR28
 '@T6G_MB_LIB.T6G(SCH_1):PAGE58_I6@PURE_QUANTA.GENOA_SP5(CHIPS)':
 'VSS_AR28': CDS_PINID='VSS_AR28';
NODE_NAME     U26 AR30
 '@T6G_MB_LIB.T6G(SCH_1):PAGE58_I6@PURE_QUANTA.GENOA_SP5(CHIPS)':
 'VSS_AR30': CDS_PINID='VSS_AR30';
NODE_NAME     U26 AR32
 '@T6G_MB_LIB.T6G(SCH_1):PAGE58_I6@PURE_QUANTA.GENOA_SP5(CHIPS)':
 'VSS_AR32': CDS_PINID='VSS_AR32';
NODE_NAME     U26 AR34
 '@T6G_MB_LIB.T6G(SCH_1):PAGE58_I6@PURE_QUANTA.GENOA_SP5(CHIPS)':
 'VSS_AR34': CDS_PINID='VSS_AR34';
NODE_NAME     U26 AR36
 '@T6G_MB_LIB.T6G(SCH_1):PAGE58_I6@PURE_QUANTA.GENOA_SP5(CHIPS)':
 'VSS_AR36': CDS_PINID='VSS_AR36';
NODE_NAME     U26 AR41
 '@T6G_MB_LIB.T6G(SCH_1):PAGE58_I6@PURE_QUANTA.GENOA_SP5(CHIPS)':
 'VSS_AR41': CDS_PINID='VSS_AR41';
NODE_NAME     U26 AR43
 '@T6G_MB_LIB.T6G(SCH_1):PAGE58_I6@PURE_QUANTA.GENOA_SP5(CHIPS)':
 'VSS_AR43': CDS_PINID='VSS_AR43';
NODE_NAME     U26 AR45
 '@T6G_MB_LIB.T6G(SCH_1):PAGE58_I6@PURE_QUANTA.GENOA_SP5(CHIPS)':
 'VSS_AR45': CDS_PINID='VSS_AR45';
NODE_NAME     U26 AR47
 '@T6G_MB_LIB.T6G(SCH_1):PAGE58_I6@PURE_QUANTA.GENOA_SP5(CHIPS)':
 'VSS_AR47': CDS_PINID='VSS_AR47';
NODE_NAME     U26 AR49
 '@T6G_MB_LIB.T6G(SCH_1):PAGE58_I6@PURE_QUANTA.GENOA_SP5(CHIPS)':
 'VSS_AR49': CDS_PINID='VSS_AR49';
NODE_NAME     U26 AR51
 '@T6G_MB_LIB.T6G(SCH_1):PAGE58_I6@PURE_QUANTA.GENOA_SP5(CHIPS)':
 'VSS_AR51': CDS_PINID='VSS_AR51';
NODE_NAME     U26 AR53
 '@T6G_MB_LIB.T6G(SCH_1):PAGE58_I6@PURE_QUANTA.GENOA_SP5(CHIPS)':
 'VSS_AR53': CDS_PINID='VSS_AR53';
NODE_NAME     U26 AR56
 '@T6G_MB_LIB.T6G(SCH_1):PAGE58_I6@PURE_QUANTA.GENOA_SP5(CHIPS)':
 'VSS_AR56': CDS_PINID='VSS_AR56';
NODE_NAME     U26 AR57
 '@T6G_MB_LIB.T6G(SCH_1):PAGE58_I6@PURE_QUANTA.GENOA_SP5(CHIPS)':
 'VSS_AR57': CDS_PINID='VSS_AR57';
NODE_NAME     U26 AR60
 '@T6G_MB_LIB.T6G(SCH_1):PAGE58_I6@PURE_QUANTA.GENOA_SP5(CHIPS)':
 'VSS_AR60': CDS_PINID='VSS_AR60';
NODE_NAME     U26 AR61
 '@T6G_MB_LIB.T6G(SCH_1):PAGE58_I6@PURE_QUANTA.GENOA_SP5(CHIPS)':
 'VSS_AR61': CDS_PINID='VSS_AR61';
NODE_NAME     U26 AR63
 '@T6G_MB_LIB.T6G(SCH_1):PAGE58_I6@PURE_QUANTA.GENOA_SP5(CHIPS)':
 'VSS_AR63': CDS_PINID='VSS_AR63';
NODE_NAME     U26 AR64
 '@T6G_MB_LIB.T6G(SCH_1):PAGE58_I6@PURE_QUANTA.GENOA_SP5(CHIPS)':
 'VSS_AR64': CDS_PINID='VSS_AR64';
NODE_NAME     U26 AR67
 '@T6G_MB_LIB.T6G(SCH_1):PAGE58_I6@PURE_QUANTA.GENOA_SP5(CHIPS)':
 'VSS_AR67': CDS_PINID='VSS_AR67';
NODE_NAME     U26 AR68
 '@T6G_MB_LIB.T6G(SCH_1):PAGE58_I6@PURE_QUANTA.GENOA_SP5(CHIPS)':
 'VSS_AR68': CDS_PINID='VSS_AR68';
NODE_NAME     U26 AR70
 '@T6G_MB_LIB.T6G(SCH_1):PAGE58_I6@PURE_QUANTA.GENOA_SP5(CHIPS)':
 'VSS_AR70': CDS_PINID='VSS_AR70';
NODE_NAME     U26 AR71
 '@T6G_MB_LIB.T6G(SCH_1):PAGE58_I6@PURE_QUANTA.GENOA_SP5(CHIPS)':
 'VSS_AR71': CDS_PINID='VSS_AR71';
NODE_NAME     U26 AR75
 '@T6G_MB_LIB.T6G(SCH_1):PAGE58_I6@PURE_QUANTA.GENOA_SP5(CHIPS)':
 'VSS_AR75': CDS_PINID='VSS_AR75';
NODE_NAME     U26 AT3
 '@T6G_MB_LIB.T6G(SCH_1):PAGE58_I6@PURE_QUANTA.GENOA_SP5(CHIPS)':
 'VSS_AT3': CDS_PINID='VSS_AT3';
NODE_NAME     U26 AT4
 '@T6G_MB_LIB.T6G(SCH_1):PAGE58_I6@PURE_QUANTA.GENOA_SP5(CHIPS)':
 'VSS_AT4': CDS_PINID='VSS_AT4';
NODE_NAME     U26 AT5
 '@T6G_MB_LIB.T6G(SCH_1):PAGE58_I6@PURE_QUANTA.GENOA_SP5(CHIPS)':
 'VSS_AT5': CDS_PINID='VSS_AT5';
NODE_NAME     U26 AT6
 '@T6G_MB_LIB.T6G(SCH_1):PAGE58_I6@PURE_QUANTA.GENOA_SP5(CHIPS)':
 'VSS_AT6': CDS_PINID='VSS_AT6';
NODE_NAME     U26 AT8
 '@T6G_MB_LIB.T6G(SCH_1):PAGE58_I6@PURE_QUANTA.GENOA_SP5(CHIPS)':
 'VSS_AT8': CDS_PINID='VSS_AT8';
NODE_NAME     U26 AT9
 '@T6G_MB_LIB.T6G(SCH_1):PAGE58_I6@PURE_QUANTA.GENOA_SP5(CHIPS)':
 'VSS_AT9': CDS_PINID='VSS_AT9';
NODE_NAME     U26 AT10
 '@T6G_MB_LIB.T6G(SCH_1):PAGE58_I6@PURE_QUANTA.GENOA_SP5(CHIPS)':
 'VSS_AT10': CDS_PINID='VSS_AT10';
NODE_NAME     U26 AT12
 '@T6G_MB_LIB.T6G(SCH_1):PAGE58_I6@PURE_QUANTA.GENOA_SP5(CHIPS)':
 'VSS_AT12': CDS_PINID='VSS_AT12';
NODE_NAME     U26 AT13
 '@T6G_MB_LIB.T6G(SCH_1):PAGE58_I6@PURE_QUANTA.GENOA_SP5(CHIPS)':
 'VSS_AT13': CDS_PINID='VSS_AT13';
NODE_NAME     U26 AT15
 '@T6G_MB_LIB.T6G(SCH_1):PAGE58_I6@PURE_QUANTA.GENOA_SP5(CHIPS)':
 'VSS_AT15': CDS_PINID='VSS_AT15';
NODE_NAME     U26 AT16
 '@T6G_MB_LIB.T6G(SCH_1):PAGE58_I6@PURE_QUANTA.GENOA_SP5(CHIPS)':
 'VSS_AT16': CDS_PINID='VSS_AT16';
NODE_NAME     U26 AT17
 '@T6G_MB_LIB.T6G(SCH_1):PAGE58_I6@PURE_QUANTA.GENOA_SP5(CHIPS)':
 'VSS_AT17': CDS_PINID='VSS_AT17';
NODE_NAME     U26 AT19
 '@T6G_MB_LIB.T6G(SCH_1):PAGE58_I6@PURE_QUANTA.GENOA_SP5(CHIPS)':
 'VSS_AT19': CDS_PINID='VSS_AT19';
NODE_NAME     U26 AT20
 '@T6G_MB_LIB.T6G(SCH_1):PAGE58_I6@PURE_QUANTA.GENOA_SP5(CHIPS)':
 'VSS_AT20': CDS_PINID='VSS_AT20';
NODE_NAME     U26 AT23
 '@T6G_MB_LIB.T6G(SCH_1):PAGE58_I6@PURE_QUANTA.GENOA_SP5(CHIPS)':
 'VSS_AT23': CDS_PINID='VSS_AT23';
NODE_NAME     U26 AT25
 '@T6G_MB_LIB.T6G(SCH_1):PAGE58_I6@PURE_QUANTA.GENOA_SP5(CHIPS)':
 'VSS_AT25': CDS_PINID='VSS_AT25';
NODE_NAME     U26 AT27
 '@T6G_MB_LIB.T6G(SCH_1):PAGE58_I6@PURE_QUANTA.GENOA_SP5(CHIPS)':
 'VSS_AT27': CDS_PINID='VSS_AT27';
NODE_NAME     U26 AT29
 '@T6G_MB_LIB.T6G(SCH_1):PAGE58_I6@PURE_QUANTA.GENOA_SP5(CHIPS)':
 'VSS_AT29': CDS_PINID='VSS_AT29';
NODE_NAME     U26 AT31
 '@T6G_MB_LIB.T6G(SCH_1):PAGE58_I6@PURE_QUANTA.GENOA_SP5(CHIPS)':
 'VSS_AT31': CDS_PINID='VSS_AT31';
NODE_NAME     U26 AT33
 '@T6G_MB_LIB.T6G(SCH_1):PAGE58_I6@PURE_QUANTA.GENOA_SP5(CHIPS)':
 'VSS_AT33': CDS_PINID='VSS_AT33';
NODE_NAME     U26 AT35
 '@T6G_MB_LIB.T6G(SCH_1):PAGE58_I6@PURE_QUANTA.GENOA_SP5(CHIPS)':
 'VSS_AT35': CDS_PINID='VSS_AT35';
NODE_NAME     U26 AT37
 '@T6G_MB_LIB.T6G(SCH_1):PAGE58_I6@PURE_QUANTA.GENOA_SP5(CHIPS)':
 'VSS_AT37': CDS_PINID='VSS_AT37';
NODE_NAME     U26 AT40
 '@T6G_MB_LIB.T6G(SCH_1):PAGE58_I6@PURE_QUANTA.GENOA_SP5(CHIPS)':
 'VSS_AT40': CDS_PINID='VSS_AT40';
NODE_NAME     U26 AT42
 '@T6G_MB_LIB.T6G(SCH_1):PAGE58_I6@PURE_QUANTA.GENOA_SP5(CHIPS)':
 'VSS_AT42': CDS_PINID='VSS_AT42';
NODE_NAME     U26 AT44
 '@T6G_MB_LIB.T6G(SCH_1):PAGE58_I6@PURE_QUANTA.GENOA_SP5(CHIPS)':
 'VSS_AT44': CDS_PINID='VSS_AT44';
NODE_NAME     U26 AT46
 '@T6G_MB_LIB.T6G(SCH_1):PAGE58_I6@PURE_QUANTA.GENOA_SP5(CHIPS)':
 'VSS_AT46': CDS_PINID='VSS_AT46';
NODE_NAME     U26 AT48
 '@T6G_MB_LIB.T6G(SCH_1):PAGE58_I6@PURE_QUANTA.GENOA_SP5(CHIPS)':
 'VSS_AT48': CDS_PINID='VSS_AT48';
NODE_NAME     U26 AT50
 '@T6G_MB_LIB.T6G(SCH_1):PAGE58_I6@PURE_QUANTA.GENOA_SP5(CHIPS)':
 'VSS_AT50': CDS_PINID='VSS_AT50';
NODE_NAME     U26 AT52
 '@T6G_MB_LIB.T6G(SCH_1):PAGE58_I6@PURE_QUANTA.GENOA_SP5(CHIPS)':
 'VSS_AT52': CDS_PINID='VSS_AT52';
NODE_NAME     U26 AT54
 '@T6G_MB_LIB.T6G(SCH_1):PAGE58_I6@PURE_QUANTA.GENOA_SP5(CHIPS)':
 'VSS_AT54': CDS_PINID='VSS_AT54';
NODE_NAME     U26 AT56
 '@T6G_MB_LIB.T6G(SCH_1):PAGE58_I6@PURE_QUANTA.GENOA_SP5(CHIPS)':
 'VSS_AT56': CDS_PINID='VSS_AT56';
NODE_NAME     U26 AT57
 '@T6G_MB_LIB.T6G(SCH_1):PAGE58_I6@PURE_QUANTA.GENOA_SP5(CHIPS)':
 'VSS_AT57': CDS_PINID='VSS_AT57';
NODE_NAME     U26 AT59
 '@T6G_MB_LIB.T6G(SCH_1):PAGE58_I6@PURE_QUANTA.GENOA_SP5(CHIPS)':
 'VSS_AT59': CDS_PINID='VSS_AT59';
NODE_NAME     U26 AT60
 '@T6G_MB_LIB.T6G(SCH_1):PAGE58_I6@PURE_QUANTA.GENOA_SP5(CHIPS)':
 'VSS_AT60': CDS_PINID='VSS_AT60';
NODE_NAME     U26 AT61
 '@T6G_MB_LIB.T6G(SCH_1):PAGE58_I6@PURE_QUANTA.GENOA_SP5(CHIPS)':
 'VSS_AT61': CDS_PINID='VSS_AT61';
NODE_NAME     U26 AT63
 '@T6G_MB_LIB.T6G(SCH_1):PAGE58_I6@PURE_QUANTA.GENOA_SP5(CHIPS)':
 'VSS_AT63': CDS_PINID='VSS_AT63';
NODE_NAME     U26 AT64
 '@T6G_MB_LIB.T6G(SCH_1):PAGE58_I6@PURE_QUANTA.GENOA_SP5(CHIPS)':
 'VSS_AT64': CDS_PINID='VSS_AT64';
NODE_NAME     U26 AT66
 '@T6G_MB_LIB.T6G(SCH_1):PAGE58_I6@PURE_QUANTA.GENOA_SP5(CHIPS)':
 'VSS_AT66': CDS_PINID='VSS_AT66';
NODE_NAME     U26 AT67
 '@T6G_MB_LIB.T6G(SCH_1):PAGE58_I6@PURE_QUANTA.GENOA_SP5(CHIPS)':
 'VSS_AT67': CDS_PINID='VSS_AT67';
NODE_NAME     U26 AT68
 '@T6G_MB_LIB.T6G(SCH_1):PAGE58_I6@PURE_QUANTA.GENOA_SP5(CHIPS)':
 'VSS_AT68': CDS_PINID='VSS_AT68';
NODE_NAME     U26 AT70
 '@T6G_MB_LIB.T6G(SCH_1):PAGE58_I6@PURE_QUANTA.GENOA_SP5(CHIPS)':
 'VSS_AT70': CDS_PINID='VSS_AT70';
NODE_NAME     U26 AT71
 '@T6G_MB_LIB.T6G(SCH_1):PAGE58_I6@PURE_QUANTA.GENOA_SP5(CHIPS)':
 'VSS_AT71': CDS_PINID='VSS_AT71';
NODE_NAME     U26 AT72
 '@T6G_MB_LIB.T6G(SCH_1):PAGE58_I6@PURE_QUANTA.GENOA_SP5(CHIPS)':
 'VSS_AT72': CDS_PINID='VSS_AT72';
NODE_NAME     U26 AT73
 '@T6G_MB_LIB.T6G(SCH_1):PAGE58_I6@PURE_QUANTA.GENOA_SP5(CHIPS)':
 'VSS_AT73': CDS_PINID='VSS_AT73';
NODE_NAME     U26 AU1
 '@T6G_MB_LIB.T6G(SCH_1):PAGE58_I6@PURE_QUANTA.GENOA_SP5(CHIPS)':
 'VSS_AU1': CDS_PINID='VSS_AU1';
NODE_NAME     U26 AU3
 '@T6G_MB_LIB.T6G(SCH_1):PAGE58_I6@PURE_QUANTA.GENOA_SP5(CHIPS)':
 'VSS_AU3': CDS_PINID='VSS_AU3';
NODE_NAME     U26 AU4
 '@T6G_MB_LIB.T6G(SCH_1):PAGE58_I6@PURE_QUANTA.GENOA_SP5(CHIPS)':
 'VSS_AU4': CDS_PINID='VSS_AU4';
NODE_NAME     U26 AU6
 '@T6G_MB_LIB.T6G(SCH_1):PAGE58_I6@PURE_QUANTA.GENOA_SP5(CHIPS)':
 'VSS_AU6': CDS_PINID='VSS_AU6';
NODE_NAME     U26 AU8
 '@T6G_MB_LIB.T6G(SCH_1):PAGE58_I6@PURE_QUANTA.GENOA_SP5(CHIPS)':
 'VSS_AU8': CDS_PINID='VSS_AU8';
NODE_NAME     U26 AU11
 '@T6G_MB_LIB.T6G(SCH_1):PAGE58_I6@PURE_QUANTA.GENOA_SP5(CHIPS)':
 'VSS_AU11': CDS_PINID='VSS_AU11';
NODE_NAME     U26 AU13
 '@T6G_MB_LIB.T6G(SCH_1):PAGE58_I6@PURE_QUANTA.GENOA_SP5(CHIPS)':
 'VSS_AU13': CDS_PINID='VSS_AU13';
NODE_NAME     U26 AU15
 '@T6G_MB_LIB.T6G(SCH_1):PAGE58_I6@PURE_QUANTA.GENOA_SP5(CHIPS)':
 'VSS_AU15': CDS_PINID='VSS_AU15';
NODE_NAME     U26 AU18
 '@T6G_MB_LIB.T6G(SCH_1):PAGE58_I6@PURE_QUANTA.GENOA_SP5(CHIPS)':
 'VSS_AU18': CDS_PINID='VSS_AU18';
NODE_NAME     U26 AU20
 '@T6G_MB_LIB.T6G(SCH_1):PAGE58_I6@PURE_QUANTA.GENOA_SP5(CHIPS)':
 'VSS_AU20': CDS_PINID='VSS_AU20';
NODE_NAME     U26 AU22
 '@T6G_MB_LIB.T6G(SCH_1):PAGE58_I6@PURE_QUANTA.GENOA_SP5(CHIPS)':
 'VSS_AU22': CDS_PINID='VSS_AU22';
NODE_NAME     U26 AU24
 '@T6G_MB_LIB.T6G(SCH_1):PAGE58_I6@PURE_QUANTA.GENOA_SP5(CHIPS)':
 'VSS_AU24': CDS_PINID='VSS_AU24';
NODE_NAME     U26 AU26
 '@T6G_MB_LIB.T6G(SCH_1):PAGE58_I6@PURE_QUANTA.GENOA_SP5(CHIPS)':
 'VSS_AU26': CDS_PINID='VSS_AU26';
NODE_NAME     U26 AU28
 '@T6G_MB_LIB.T6G(SCH_1):PAGE58_I6@PURE_QUANTA.GENOA_SP5(CHIPS)':
 'VSS_AU28': CDS_PINID='VSS_AU28';
NODE_NAME     U26 AU30
 '@T6G_MB_LIB.T6G(SCH_1):PAGE58_I6@PURE_QUANTA.GENOA_SP5(CHIPS)':
 'VSS_AU30': CDS_PINID='VSS_AU30';
NODE_NAME     U26 AU32
 '@T6G_MB_LIB.T6G(SCH_1):PAGE58_I6@PURE_QUANTA.GENOA_SP5(CHIPS)':
 'VSS_AU32': CDS_PINID='VSS_AU32';
NODE_NAME     U26 AU34
 '@T6G_MB_LIB.T6G(SCH_1):PAGE58_I6@PURE_QUANTA.GENOA_SP5(CHIPS)':
 'VSS_AU34': CDS_PINID='VSS_AU34';
NODE_NAME     U26 AU36
 '@T6G_MB_LIB.T6G(SCH_1):PAGE58_I6@PURE_QUANTA.GENOA_SP5(CHIPS)':
 'VSS_AU36': CDS_PINID='VSS_AU36';
NODE_NAME     U26 AU41
 '@T6G_MB_LIB.T6G(SCH_1):PAGE58_I6@PURE_QUANTA.GENOA_SP5(CHIPS)':
 'VSS_AU41': CDS_PINID='VSS_AU41';
NODE_NAME     U26 AU43
 '@T6G_MB_LIB.T6G(SCH_1):PAGE58_I6@PURE_QUANTA.GENOA_SP5(CHIPS)':
 'VSS_AU43': CDS_PINID='VSS_AU43';
NODE_NAME     U26 AU45
 '@T6G_MB_LIB.T6G(SCH_1):PAGE58_I6@PURE_QUANTA.GENOA_SP5(CHIPS)':
 'VSS_AU45': CDS_PINID='VSS_AU45';
NODE_NAME     U26 AU47
 '@T6G_MB_LIB.T6G(SCH_1):PAGE58_I6@PURE_QUANTA.GENOA_SP5(CHIPS)':
 'VSS_AU47': CDS_PINID='VSS_AU47';
NODE_NAME     U26 AU49
 '@T6G_MB_LIB.T6G(SCH_1):PAGE58_I6@PURE_QUANTA.GENOA_SP5(CHIPS)':
 'VSS_AU49': CDS_PINID='VSS_AU49';
NODE_NAME     U26 AU51
 '@T6G_MB_LIB.T6G(SCH_1):PAGE58_I6@PURE_QUANTA.GENOA_SP5(CHIPS)':
 'VSS_AU51': CDS_PINID='VSS_AU51';
NODE_NAME     U26 AU53
 '@T6G_MB_LIB.T6G(SCH_1):PAGE58_I6@PURE_QUANTA.GENOA_SP5(CHIPS)':
 'VSS_AU53': CDS_PINID='VSS_AU53';
NODE_NAME     U26 AU56
 '@T6G_MB_LIB.T6G(SCH_1):PAGE58_I6@PURE_QUANTA.GENOA_SP5(CHIPS)':
 'VSS_AU56': CDS_PINID='VSS_AU56';
NODE_NAME     U26 AU58
 '@T6G_MB_LIB.T6G(SCH_1):PAGE58_I6@PURE_QUANTA.GENOA_SP5(CHIPS)':
 'VSS_AU58': CDS_PINID='VSS_AU58';
NODE_NAME     U26 AU61
 '@T6G_MB_LIB.T6G(SCH_1):PAGE58_I6@PURE_QUANTA.GENOA_SP5(CHIPS)':
 'VSS_AU61': CDS_PINID='VSS_AU61';
NODE_NAME     U26 AU63
 '@T6G_MB_LIB.T6G(SCH_1):PAGE58_I6@PURE_QUANTA.GENOA_SP5(CHIPS)':
 'VSS_AU63': CDS_PINID='VSS_AU63';
NODE_NAME     U26 AU65
 '@T6G_MB_LIB.T6G(SCH_1):PAGE58_I6@PURE_QUANTA.GENOA_SP5(CHIPS)':
 'VSS_AU65': CDS_PINID='VSS_AU65';
NODE_NAME     U26 AU68
 '@T6G_MB_LIB.T6G(SCH_1):PAGE58_I6@PURE_QUANTA.GENOA_SP5(CHIPS)':
 'VSS_AU68': CDS_PINID='VSS_AU68';
NODE_NAME     U26 AU70
 '@T6G_MB_LIB.T6G(SCH_1):PAGE58_I6@PURE_QUANTA.GENOA_SP5(CHIPS)':
 'VSS_AU70': CDS_PINID='VSS_AU70';
NODE_NAME     U26 AU72
 '@T6G_MB_LIB.T6G(SCH_1):PAGE58_I6@PURE_QUANTA.GENOA_SP5(CHIPS)':
 'VSS_AU72': CDS_PINID='VSS_AU72';
NODE_NAME     U26 AU73
 '@T6G_MB_LIB.T6G(SCH_1):PAGE58_I6@PURE_QUANTA.GENOA_SP5(CHIPS)':
 'VSS_AU73': CDS_PINID='VSS_AU73';
NODE_NAME     U26 AU75
 '@T6G_MB_LIB.T6G(SCH_1):PAGE58_I6@PURE_QUANTA.GENOA_SP5(CHIPS)':
 'VSS_AU75': CDS_PINID='VSS_AU75';
NODE_NAME     U26 AV3
 '@T6G_MB_LIB.T6G(SCH_1):PAGE58_I6@PURE_QUANTA.GENOA_SP5(CHIPS)':
 'VSS_AV3': CDS_PINID='VSS_AV3';
NODE_NAME     U26 AV8
 '@T6G_MB_LIB.T6G(SCH_1):PAGE58_I6@PURE_QUANTA.GENOA_SP5(CHIPS)':
 'VSS_AV8': CDS_PINID='VSS_AV8';
NODE_NAME     U26 AV10
 '@T6G_MB_LIB.T6G(SCH_1):PAGE58_I6@PURE_QUANTA.GENOA_SP5(CHIPS)':
 'VSS_AV10': CDS_PINID='VSS_AV10';
NODE_NAME     U26 AV15
 '@T6G_MB_LIB.T6G(SCH_1):PAGE58_I6@PURE_QUANTA.GENOA_SP5(CHIPS)':
 'VSS_AV15': CDS_PINID='VSS_AV15';
NODE_NAME     U26 AV17
 '@T6G_MB_LIB.T6G(SCH_1):PAGE58_I6@PURE_QUANTA.GENOA_SP5(CHIPS)':
 'VSS_AV17': CDS_PINID='VSS_AV17';
NODE_NAME     U26 AV23
 '@T6G_MB_LIB.T6G(SCH_1):PAGE58_I6@PURE_QUANTA.GENOA_SP5(CHIPS)':
 'VSS_AV23': CDS_PINID='VSS_AV23';
NODE_NAME     U26 AV25
 '@T6G_MB_LIB.T6G(SCH_1):PAGE58_I6@PURE_QUANTA.GENOA_SP5(CHIPS)':
 'VSS_AV25': CDS_PINID='VSS_AV25';
NODE_NAME     U26 AV27
 '@T6G_MB_LIB.T6G(SCH_1):PAGE58_I6@PURE_QUANTA.GENOA_SP5(CHIPS)':
 'VSS_AV27': CDS_PINID='VSS_AV27';
NODE_NAME     U26 AV29
 '@T6G_MB_LIB.T6G(SCH_1):PAGE58_I6@PURE_QUANTA.GENOA_SP5(CHIPS)':
 'VSS_AV29': CDS_PINID='VSS_AV29';
NODE_NAME     U26 AV31
 '@T6G_MB_LIB.T6G(SCH_1):PAGE58_I6@PURE_QUANTA.GENOA_SP5(CHIPS)':
 'VSS_AV31': CDS_PINID='VSS_AV31';
NODE_NAME     U26 AV33
 '@T6G_MB_LIB.T6G(SCH_1):PAGE58_I6@PURE_QUANTA.GENOA_SP5(CHIPS)':
 'VSS_AV33': CDS_PINID='VSS_AV33';
NODE_NAME     U26 AV35
 '@T6G_MB_LIB.T6G(SCH_1):PAGE58_I6@PURE_QUANTA.GENOA_SP5(CHIPS)':
 'VSS_AV35': CDS_PINID='VSS_AV35';
NODE_NAME     U26 AV37
 '@T6G_MB_LIB.T6G(SCH_1):PAGE58_I6@PURE_QUANTA.GENOA_SP5(CHIPS)':
 'VSS_AV37': CDS_PINID='VSS_AV37';
NODE_NAME     U26 AV40
 '@T6G_MB_LIB.T6G(SCH_1):PAGE58_I6@PURE_QUANTA.GENOA_SP5(CHIPS)':
 'VSS_AV40': CDS_PINID='VSS_AV40';
NODE_NAME     U26 AV42
 '@T6G_MB_LIB.T6G(SCH_1):PAGE58_I6@PURE_QUANTA.GENOA_SP5(CHIPS)':
 'VSS_AV42': CDS_PINID='VSS_AV42';
NODE_NAME     U26 AV44
 '@T6G_MB_LIB.T6G(SCH_1):PAGE58_I6@PURE_QUANTA.GENOA_SP5(CHIPS)':
 'VSS_AV44': CDS_PINID='VSS_AV44';
NODE_NAME     U26 AV46
 '@T6G_MB_LIB.T6G(SCH_1):PAGE58_I6@PURE_QUANTA.GENOA_SP5(CHIPS)':
 'VSS_AV46': CDS_PINID='VSS_AV46';
NODE_NAME     U26 AV48
 '@T6G_MB_LIB.T6G(SCH_1):PAGE58_I6@PURE_QUANTA.GENOA_SP5(CHIPS)':
 'VSS_AV48': CDS_PINID='VSS_AV48';
NODE_NAME     U26 AV50
 '@T6G_MB_LIB.T6G(SCH_1):PAGE58_I6@PURE_QUANTA.GENOA_SP5(CHIPS)':
 'VSS_AV50': CDS_PINID='VSS_AV50';
NODE_NAME     U26 AV52
 '@T6G_MB_LIB.T6G(SCH_1):PAGE58_I6@PURE_QUANTA.GENOA_SP5(CHIPS)':
 'VSS_AV52': CDS_PINID='VSS_AV52';
NODE_NAME     U26 AV54
 '@T6G_MB_LIB.T6G(SCH_1):PAGE58_I6@PURE_QUANTA.GENOA_SP5(CHIPS)':
 'VSS_AV54': CDS_PINID='VSS_AV54';
NODE_NAME     U26 AV59
 '@T6G_MB_LIB.T6G(SCH_1):PAGE58_I6@PURE_QUANTA.GENOA_SP5(CHIPS)':
 'VSS_AV59': CDS_PINID='VSS_AV59';
NODE_NAME     U26 AV61
 '@T6G_MB_LIB.T6G(SCH_1):PAGE58_I6@PURE_QUANTA.GENOA_SP5(CHIPS)':
 'VSS_AV61': CDS_PINID='VSS_AV61';
NODE_NAME     U26 AV66
 '@T6G_MB_LIB.T6G(SCH_1):PAGE58_I6@PURE_QUANTA.GENOA_SP5(CHIPS)':
 'VSS_AV66': CDS_PINID='VSS_AV66';
NODE_NAME     U26 AV68
 '@T6G_MB_LIB.T6G(SCH_1):PAGE58_I6@PURE_QUANTA.GENOA_SP5(CHIPS)':
 'VSS_AV68': CDS_PINID='VSS_AV68';
NODE_NAME     U26 AV73
 '@T6G_MB_LIB.T6G(SCH_1):PAGE58_I6@PURE_QUANTA.GENOA_SP5(CHIPS)':
 'VSS_AV73': CDS_PINID='VSS_AV73';
NODE_NAME     U26 AW1
 '@T6G_MB_LIB.T6G(SCH_1):PAGE58_I6@PURE_QUANTA.GENOA_SP5(CHIPS)':
 'VSS_AW1': CDS_PINID='VSS_AW1';
NODE_NAME     U26 AW4
 '@T6G_MB_LIB.T6G(SCH_1):PAGE58_I6@PURE_QUANTA.GENOA_SP5(CHIPS)':
 'VSS_AW4': CDS_PINID='VSS_AW4';
NODE_NAME     U26 AW6
 '@T6G_MB_LIB.T6G(SCH_1):PAGE58_I6@PURE_QUANTA.GENOA_SP5(CHIPS)':
 'VSS_AW6': CDS_PINID='VSS_AW6';
NODE_NAME     U26 AW8
 '@T6G_MB_LIB.T6G(SCH_1):PAGE58_I6@PURE_QUANTA.GENOA_SP5(CHIPS)':
 'VSS_AW8': CDS_PINID='VSS_AW8';
NODE_NAME     U26 AW11
 '@T6G_MB_LIB.T6G(SCH_1):PAGE58_I6@PURE_QUANTA.GENOA_SP5(CHIPS)':
 'VSS_AW11': CDS_PINID='VSS_AW11';
NODE_NAME     U26 AW13
 '@T6G_MB_LIB.T6G(SCH_1):PAGE58_I6@PURE_QUANTA.GENOA_SP5(CHIPS)':
 'VSS_AW13': CDS_PINID='VSS_AW13';
NODE_NAME     U26 AW15
 '@T6G_MB_LIB.T6G(SCH_1):PAGE58_I6@PURE_QUANTA.GENOA_SP5(CHIPS)':
 'VSS_AW15': CDS_PINID='VSS_AW15';
NODE_NAME     U26 AW18
 '@T6G_MB_LIB.T6G(SCH_1):PAGE58_I6@PURE_QUANTA.GENOA_SP5(CHIPS)':
 'VSS_AW18': CDS_PINID='VSS_AW18';
NODE_NAME     U26 AW20
 '@T6G_MB_LIB.T6G(SCH_1):PAGE58_I6@PURE_QUANTA.GENOA_SP5(CHIPS)':
 'VSS_AW20': CDS_PINID='VSS_AW20';
NODE_NAME     U26 AW22
 '@T6G_MB_LIB.T6G(SCH_1):PAGE58_I6@PURE_QUANTA.GENOA_SP5(CHIPS)':
 'VSS_AW22': CDS_PINID='VSS_AW22';
NODE_NAME     U26 AW24
 '@T6G_MB_LIB.T6G(SCH_1):PAGE58_I6@PURE_QUANTA.GENOA_SP5(CHIPS)':
 'VSS_AW24': CDS_PINID='VSS_AW24';
NODE_NAME     U26 AW26
 '@T6G_MB_LIB.T6G(SCH_1):PAGE58_I6@PURE_QUANTA.GENOA_SP5(CHIPS)':
 'VSS_AW26': CDS_PINID='VSS_AW26';
NODE_NAME     U26 AW28
 '@T6G_MB_LIB.T6G(SCH_1):PAGE58_I6@PURE_QUANTA.GENOA_SP5(CHIPS)':
 'VSS_AW28': CDS_PINID='VSS_AW28';
NODE_NAME     U26 AW49
 '@T6G_MB_LIB.T6G(SCH_1):PAGE58_I6@PURE_QUANTA.GENOA_SP5(CHIPS)':
 'VSS_AW49': CDS_PINID='VSS_AW49';
NODE_NAME     U26 AW51
 '@T6G_MB_LIB.T6G(SCH_1):PAGE58_I6@PURE_QUANTA.GENOA_SP5(CHIPS)':
 'VSS_AW51': CDS_PINID='VSS_AW51';
NODE_NAME     U26 AW53
 '@T6G_MB_LIB.T6G(SCH_1):PAGE58_I6@PURE_QUANTA.GENOA_SP5(CHIPS)':
 'VSS_AW53': CDS_PINID='VSS_AW53';
NODE_NAME     U26 AW56
 '@T6G_MB_LIB.T6G(SCH_1):PAGE58_I6@PURE_QUANTA.GENOA_SP5(CHIPS)':
 'VSS_AW56': CDS_PINID='VSS_AW56';
NODE_NAME     U26 AW58
 '@T6G_MB_LIB.T6G(SCH_1):PAGE58_I6@PURE_QUANTA.GENOA_SP5(CHIPS)':
 'VSS_AW58': CDS_PINID='VSS_AW58';
NODE_NAME     U26 AW61
 '@T6G_MB_LIB.T6G(SCH_1):PAGE58_I6@PURE_QUANTA.GENOA_SP5(CHIPS)':
 'VSS_AW61': CDS_PINID='VSS_AW61';
NODE_NAME     U26 AD49
 '@T6G_MB_LIB.T6G(SCH_1):PAGE58_I9@PURE_QUANTA.GENOA_SP5(CHIPS)':
 'VSS_AD49': CDS_PINID='VSS_AD49';
NODE_NAME     U26 AD50
 '@T6G_MB_LIB.T6G(SCH_1):PAGE58_I9@PURE_QUANTA.GENOA_SP5(CHIPS)':
 'VSS_AD50': CDS_PINID='VSS_AD50';
NODE_NAME     U26 AD51
 '@T6G_MB_LIB.T6G(SCH_1):PAGE58_I9@PURE_QUANTA.GENOA_SP5(CHIPS)':
 'VSS_AD51': CDS_PINID='VSS_AD51';
NODE_NAME     U26 AD52
 '@T6G_MB_LIB.T6G(SCH_1):PAGE58_I9@PURE_QUANTA.GENOA_SP5(CHIPS)':
 'VSS_AD52': CDS_PINID='VSS_AD52';
NODE_NAME     U26 AD53
 '@T6G_MB_LIB.T6G(SCH_1):PAGE58_I9@PURE_QUANTA.GENOA_SP5(CHIPS)':
 'VSS_AD53': CDS_PINID='VSS_AD53';
NODE_NAME     U26 AD57
 '@T6G_MB_LIB.T6G(SCH_1):PAGE58_I9@PURE_QUANTA.GENOA_SP5(CHIPS)':
 'VSS_AD57': CDS_PINID='VSS_AD57';
NODE_NAME     U26 AD59
 '@T6G_MB_LIB.T6G(SCH_1):PAGE58_I9@PURE_QUANTA.GENOA_SP5(CHIPS)':
 'VSS_AD59': CDS_PINID='VSS_AD59';
NODE_NAME     U26 AD61
 '@T6G_MB_LIB.T6G(SCH_1):PAGE58_I9@PURE_QUANTA.GENOA_SP5(CHIPS)':
 'VSS_AD61': CDS_PINID='VSS_AD61';
NODE_NAME     U26 AD64
 '@T6G_MB_LIB.T6G(SCH_1):PAGE58_I9@PURE_QUANTA.GENOA_SP5(CHIPS)':
 'VSS_AD64': CDS_PINID='VSS_AD64';
NODE_NAME     U26 AD66
 '@T6G_MB_LIB.T6G(SCH_1):PAGE58_I9@PURE_QUANTA.GENOA_SP5(CHIPS)':
 'VSS_AD66': CDS_PINID='VSS_AD66';
NODE_NAME     U26 AD68
 '@T6G_MB_LIB.T6G(SCH_1):PAGE58_I9@PURE_QUANTA.GENOA_SP5(CHIPS)':
 'VSS_AD68': CDS_PINID='VSS_AD68';
NODE_NAME     U26 AD71
 '@T6G_MB_LIB.T6G(SCH_1):PAGE58_I9@PURE_QUANTA.GENOA_SP5(CHIPS)':
 'VSS_AD71': CDS_PINID='VSS_AD71';
NODE_NAME     U26 AD73
 '@T6G_MB_LIB.T6G(SCH_1):PAGE58_I9@PURE_QUANTA.GENOA_SP5(CHIPS)':
 'VSS_AD73': CDS_PINID='VSS_AD73';
NODE_NAME     U26 AE1
 '@T6G_MB_LIB.T6G(SCH_1):PAGE58_I9@PURE_QUANTA.GENOA_SP5(CHIPS)':
 'VSS_AE1': CDS_PINID='VSS_AE1';
NODE_NAME     U26 AE6
 '@T6G_MB_LIB.T6G(SCH_1):PAGE58_I9@PURE_QUANTA.GENOA_SP5(CHIPS)':
 'VSS_AE6': CDS_PINID='VSS_AE6';
NODE_NAME     U26 AE8
 '@T6G_MB_LIB.T6G(SCH_1):PAGE58_I9@PURE_QUANTA.GENOA_SP5(CHIPS)':
 'VSS_AE8': CDS_PINID='VSS_AE8';
NODE_NAME     U26 AE11
 '@T6G_MB_LIB.T6G(SCH_1):PAGE58_I9@PURE_QUANTA.GENOA_SP5(CHIPS)':
 'VSS_AE11': CDS_PINID='VSS_AE11';
NODE_NAME     U26 AE13
 '@T6G_MB_LIB.T6G(SCH_1):PAGE58_I9@PURE_QUANTA.GENOA_SP5(CHIPS)':
 'VSS_AE13': CDS_PINID='VSS_AE13';
NODE_NAME     U26 AE15
 '@T6G_MB_LIB.T6G(SCH_1):PAGE58_I9@PURE_QUANTA.GENOA_SP5(CHIPS)':
 'VSS_AE15': CDS_PINID='VSS_AE15';
NODE_NAME     U26 AE18
 '@T6G_MB_LIB.T6G(SCH_1):PAGE58_I9@PURE_QUANTA.GENOA_SP5(CHIPS)':
 'VSS_AE18': CDS_PINID='VSS_AE18';
NODE_NAME     U26 AE20
 '@T6G_MB_LIB.T6G(SCH_1):PAGE58_I9@PURE_QUANTA.GENOA_SP5(CHIPS)':
 'VSS_AE20': CDS_PINID='VSS_AE20';
NODE_NAME     U26 AE22
 '@T6G_MB_LIB.T6G(SCH_1):PAGE58_I9@PURE_QUANTA.GENOA_SP5(CHIPS)':
 'VSS_AE22': CDS_PINID='VSS_AE22';
NODE_NAME     U26 AE25
 '@T6G_MB_LIB.T6G(SCH_1):PAGE58_I9@PURE_QUANTA.GENOA_SP5(CHIPS)':
 'VSS_AE25': CDS_PINID='VSS_AE25';
NODE_NAME     U26 AE28
 '@T6G_MB_LIB.T6G(SCH_1):PAGE58_I9@PURE_QUANTA.GENOA_SP5(CHIPS)':
 'VSS_AE28': CDS_PINID='VSS_AE28';
NODE_NAME     U26 AE31
 '@T6G_MB_LIB.T6G(SCH_1):PAGE58_I9@PURE_QUANTA.GENOA_SP5(CHIPS)':
 'VSS_AE31': CDS_PINID='VSS_AE31';
NODE_NAME     U26 AE34
 '@T6G_MB_LIB.T6G(SCH_1):PAGE58_I9@PURE_QUANTA.GENOA_SP5(CHIPS)':
 'VSS_AE34': CDS_PINID='VSS_AE34';
NODE_NAME     U26 AE35
 '@T6G_MB_LIB.T6G(SCH_1):PAGE58_I9@PURE_QUANTA.GENOA_SP5(CHIPS)':
 'VSS_AE35': CDS_PINID='VSS_AE35';
NODE_NAME     U26 AE36
 '@T6G_MB_LIB.T6G(SCH_1):PAGE58_I9@PURE_QUANTA.GENOA_SP5(CHIPS)':
 'VSS_AE36': CDS_PINID='VSS_AE36';
NODE_NAME     U26 AE40
 '@T6G_MB_LIB.T6G(SCH_1):PAGE58_I9@PURE_QUANTA.GENOA_SP5(CHIPS)':
 'VSS_AE40': CDS_PINID='VSS_AE40';
NODE_NAME     U26 AE41
 '@T6G_MB_LIB.T6G(SCH_1):PAGE58_I9@PURE_QUANTA.GENOA_SP5(CHIPS)':
 'VSS_AE41': CDS_PINID='VSS_AE41';
NODE_NAME     U26 AE42
 '@T6G_MB_LIB.T6G(SCH_1):PAGE58_I9@PURE_QUANTA.GENOA_SP5(CHIPS)':
 'VSS_AE42': CDS_PINID='VSS_AE42';
NODE_NAME     U26 AE45
 '@T6G_MB_LIB.T6G(SCH_1):PAGE58_I9@PURE_QUANTA.GENOA_SP5(CHIPS)':
 'VSS_AE45': CDS_PINID='VSS_AE45';
NODE_NAME     U26 AE48
 '@T6G_MB_LIB.T6G(SCH_1):PAGE58_I9@PURE_QUANTA.GENOA_SP5(CHIPS)':
 'VSS_AE48': CDS_PINID='VSS_AE48';
NODE_NAME     U26 AE51
 '@T6G_MB_LIB.T6G(SCH_1):PAGE58_I9@PURE_QUANTA.GENOA_SP5(CHIPS)':
 'VSS_AE51': CDS_PINID='VSS_AE51';
NODE_NAME     U26 AE54
 '@T6G_MB_LIB.T6G(SCH_1):PAGE58_I9@PURE_QUANTA.GENOA_SP5(CHIPS)':
 'VSS_AE54': CDS_PINID='VSS_AE54';
NODE_NAME     U26 AE56
 '@T6G_MB_LIB.T6G(SCH_1):PAGE58_I9@PURE_QUANTA.GENOA_SP5(CHIPS)':
 'VSS_AE56': CDS_PINID='VSS_AE56';
NODE_NAME     U26 AE58
 '@T6G_MB_LIB.T6G(SCH_1):PAGE58_I9@PURE_QUANTA.GENOA_SP5(CHIPS)':
 'VSS_AE58': CDS_PINID='VSS_AE58';
NODE_NAME     U26 AE61
 '@T6G_MB_LIB.T6G(SCH_1):PAGE58_I9@PURE_QUANTA.GENOA_SP5(CHIPS)':
 'VSS_AE61': CDS_PINID='VSS_AE61';
NODE_NAME     U26 AE63
 '@T6G_MB_LIB.T6G(SCH_1):PAGE58_I9@PURE_QUANTA.GENOA_SP5(CHIPS)':
 'VSS_AE63': CDS_PINID='VSS_AE63';
NODE_NAME     U26 AE65
 '@T6G_MB_LIB.T6G(SCH_1):PAGE58_I9@PURE_QUANTA.GENOA_SP5(CHIPS)':
 'VSS_AE65': CDS_PINID='VSS_AE65';
NODE_NAME     U26 AE68
 '@T6G_MB_LIB.T6G(SCH_1):PAGE58_I9@PURE_QUANTA.GENOA_SP5(CHIPS)':
 'VSS_AE68': CDS_PINID='VSS_AE68';
NODE_NAME     U26 AE70
 '@T6G_MB_LIB.T6G(SCH_1):PAGE58_I9@PURE_QUANTA.GENOA_SP5(CHIPS)':
 'VSS_AE70': CDS_PINID='VSS_AE70';
NODE_NAME     U26 AE72
 '@T6G_MB_LIB.T6G(SCH_1):PAGE58_I9@PURE_QUANTA.GENOA_SP5(CHIPS)':
 'VSS_AE72': CDS_PINID='VSS_AE72';
NODE_NAME     U26 AE75
 '@T6G_MB_LIB.T6G(SCH_1):PAGE58_I9@PURE_QUANTA.GENOA_SP5(CHIPS)':
 'VSS_AE75': CDS_PINID='VSS_AE75';
NODE_NAME     U26 AF3
 '@T6G_MB_LIB.T6G(SCH_1):PAGE58_I9@PURE_QUANTA.GENOA_SP5(CHIPS)':
 'VSS_AF3': CDS_PINID='VSS_AF3';
NODE_NAME     U26 AF8
 '@T6G_MB_LIB.T6G(SCH_1):PAGE58_I9@PURE_QUANTA.GENOA_SP5(CHIPS)':
 'VSS_AF8': CDS_PINID='VSS_AF8';
NODE_NAME     U26 AF10
 '@T6G_MB_LIB.T6G(SCH_1):PAGE58_I9@PURE_QUANTA.GENOA_SP5(CHIPS)':
 'VSS_AF10': CDS_PINID='VSS_AF10';
NODE_NAME     U26 AF15
 '@T6G_MB_LIB.T6G(SCH_1):PAGE58_I9@PURE_QUANTA.GENOA_SP5(CHIPS)':
 'VSS_AF15': CDS_PINID='VSS_AF15';
NODE_NAME     U26 AF17
 '@T6G_MB_LIB.T6G(SCH_1):PAGE58_I9@PURE_QUANTA.GENOA_SP5(CHIPS)':
 'VSS_AF17': CDS_PINID='VSS_AF17';
NODE_NAME     U26 AF22
 '@T6G_MB_LIB.T6G(SCH_1):PAGE58_I9@PURE_QUANTA.GENOA_SP5(CHIPS)':
 'VSS_AF22': CDS_PINID='VSS_AF22';
NODE_NAME     U26 AF25
 '@T6G_MB_LIB.T6G(SCH_1):PAGE58_I9@PURE_QUANTA.GENOA_SP5(CHIPS)':
 'VSS_AF25': CDS_PINID='VSS_AF25';
NODE_NAME     U26 AF28
 '@T6G_MB_LIB.T6G(SCH_1):PAGE58_I9@PURE_QUANTA.GENOA_SP5(CHIPS)':
 'VSS_AF28': CDS_PINID='VSS_AF28';
NODE_NAME     U26 AF31
 '@T6G_MB_LIB.T6G(SCH_1):PAGE58_I9@PURE_QUANTA.GENOA_SP5(CHIPS)':
 'VSS_AF31': CDS_PINID='VSS_AF31';
NODE_NAME     U26 AF34
 '@T6G_MB_LIB.T6G(SCH_1):PAGE58_I9@PURE_QUANTA.GENOA_SP5(CHIPS)':
 'VSS_AF34': CDS_PINID='VSS_AF34';
NODE_NAME     U26 AF37
 '@T6G_MB_LIB.T6G(SCH_1):PAGE58_I9@PURE_QUANTA.GENOA_SP5(CHIPS)':
 'VSS_AF37': CDS_PINID='VSS_AF37';
NODE_NAME     U26 AF39
 '@T6G_MB_LIB.T6G(SCH_1):PAGE58_I9@PURE_QUANTA.GENOA_SP5(CHIPS)':
 'VSS_AF39': CDS_PINID='VSS_AF39';
NODE_NAME     U26 AF42
 '@T6G_MB_LIB.T6G(SCH_1):PAGE58_I9@PURE_QUANTA.GENOA_SP5(CHIPS)':
 'VSS_AF42': CDS_PINID='VSS_AF42';
NODE_NAME     U26 AF45
 '@T6G_MB_LIB.T6G(SCH_1):PAGE58_I9@PURE_QUANTA.GENOA_SP5(CHIPS)':
 'VSS_AF45': CDS_PINID='VSS_AF45';
NODE_NAME     U26 AF48
 '@T6G_MB_LIB.T6G(SCH_1):PAGE58_I9@PURE_QUANTA.GENOA_SP5(CHIPS)':
 'VSS_AF48': CDS_PINID='VSS_AF48';
NODE_NAME     U26 AF51
 '@T6G_MB_LIB.T6G(SCH_1):PAGE58_I9@PURE_QUANTA.GENOA_SP5(CHIPS)':
 'VSS_AF51': CDS_PINID='VSS_AF51';
NODE_NAME     U26 AF54
 '@T6G_MB_LIB.T6G(SCH_1):PAGE58_I9@PURE_QUANTA.GENOA_SP5(CHIPS)':
 'VSS_AF54': CDS_PINID='VSS_AF54';
NODE_NAME     U26 AF59
 '@T6G_MB_LIB.T6G(SCH_1):PAGE58_I9@PURE_QUANTA.GENOA_SP5(CHIPS)':
 'VSS_AF59': CDS_PINID='VSS_AF59';
NODE_NAME     U26 AF61
 '@T6G_MB_LIB.T6G(SCH_1):PAGE58_I9@PURE_QUANTA.GENOA_SP5(CHIPS)':
 'VSS_AF61': CDS_PINID='VSS_AF61';
NODE_NAME     U26 AF66
 '@T6G_MB_LIB.T6G(SCH_1):PAGE58_I9@PURE_QUANTA.GENOA_SP5(CHIPS)':
 'VSS_AF66': CDS_PINID='VSS_AF66';
NODE_NAME     U26 AF68
 '@T6G_MB_LIB.T6G(SCH_1):PAGE58_I9@PURE_QUANTA.GENOA_SP5(CHIPS)':
 'VSS_AF68': CDS_PINID='VSS_AF68';
NODE_NAME     U26 AF73
 '@T6G_MB_LIB.T6G(SCH_1):PAGE58_I9@PURE_QUANTA.GENOA_SP5(CHIPS)':
 'VSS_AF73': CDS_PINID='VSS_AF73';
NODE_NAME     U26 AG1
 '@T6G_MB_LIB.T6G(SCH_1):PAGE58_I9@PURE_QUANTA.GENOA_SP5(CHIPS)':
 'VSS_AG1': CDS_PINID='VSS_AG1';
NODE_NAME     U26 AG4
 '@T6G_MB_LIB.T6G(SCH_1):PAGE58_I9@PURE_QUANTA.GENOA_SP5(CHIPS)':
 'VSS_AG4': CDS_PINID='VSS_AG4';
NODE_NAME     U26 AG6
 '@T6G_MB_LIB.T6G(SCH_1):PAGE58_I9@PURE_QUANTA.GENOA_SP5(CHIPS)':
 'VSS_AG6': CDS_PINID='VSS_AG6';
NODE_NAME     U26 AG8
 '@T6G_MB_LIB.T6G(SCH_1):PAGE58_I9@PURE_QUANTA.GENOA_SP5(CHIPS)':
 'VSS_AG8': CDS_PINID='VSS_AG8';
NODE_NAME     U26 AG11
 '@T6G_MB_LIB.T6G(SCH_1):PAGE58_I9@PURE_QUANTA.GENOA_SP5(CHIPS)':
 'VSS_AG11': CDS_PINID='VSS_AG11';
NODE_NAME     U26 AG13
 '@T6G_MB_LIB.T6G(SCH_1):PAGE58_I9@PURE_QUANTA.GENOA_SP5(CHIPS)':
 'VSS_AG13': CDS_PINID='VSS_AG13';
NODE_NAME     U26 AG15
 '@T6G_MB_LIB.T6G(SCH_1):PAGE58_I9@PURE_QUANTA.GENOA_SP5(CHIPS)':
 'VSS_AG15': CDS_PINID='VSS_AG15';
NODE_NAME     U26 AG18
 '@T6G_MB_LIB.T6G(SCH_1):PAGE58_I9@PURE_QUANTA.GENOA_SP5(CHIPS)':
 'VSS_AG18': CDS_PINID='VSS_AG18';
NODE_NAME     U26 AG20
 '@T6G_MB_LIB.T6G(SCH_1):PAGE58_I9@PURE_QUANTA.GENOA_SP5(CHIPS)':
 'VSS_AG20': CDS_PINID='VSS_AG20';
NODE_NAME     U26 AG22
 '@T6G_MB_LIB.T6G(SCH_1):PAGE58_I9@PURE_QUANTA.GENOA_SP5(CHIPS)':
 'VSS_AG22': CDS_PINID='VSS_AG22';
NODE_NAME     U26 AG25
 '@T6G_MB_LIB.T6G(SCH_1):PAGE58_I9@PURE_QUANTA.GENOA_SP5(CHIPS)':
 'VSS_AG25': CDS_PINID='VSS_AG25';
NODE_NAME     U26 AG28
 '@T6G_MB_LIB.T6G(SCH_1):PAGE58_I9@PURE_QUANTA.GENOA_SP5(CHIPS)':
 'VSS_AG28': CDS_PINID='VSS_AG28';
NODE_NAME     U26 AG31
 '@T6G_MB_LIB.T6G(SCH_1):PAGE58_I9@PURE_QUANTA.GENOA_SP5(CHIPS)':
 'VSS_AG31': CDS_PINID='VSS_AG31';
NODE_NAME     U26 AG34
 '@T6G_MB_LIB.T6G(SCH_1):PAGE58_I9@PURE_QUANTA.GENOA_SP5(CHIPS)':
 'VSS_AG34': CDS_PINID='VSS_AG34';
NODE_NAME     U26 AG42
 '@T6G_MB_LIB.T6G(SCH_1):PAGE58_I9@PURE_QUANTA.GENOA_SP5(CHIPS)':
 'VSS_AG42': CDS_PINID='VSS_AG42';
NODE_NAME     U26 AG45
 '@T6G_MB_LIB.T6G(SCH_1):PAGE58_I9@PURE_QUANTA.GENOA_SP5(CHIPS)':
 'VSS_AG45': CDS_PINID='VSS_AG45';
NODE_NAME     U26 AG48
 '@T6G_MB_LIB.T6G(SCH_1):PAGE58_I9@PURE_QUANTA.GENOA_SP5(CHIPS)':
 'VSS_AG48': CDS_PINID='VSS_AG48';
NODE_NAME     U26 AG51
 '@T6G_MB_LIB.T6G(SCH_1):PAGE58_I9@PURE_QUANTA.GENOA_SP5(CHIPS)':
 'VSS_AG51': CDS_PINID='VSS_AG51';
NODE_NAME     U26 AG54
 '@T6G_MB_LIB.T6G(SCH_1):PAGE58_I9@PURE_QUANTA.GENOA_SP5(CHIPS)':
 'VSS_AG54': CDS_PINID='VSS_AG54';
NODE_NAME     U26 AG56
 '@T6G_MB_LIB.T6G(SCH_1):PAGE58_I9@PURE_QUANTA.GENOA_SP5(CHIPS)':
 'VSS_AG56': CDS_PINID='VSS_AG56';
NODE_NAME     U26 AG58
 '@T6G_MB_LIB.T6G(SCH_1):PAGE58_I9@PURE_QUANTA.GENOA_SP5(CHIPS)':
 'VSS_AG58': CDS_PINID='VSS_AG58';
NODE_NAME     U26 AG61
 '@T6G_MB_LIB.T6G(SCH_1):PAGE58_I9@PURE_QUANTA.GENOA_SP5(CHIPS)':
 'VSS_AG61': CDS_PINID='VSS_AG61';
NODE_NAME     U26 AG63
 '@T6G_MB_LIB.T6G(SCH_1):PAGE58_I9@PURE_QUANTA.GENOA_SP5(CHIPS)':
 'VSS_AG63': CDS_PINID='VSS_AG63';
NODE_NAME     U26 AG65
 '@T6G_MB_LIB.T6G(SCH_1):PAGE58_I9@PURE_QUANTA.GENOA_SP5(CHIPS)':
 'VSS_AG65': CDS_PINID='VSS_AG65';
NODE_NAME     U26 AG68
 '@T6G_MB_LIB.T6G(SCH_1):PAGE58_I9@PURE_QUANTA.GENOA_SP5(CHIPS)':
 'VSS_AG68': CDS_PINID='VSS_AG68';
NODE_NAME     U26 AG70
 '@T6G_MB_LIB.T6G(SCH_1):PAGE58_I9@PURE_QUANTA.GENOA_SP5(CHIPS)':
 'VSS_AG70': CDS_PINID='VSS_AG70';
NODE_NAME     U26 AG72
 '@T6G_MB_LIB.T6G(SCH_1):PAGE58_I9@PURE_QUANTA.GENOA_SP5(CHIPS)':
 'VSS_AG72': CDS_PINID='VSS_AG72';
NODE_NAME     U26 AG75
 '@T6G_MB_LIB.T6G(SCH_1):PAGE58_I9@PURE_QUANTA.GENOA_SP5(CHIPS)':
 'VSS_AG75': CDS_PINID='VSS_AG75';
NODE_NAME     U26 AH3
 '@T6G_MB_LIB.T6G(SCH_1):PAGE58_I9@PURE_QUANTA.GENOA_SP5(CHIPS)':
 'VSS_AH3': CDS_PINID='VSS_AH3';
NODE_NAME     U26 AH5
 '@T6G_MB_LIB.T6G(SCH_1):PAGE58_I9@PURE_QUANTA.GENOA_SP5(CHIPS)':
 'VSS_AH5': CDS_PINID='VSS_AH5';
NODE_NAME     U26 AH8
 '@T6G_MB_LIB.T6G(SCH_1):PAGE58_I9@PURE_QUANTA.GENOA_SP5(CHIPS)':
 'VSS_AH8': CDS_PINID='VSS_AH8';
NODE_NAME     U26 AH10
 '@T6G_MB_LIB.T6G(SCH_1):PAGE58_I9@PURE_QUANTA.GENOA_SP5(CHIPS)':
 'VSS_AH10': CDS_PINID='VSS_AH10';
NODE_NAME     U26 AH12
 '@T6G_MB_LIB.T6G(SCH_1):PAGE58_I9@PURE_QUANTA.GENOA_SP5(CHIPS)':
 'VSS_AH12': CDS_PINID='VSS_AH12';
NODE_NAME     U26 AH15
 '@T6G_MB_LIB.T6G(SCH_1):PAGE58_I9@PURE_QUANTA.GENOA_SP5(CHIPS)':
 'VSS_AH15': CDS_PINID='VSS_AH15';
NODE_NAME     U26 AH17
 '@T6G_MB_LIB.T6G(SCH_1):PAGE58_I9@PURE_QUANTA.GENOA_SP5(CHIPS)':
 'VSS_AH17': CDS_PINID='VSS_AH17';
NODE_NAME     U26 AH19
 '@T6G_MB_LIB.T6G(SCH_1):PAGE58_I9@PURE_QUANTA.GENOA_SP5(CHIPS)':
 'VSS_AH19': CDS_PINID='VSS_AH19';
NODE_NAME     U26 AH23
 '@T6G_MB_LIB.T6G(SCH_1):PAGE58_I9@PURE_QUANTA.GENOA_SP5(CHIPS)':
 'VSS_AH23': CDS_PINID='VSS_AH23';
NODE_NAME     U26 AH24
 '@T6G_MB_LIB.T6G(SCH_1):PAGE58_I9@PURE_QUANTA.GENOA_SP5(CHIPS)':
 'VSS_AH24': CDS_PINID='VSS_AH24';
NODE_NAME     U26 AH25
 '@T6G_MB_LIB.T6G(SCH_1):PAGE58_I9@PURE_QUANTA.GENOA_SP5(CHIPS)':
 'VSS_AH25': CDS_PINID='VSS_AH25';
NODE_NAME     U26 AH26
 '@T6G_MB_LIB.T6G(SCH_1):PAGE58_I9@PURE_QUANTA.GENOA_SP5(CHIPS)':
 'VSS_AH26': CDS_PINID='VSS_AH26';
NODE_NAME     U26 AH27
 '@T6G_MB_LIB.T6G(SCH_1):PAGE58_I9@PURE_QUANTA.GENOA_SP5(CHIPS)':
 'VSS_AH27': CDS_PINID='VSS_AH27';
NODE_NAME     U26 AH28
 '@T6G_MB_LIB.T6G(SCH_1):PAGE58_I9@PURE_QUANTA.GENOA_SP5(CHIPS)':
 'VSS_AH28': CDS_PINID='VSS_AH28';
NODE_NAME     U26 AH29
 '@T6G_MB_LIB.T6G(SCH_1):PAGE58_I9@PURE_QUANTA.GENOA_SP5(CHIPS)':
 'VSS_AH29': CDS_PINID='VSS_AH29';
NODE_NAME     U26 AH30
 '@T6G_MB_LIB.T6G(SCH_1):PAGE58_I9@PURE_QUANTA.GENOA_SP5(CHIPS)':
 'VSS_AH30': CDS_PINID='VSS_AH30';
NODE_NAME     U26 AH31
 '@T6G_MB_LIB.T6G(SCH_1):PAGE58_I9@PURE_QUANTA.GENOA_SP5(CHIPS)':
 'VSS_AH31': CDS_PINID='VSS_AH31';
NODE_NAME     U26 AH32
 '@T6G_MB_LIB.T6G(SCH_1):PAGE58_I9@PURE_QUANTA.GENOA_SP5(CHIPS)':
 'VSS_AH32': CDS_PINID='VSS_AH32';
NODE_NAME     U26 AH34
 '@T6G_MB_LIB.T6G(SCH_1):PAGE58_I9@PURE_QUANTA.GENOA_SP5(CHIPS)':
 'VSS_AH34': CDS_PINID='VSS_AH34';
NODE_NAME     U26 AH37
 '@T6G_MB_LIB.T6G(SCH_1):PAGE58_I9@PURE_QUANTA.GENOA_SP5(CHIPS)':
 'VSS_AH37': CDS_PINID='VSS_AH37';
NODE_NAME     U26 AH39
 '@T6G_MB_LIB.T6G(SCH_1):PAGE58_I9@PURE_QUANTA.GENOA_SP5(CHIPS)':
 'VSS_AH39': CDS_PINID='VSS_AH39';
NODE_NAME     U26 AH42
 '@T6G_MB_LIB.T6G(SCH_1):PAGE58_I9@PURE_QUANTA.GENOA_SP5(CHIPS)':
 'VSS_AH42': CDS_PINID='VSS_AH42';
NODE_NAME     U26 AH43
 '@T6G_MB_LIB.T6G(SCH_1):PAGE58_I9@PURE_QUANTA.GENOA_SP5(CHIPS)':
 'VSS_AH43': CDS_PINID='VSS_AH43';
NODE_NAME     U26 AH44
 '@T6G_MB_LIB.T6G(SCH_1):PAGE58_I9@PURE_QUANTA.GENOA_SP5(CHIPS)':
 'VSS_AH44': CDS_PINID='VSS_AH44';
NODE_NAME     U26 AH45
 '@T6G_MB_LIB.T6G(SCH_1):PAGE58_I9@PURE_QUANTA.GENOA_SP5(CHIPS)':
 'VSS_AH45': CDS_PINID='VSS_AH45';
NODE_NAME     U26 AH46
 '@T6G_MB_LIB.T6G(SCH_1):PAGE58_I9@PURE_QUANTA.GENOA_SP5(CHIPS)':
 'VSS_AH46': CDS_PINID='VSS_AH46';
NODE_NAME     U26 AH47
 '@T6G_MB_LIB.T6G(SCH_1):PAGE58_I9@PURE_QUANTA.GENOA_SP5(CHIPS)':
 'VSS_AH47': CDS_PINID='VSS_AH47';
NODE_NAME     U26 AH48
 '@T6G_MB_LIB.T6G(SCH_1):PAGE58_I9@PURE_QUANTA.GENOA_SP5(CHIPS)':
 'VSS_AH48': CDS_PINID='VSS_AH48';
NODE_NAME     U26 AH49
 '@T6G_MB_LIB.T6G(SCH_1):PAGE58_I9@PURE_QUANTA.GENOA_SP5(CHIPS)':
 'VSS_AH49': CDS_PINID='VSS_AH49';
NODE_NAME     U26 AH50
 '@T6G_MB_LIB.T6G(SCH_1):PAGE58_I9@PURE_QUANTA.GENOA_SP5(CHIPS)':
 'VSS_AH50': CDS_PINID='VSS_AH50';
NODE_NAME     U26 AH51
 '@T6G_MB_LIB.T6G(SCH_1):PAGE58_I9@PURE_QUANTA.GENOA_SP5(CHIPS)':
 'VSS_AH51': CDS_PINID='VSS_AH51';
NODE_NAME     U26 AH52
 '@T6G_MB_LIB.T6G(SCH_1):PAGE58_I9@PURE_QUANTA.GENOA_SP5(CHIPS)':
 'VSS_AH52': CDS_PINID='VSS_AH52';
NODE_NAME     U26 AH53
 '@T6G_MB_LIB.T6G(SCH_1):PAGE58_I9@PURE_QUANTA.GENOA_SP5(CHIPS)':
 'VSS_AH53': CDS_PINID='VSS_AH53';
NODE_NAME     U26 AH57
 '@T6G_MB_LIB.T6G(SCH_1):PAGE58_I9@PURE_QUANTA.GENOA_SP5(CHIPS)':
 'VSS_AH57': CDS_PINID='VSS_AH57';
NODE_NAME     U26 AH59
 '@T6G_MB_LIB.T6G(SCH_1):PAGE58_I9@PURE_QUANTA.GENOA_SP5(CHIPS)':
 'VSS_AH59': CDS_PINID='VSS_AH59';
NODE_NAME     U26 AH61
 '@T6G_MB_LIB.T6G(SCH_1):PAGE58_I9@PURE_QUANTA.GENOA_SP5(CHIPS)':
 'VSS_AH61': CDS_PINID='VSS_AH61';
NODE_NAME     U26 AH64
 '@T6G_MB_LIB.T6G(SCH_1):PAGE58_I9@PURE_QUANTA.GENOA_SP5(CHIPS)':
 'VSS_AH64': CDS_PINID='VSS_AH64';
NODE_NAME     U26 AH66
 '@T6G_MB_LIB.T6G(SCH_1):PAGE58_I9@PURE_QUANTA.GENOA_SP5(CHIPS)':
 'VSS_AH66': CDS_PINID='VSS_AH66';
NODE_NAME     U26 AH68
 '@T6G_MB_LIB.T6G(SCH_1):PAGE58_I9@PURE_QUANTA.GENOA_SP5(CHIPS)':
 'VSS_AH68': CDS_PINID='VSS_AH68';
NODE_NAME     U26 AH71
 '@T6G_MB_LIB.T6G(SCH_1):PAGE58_I9@PURE_QUANTA.GENOA_SP5(CHIPS)':
 'VSS_AH71': CDS_PINID='VSS_AH71';
NODE_NAME     U26 AH73
 '@T6G_MB_LIB.T6G(SCH_1):PAGE58_I9@PURE_QUANTA.GENOA_SP5(CHIPS)':
 'VSS_AH73': CDS_PINID='VSS_AH73';
NODE_NAME     U26 AJ1
 '@T6G_MB_LIB.T6G(SCH_1):PAGE58_I9@PURE_QUANTA.GENOA_SP5(CHIPS)':
 'VSS_AJ1': CDS_PINID='VSS_AJ1';
NODE_NAME     U26 AJ6
 '@T6G_MB_LIB.T6G(SCH_1):PAGE58_I9@PURE_QUANTA.GENOA_SP5(CHIPS)':
 'VSS_AJ6': CDS_PINID='VSS_AJ6';
NODE_NAME     U26 AJ8
 '@T6G_MB_LIB.T6G(SCH_1):PAGE58_I9@PURE_QUANTA.GENOA_SP5(CHIPS)':
 'VSS_AJ8': CDS_PINID='VSS_AJ8';
NODE_NAME     U26 AJ15
 '@T6G_MB_LIB.T6G(SCH_1):PAGE58_I9@PURE_QUANTA.GENOA_SP5(CHIPS)':
 'VSS_AJ15': CDS_PINID='VSS_AJ15';
NODE_NAME     U26 AJ20
 '@T6G_MB_LIB.T6G(SCH_1):PAGE58_I9@PURE_QUANTA.GENOA_SP5(CHIPS)':
 'VSS_AJ20': CDS_PINID='VSS_AJ20';
NODE_NAME     U26 AJ22
 '@T6G_MB_LIB.T6G(SCH_1):PAGE58_I9@PURE_QUANTA.GENOA_SP5(CHIPS)':
 'VSS_AJ22': CDS_PINID='VSS_AJ22';
NODE_NAME     U26 AJ25
 '@T6G_MB_LIB.T6G(SCH_1):PAGE58_I9@PURE_QUANTA.GENOA_SP5(CHIPS)':
 'VSS_AJ25': CDS_PINID='VSS_AJ25';
NODE_NAME     U26 AJ28
 '@T6G_MB_LIB.T6G(SCH_1):PAGE58_I9@PURE_QUANTA.GENOA_SP5(CHIPS)':
 'VSS_AJ28': CDS_PINID='VSS_AJ28';
NODE_NAME     U26 AJ31
 '@T6G_MB_LIB.T6G(SCH_1):PAGE58_I9@PURE_QUANTA.GENOA_SP5(CHIPS)':
 'VSS_AJ31': CDS_PINID='VSS_AJ31';
NODE_NAME     U26 AJ34
 '@T6G_MB_LIB.T6G(SCH_1):PAGE58_I9@PURE_QUANTA.GENOA_SP5(CHIPS)':
 'VSS_AJ34': CDS_PINID='VSS_AJ34';
NODE_NAME     U26 AJ35
 '@T6G_MB_LIB.T6G(SCH_1):PAGE58_I9@PURE_QUANTA.GENOA_SP5(CHIPS)':
 'VSS_AJ35': CDS_PINID='VSS_AJ35';
NODE_NAME     U26 AJ36
 '@T6G_MB_LIB.T6G(SCH_1):PAGE58_I9@PURE_QUANTA.GENOA_SP5(CHIPS)':
 'VSS_AJ36': CDS_PINID='VSS_AJ36';
NODE_NAME     U26 AJ40
 '@T6G_MB_LIB.T6G(SCH_1):PAGE58_I9@PURE_QUANTA.GENOA_SP5(CHIPS)':
 'VSS_AJ40': CDS_PINID='VSS_AJ40';
NODE_NAME     U26 AJ41
 '@T6G_MB_LIB.T6G(SCH_1):PAGE58_I9@PURE_QUANTA.GENOA_SP5(CHIPS)':
 'VSS_AJ41': CDS_PINID='VSS_AJ41';
NODE_NAME     U26 AJ42
 '@T6G_MB_LIB.T6G(SCH_1):PAGE58_I9@PURE_QUANTA.GENOA_SP5(CHIPS)':
 'VSS_AJ42': CDS_PINID='VSS_AJ42';
NODE_NAME     U26 AJ45
 '@T6G_MB_LIB.T6G(SCH_1):PAGE58_I9@PURE_QUANTA.GENOA_SP5(CHIPS)':
 'VSS_AJ45': CDS_PINID='VSS_AJ45';
NODE_NAME     U26 AJ48
 '@T6G_MB_LIB.T6G(SCH_1):PAGE58_I9@PURE_QUANTA.GENOA_SP5(CHIPS)':
 'VSS_AJ48': CDS_PINID='VSS_AJ48';
NODE_NAME     U26 AJ51
 '@T6G_MB_LIB.T6G(SCH_1):PAGE58_I9@PURE_QUANTA.GENOA_SP5(CHIPS)':
 'VSS_AJ51': CDS_PINID='VSS_AJ51';
NODE_NAME     U26 AJ54
 '@T6G_MB_LIB.T6G(SCH_1):PAGE58_I9@PURE_QUANTA.GENOA_SP5(CHIPS)':
 'VSS_AJ54': CDS_PINID='VSS_AJ54';
NODE_NAME     U26 AJ56
 '@T6G_MB_LIB.T6G(SCH_1):PAGE58_I9@PURE_QUANTA.GENOA_SP5(CHIPS)':
 'VSS_AJ56': CDS_PINID='VSS_AJ56';
NODE_NAME     U26 AJ61
 '@T6G_MB_LIB.T6G(SCH_1):PAGE58_I9@PURE_QUANTA.GENOA_SP5(CHIPS)':
 'VSS_AJ61': CDS_PINID='VSS_AJ61';
NODE_NAME     U26 AJ63
 '@T6G_MB_LIB.T6G(SCH_1):PAGE58_I9@PURE_QUANTA.GENOA_SP5(CHIPS)':
 'VSS_AJ63': CDS_PINID='VSS_AJ63';
NODE_NAME     U26 AJ68
 '@T6G_MB_LIB.T6G(SCH_1):PAGE58_I9@PURE_QUANTA.GENOA_SP5(CHIPS)':
 'VSS_AJ68': CDS_PINID='VSS_AJ68';
NODE_NAME     U26 AJ70
 '@T6G_MB_LIB.T6G(SCH_1):PAGE58_I9@PURE_QUANTA.GENOA_SP5(CHIPS)':
 'VSS_AJ70': CDS_PINID='VSS_AJ70';
NODE_NAME     U26 AJ75
 '@T6G_MB_LIB.T6G(SCH_1):PAGE58_I9@PURE_QUANTA.GENOA_SP5(CHIPS)':
 'VSS_AJ75': CDS_PINID='VSS_AJ75';
NODE_NAME     U26 AK3
 '@T6G_MB_LIB.T6G(SCH_1):PAGE58_I9@PURE_QUANTA.GENOA_SP5(CHIPS)':
 'VSS_AK3': CDS_PINID='VSS_AK3';
NODE_NAME     U26 AK5
 '@T6G_MB_LIB.T6G(SCH_1):PAGE58_I9@PURE_QUANTA.GENOA_SP5(CHIPS)':
 'VSS_AK5': CDS_PINID='VSS_AK5';
NODE_NAME     U26 AK8
 '@T6G_MB_LIB.T6G(SCH_1):PAGE58_I9@PURE_QUANTA.GENOA_SP5(CHIPS)':
 'VSS_AK8': CDS_PINID='VSS_AK8';
NODE_NAME     U26 AK10
 '@T6G_MB_LIB.T6G(SCH_1):PAGE58_I9@PURE_QUANTA.GENOA_SP5(CHIPS)':
 'VSS_AK10': CDS_PINID='VSS_AK10';
NODE_NAME     U26 AK12
 '@T6G_MB_LIB.T6G(SCH_1):PAGE58_I9@PURE_QUANTA.GENOA_SP5(CHIPS)':
 'VSS_AK12': CDS_PINID='VSS_AK12';
NODE_NAME     U26 AK15
 '@T6G_MB_LIB.T6G(SCH_1):PAGE58_I9@PURE_QUANTA.GENOA_SP5(CHIPS)':
 'VSS_AK15': CDS_PINID='VSS_AK15';
NODE_NAME     U26 AK17
 '@T6G_MB_LIB.T6G(SCH_1):PAGE58_I9@PURE_QUANTA.GENOA_SP5(CHIPS)':
 'VSS_AK17': CDS_PINID='VSS_AK17';
NODE_NAME     U26 AK19
 '@T6G_MB_LIB.T6G(SCH_1):PAGE58_I9@PURE_QUANTA.GENOA_SP5(CHIPS)':
 'VSS_AK19': CDS_PINID='VSS_AK19';
NODE_NAME     U26 AK22
 '@T6G_MB_LIB.T6G(SCH_1):PAGE58_I9@PURE_QUANTA.GENOA_SP5(CHIPS)':
 'VSS_AK22': CDS_PINID='VSS_AK22';
NODE_NAME     U26 AK25
 '@T6G_MB_LIB.T6G(SCH_1):PAGE58_I9@PURE_QUANTA.GENOA_SP5(CHIPS)':
 'VSS_AK25': CDS_PINID='VSS_AK25';
NODE_NAME     U26 AK28
 '@T6G_MB_LIB.T6G(SCH_1):PAGE58_I9@PURE_QUANTA.GENOA_SP5(CHIPS)':
 'VSS_AK28': CDS_PINID='VSS_AK28';
NODE_NAME     U26 AK31
 '@T6G_MB_LIB.T6G(SCH_1):PAGE58_I9@PURE_QUANTA.GENOA_SP5(CHIPS)':
 'VSS_AK31': CDS_PINID='VSS_AK31';
NODE_NAME     U26 AK34
 '@T6G_MB_LIB.T6G(SCH_1):PAGE58_I9@PURE_QUANTA.GENOA_SP5(CHIPS)':
 'VSS_AK34': CDS_PINID='VSS_AK34';
NODE_NAME     U26 AK37
 '@T6G_MB_LIB.T6G(SCH_1):PAGE58_I9@PURE_QUANTA.GENOA_SP5(CHIPS)':
 'VSS_AK37': CDS_PINID='VSS_AK37';
NODE_NAME     U26 AK39
 '@T6G_MB_LIB.T6G(SCH_1):PAGE58_I9@PURE_QUANTA.GENOA_SP5(CHIPS)':
 'VSS_AK39': CDS_PINID='VSS_AK39';
NODE_NAME     U26 AK42
 '@T6G_MB_LIB.T6G(SCH_1):PAGE58_I9@PURE_QUANTA.GENOA_SP5(CHIPS)':
 'VSS_AK42': CDS_PINID='VSS_AK42';
NODE_NAME     U26 AK45
 '@T6G_MB_LIB.T6G(SCH_1):PAGE58_I9@PURE_QUANTA.GENOA_SP5(CHIPS)':
 'VSS_AK45': CDS_PINID='VSS_AK45';
NODE_NAME     U26 AK48
 '@T6G_MB_LIB.T6G(SCH_1):PAGE58_I9@PURE_QUANTA.GENOA_SP5(CHIPS)':
 'VSS_AK48': CDS_PINID='VSS_AK48';
NODE_NAME     U26 AK51
 '@T6G_MB_LIB.T6G(SCH_1):PAGE58_I9@PURE_QUANTA.GENOA_SP5(CHIPS)':
 'VSS_AK51': CDS_PINID='VSS_AK51';
NODE_NAME     U26 AK54
 '@T6G_MB_LIB.T6G(SCH_1):PAGE58_I9@PURE_QUANTA.GENOA_SP5(CHIPS)':
 'VSS_AK54': CDS_PINID='VSS_AK54';
NODE_NAME     U26 AK57
 '@T6G_MB_LIB.T6G(SCH_1):PAGE58_I9@PURE_QUANTA.GENOA_SP5(CHIPS)':
 'VSS_AK57': CDS_PINID='VSS_AK57';
NODE_NAME     U26 AK59
 '@T6G_MB_LIB.T6G(SCH_1):PAGE58_I9@PURE_QUANTA.GENOA_SP5(CHIPS)':
 'VSS_AK59': CDS_PINID='VSS_AK59';
NODE_NAME     U26 AK61
 '@T6G_MB_LIB.T6G(SCH_1):PAGE58_I9@PURE_QUANTA.GENOA_SP5(CHIPS)':
 'VSS_AK61': CDS_PINID='VSS_AK61';
NODE_NAME     U26 AK64
 '@T6G_MB_LIB.T6G(SCH_1):PAGE58_I9@PURE_QUANTA.GENOA_SP5(CHIPS)':
 'VSS_AK64': CDS_PINID='VSS_AK64';
NODE_NAME     U26 AK66
 '@T6G_MB_LIB.T6G(SCH_1):PAGE58_I9@PURE_QUANTA.GENOA_SP5(CHIPS)':
 'VSS_AK66': CDS_PINID='VSS_AK66';
NODE_NAME     U26 AK68
 '@T6G_MB_LIB.T6G(SCH_1):PAGE58_I9@PURE_QUANTA.GENOA_SP5(CHIPS)':
 'VSS_AK68': CDS_PINID='VSS_AK68';
NODE_NAME     U26 AK71
 '@T6G_MB_LIB.T6G(SCH_1):PAGE58_I9@PURE_QUANTA.GENOA_SP5(CHIPS)':
 'VSS_AK71': CDS_PINID='VSS_AK71';
NODE_NAME     U26 AK73
 '@T6G_MB_LIB.T6G(SCH_1):PAGE58_I9@PURE_QUANTA.GENOA_SP5(CHIPS)':
 'VSS_AK73': CDS_PINID='VSS_AK73';
NODE_NAME     U26 AL1
 '@T6G_MB_LIB.T6G(SCH_1):PAGE58_I9@PURE_QUANTA.GENOA_SP5(CHIPS)':
 'VSS_AL1': CDS_PINID='VSS_AL1';
NODE_NAME     U26 AL4
 '@T6G_MB_LIB.T6G(SCH_1):PAGE58_I9@PURE_QUANTA.GENOA_SP5(CHIPS)':
 'VSS_AL4': CDS_PINID='VSS_AL4';
NODE_NAME     U26 AL6
 '@T6G_MB_LIB.T6G(SCH_1):PAGE58_I9@PURE_QUANTA.GENOA_SP5(CHIPS)':
 'VSS_AL6': CDS_PINID='VSS_AL6';
NODE_NAME     U26 AL8
 '@T6G_MB_LIB.T6G(SCH_1):PAGE58_I9@PURE_QUANTA.GENOA_SP5(CHIPS)':
 'VSS_AL8': CDS_PINID='VSS_AL8';
NODE_NAME     U26 AL11
 '@T6G_MB_LIB.T6G(SCH_1):PAGE58_I9@PURE_QUANTA.GENOA_SP5(CHIPS)':
 'VSS_AL11': CDS_PINID='VSS_AL11';
NODE_NAME     U26 AL13
 '@T6G_MB_LIB.T6G(SCH_1):PAGE58_I9@PURE_QUANTA.GENOA_SP5(CHIPS)':
 'VSS_AL13': CDS_PINID='VSS_AL13';
NODE_NAME     U26 AL15
 '@T6G_MB_LIB.T6G(SCH_1):PAGE58_I9@PURE_QUANTA.GENOA_SP5(CHIPS)':
 'VSS_AL15': CDS_PINID='VSS_AL15';
NODE_NAME     U26 AL18
 '@T6G_MB_LIB.T6G(SCH_1):PAGE58_I9@PURE_QUANTA.GENOA_SP5(CHIPS)':
 'VSS_AL18': CDS_PINID='VSS_AL18';
NODE_NAME     U26 AL20
 '@T6G_MB_LIB.T6G(SCH_1):PAGE58_I9@PURE_QUANTA.GENOA_SP5(CHIPS)':
 'VSS_AL20': CDS_PINID='VSS_AL20';
NODE_NAME     U26 AL22
 '@T6G_MB_LIB.T6G(SCH_1):PAGE58_I9@PURE_QUANTA.GENOA_SP5(CHIPS)':
 'VSS_AL22': CDS_PINID='VSS_AL22';
NODE_NAME     U26 AL25
 '@T6G_MB_LIB.T6G(SCH_1):PAGE58_I9@PURE_QUANTA.GENOA_SP5(CHIPS)':
 'VSS_AL25': CDS_PINID='VSS_AL25';
NODE_NAME     U26 AL28
 '@T6G_MB_LIB.T6G(SCH_1):PAGE58_I9@PURE_QUANTA.GENOA_SP5(CHIPS)':
 'VSS_AL28': CDS_PINID='VSS_AL28';
NODE_NAME     U26 AL31
 '@T6G_MB_LIB.T6G(SCH_1):PAGE58_I9@PURE_QUANTA.GENOA_SP5(CHIPS)':
 'VSS_AL31': CDS_PINID='VSS_AL31';
NODE_NAME     U26 AL34
 '@T6G_MB_LIB.T6G(SCH_1):PAGE58_I9@PURE_QUANTA.GENOA_SP5(CHIPS)':
 'VSS_AL34': CDS_PINID='VSS_AL34';
NODE_NAME     U26 AL42
 '@T6G_MB_LIB.T6G(SCH_1):PAGE58_I9@PURE_QUANTA.GENOA_SP5(CHIPS)':
 'VSS_AL42': CDS_PINID='VSS_AL42';
NODE_NAME     U26 AL45
 '@T6G_MB_LIB.T6G(SCH_1):PAGE58_I9@PURE_QUANTA.GENOA_SP5(CHIPS)':
 'VSS_AL45': CDS_PINID='VSS_AL45';
NODE_NAME     U26 AL48
 '@T6G_MB_LIB.T6G(SCH_1):PAGE58_I9@PURE_QUANTA.GENOA_SP5(CHIPS)':
 'VSS_AL48': CDS_PINID='VSS_AL48';
NODE_NAME     U26 AL51
 '@T6G_MB_LIB.T6G(SCH_1):PAGE58_I9@PURE_QUANTA.GENOA_SP5(CHIPS)':
 'VSS_AL51': CDS_PINID='VSS_AL51';
NODE_NAME     U26 AL54
 '@T6G_MB_LIB.T6G(SCH_1):PAGE58_I9@PURE_QUANTA.GENOA_SP5(CHIPS)':
 'VSS_AL54': CDS_PINID='VSS_AL54';
NODE_NAME     U26 AL56
 '@T6G_MB_LIB.T6G(SCH_1):PAGE58_I9@PURE_QUANTA.GENOA_SP5(CHIPS)':
 'VSS_AL56': CDS_PINID='VSS_AL56';
NODE_NAME     U26 AL58
 '@T6G_MB_LIB.T6G(SCH_1):PAGE58_I9@PURE_QUANTA.GENOA_SP5(CHIPS)':
 'VSS_AL58': CDS_PINID='VSS_AL58';
NODE_NAME     U26 AL61
 '@T6G_MB_LIB.T6G(SCH_1):PAGE58_I9@PURE_QUANTA.GENOA_SP5(CHIPS)':
 'VSS_AL61': CDS_PINID='VSS_AL61';
NODE_NAME     U26 AL63
 '@T6G_MB_LIB.T6G(SCH_1):PAGE58_I9@PURE_QUANTA.GENOA_SP5(CHIPS)':
 'VSS_AL63': CDS_PINID='VSS_AL63';
NODE_NAME     U26 AL65
 '@T6G_MB_LIB.T6G(SCH_1):PAGE58_I9@PURE_QUANTA.GENOA_SP5(CHIPS)':
 'VSS_AL65': CDS_PINID='VSS_AL65';
NODE_NAME     U26 AL68
 '@T6G_MB_LIB.T6G(SCH_1):PAGE58_I9@PURE_QUANTA.GENOA_SP5(CHIPS)':
 'VSS_AL68': CDS_PINID='VSS_AL68';
NODE_NAME     U26 AL70
 '@T6G_MB_LIB.T6G(SCH_1):PAGE58_I9@PURE_QUANTA.GENOA_SP5(CHIPS)':
 'VSS_AL70': CDS_PINID='VSS_AL70';
NODE_NAME     U26 AL72
 '@T6G_MB_LIB.T6G(SCH_1):PAGE58_I9@PURE_QUANTA.GENOA_SP5(CHIPS)':
 'VSS_AL72': CDS_PINID='VSS_AL72';
NODE_NAME     U26 AL75
 '@T6G_MB_LIB.T6G(SCH_1):PAGE58_I9@PURE_QUANTA.GENOA_SP5(CHIPS)':
 'VSS_AL75': CDS_PINID='VSS_AL75';
NODE_NAME     U26 AM3
 '@T6G_MB_LIB.T6G(SCH_1):PAGE58_I9@PURE_QUANTA.GENOA_SP5(CHIPS)':
 'VSS_AM3': CDS_PINID='VSS_AM3';
NODE_NAME     U26 AM8
 '@T6G_MB_LIB.T6G(SCH_1):PAGE58_I9@PURE_QUANTA.GENOA_SP5(CHIPS)':
 'VSS_AM8': CDS_PINID='VSS_AM8';
NODE_NAME     U26 AM10
 '@T6G_MB_LIB.T6G(SCH_1):PAGE58_I9@PURE_QUANTA.GENOA_SP5(CHIPS)':
 'VSS_AM10': CDS_PINID='VSS_AM10';
NODE_NAME     U26 AM15
 '@T6G_MB_LIB.T6G(SCH_1):PAGE58_I9@PURE_QUANTA.GENOA_SP5(CHIPS)':
 'VSS_AM15': CDS_PINID='VSS_AM15';
NODE_NAME     U26 AM17
 '@T6G_MB_LIB.T6G(SCH_1):PAGE58_I9@PURE_QUANTA.GENOA_SP5(CHIPS)':
 'VSS_AM17': CDS_PINID='VSS_AM17';
NODE_NAME     U26 AM23
 '@T6G_MB_LIB.T6G(SCH_1):PAGE58_I9@PURE_QUANTA.GENOA_SP5(CHIPS)':
 'VSS_AM23': CDS_PINID='VSS_AM23';
NODE_NAME     U26 AM24
 '@T6G_MB_LIB.T6G(SCH_1):PAGE58_I9@PURE_QUANTA.GENOA_SP5(CHIPS)':
 'VSS_AM24': CDS_PINID='VSS_AM24';
NODE_NAME     U26 AM25
 '@T6G_MB_LIB.T6G(SCH_1):PAGE58_I9@PURE_QUANTA.GENOA_SP5(CHIPS)':
 'VSS_AM25': CDS_PINID='VSS_AM25';
NODE_NAME     U26 AM26
 '@T6G_MB_LIB.T6G(SCH_1):PAGE58_I9@PURE_QUANTA.GENOA_SP5(CHIPS)':
 'VSS_AM26': CDS_PINID='VSS_AM26';
NODE_NAME     U26 AM27
 '@T6G_MB_LIB.T6G(SCH_1):PAGE58_I9@PURE_QUANTA.GENOA_SP5(CHIPS)':
 'VSS_AM27': CDS_PINID='VSS_AM27';
NODE_NAME     U26 AM28
 '@T6G_MB_LIB.T6G(SCH_1):PAGE58_I9@PURE_QUANTA.GENOA_SP5(CHIPS)':
 'VSS_AM28': CDS_PINID='VSS_AM28';
NODE_NAME     U26 AM29
 '@T6G_MB_LIB.T6G(SCH_1):PAGE58_I9@PURE_QUANTA.GENOA_SP5(CHIPS)':
 'VSS_AM29': CDS_PINID='VSS_AM29';
NODE_NAME     U26 AM30
 '@T6G_MB_LIB.T6G(SCH_1):PAGE58_I9@PURE_QUANTA.GENOA_SP5(CHIPS)':
 'VSS_AM30': CDS_PINID='VSS_AM30';
NODE_NAME     U26 AM31
 '@T6G_MB_LIB.T6G(SCH_1):PAGE58_I9@PURE_QUANTA.GENOA_SP5(CHIPS)':
 'VSS_AM31': CDS_PINID='VSS_AM31';
NODE_NAME     U26 AM32
 '@T6G_MB_LIB.T6G(SCH_1):PAGE58_I9@PURE_QUANTA.GENOA_SP5(CHIPS)':
 'VSS_AM32': CDS_PINID='VSS_AM32';
NODE_NAME     U26 AM33
 '@T6G_MB_LIB.T6G(SCH_1):PAGE58_I9@PURE_QUANTA.GENOA_SP5(CHIPS)':
 'VSS_AM33': CDS_PINID='VSS_AM33';
NODE_NAME     U26 AM34
 '@T6G_MB_LIB.T6G(SCH_1):PAGE58_I9@PURE_QUANTA.GENOA_SP5(CHIPS)':
 'VSS_AM34': CDS_PINID='VSS_AM34';
NODE_NAME     U26 AM39
 '@T6G_MB_LIB.T6G(SCH_1):PAGE58_I9@PURE_QUANTA.GENOA_SP5(CHIPS)':
 'VSS_AM39': CDS_PINID='VSS_AM39';
NODE_NAME     U26 AA1
 '@T6G_MB_LIB.T6G(SCH_1):PAGE58_I12@PURE_QUANTA.GENOA_SP5(CHIPS)':
 'VSS_AA1': CDS_PINID='VSS_AA1';
NODE_NAME     U26 AA4
 '@T6G_MB_LIB.T6G(SCH_1):PAGE58_I12@PURE_QUANTA.GENOA_SP5(CHIPS)':
 'VSS_AA4': CDS_PINID='VSS_AA4';
NODE_NAME     U26 AA6
 '@T6G_MB_LIB.T6G(SCH_1):PAGE58_I12@PURE_QUANTA.GENOA_SP5(CHIPS)':
 'VSS_AA6': CDS_PINID='VSS_AA6';
NODE_NAME     U26 AA8
 '@T6G_MB_LIB.T6G(SCH_1):PAGE58_I12@PURE_QUANTA.GENOA_SP5(CHIPS)':
 'VSS_AA8': CDS_PINID='VSS_AA8';
NODE_NAME     U26 AA11
 '@T6G_MB_LIB.T6G(SCH_1):PAGE58_I12@PURE_QUANTA.GENOA_SP5(CHIPS)':
 'VSS_AA11': CDS_PINID='VSS_AA11';
NODE_NAME     U26 AA13
 '@T6G_MB_LIB.T6G(SCH_1):PAGE58_I12@PURE_QUANTA.GENOA_SP5(CHIPS)':
 'VSS_AA13': CDS_PINID='VSS_AA13';
NODE_NAME     U26 AA15
 '@T6G_MB_LIB.T6G(SCH_1):PAGE58_I12@PURE_QUANTA.GENOA_SP5(CHIPS)':
 'VSS_AA15': CDS_PINID='VSS_AA15';
NODE_NAME     U26 AA18
 '@T6G_MB_LIB.T6G(SCH_1):PAGE58_I12@PURE_QUANTA.GENOA_SP5(CHIPS)':
 'VSS_AA18': CDS_PINID='VSS_AA18';
NODE_NAME     U26 AA20
 '@T6G_MB_LIB.T6G(SCH_1):PAGE58_I12@PURE_QUANTA.GENOA_SP5(CHIPS)':
 'VSS_AA20': CDS_PINID='VSS_AA20';
NODE_NAME     U26 AA31
 '@T6G_MB_LIB.T6G(SCH_1):PAGE58_I12@PURE_QUANTA.GENOA_SP5(CHIPS)':
 'VSS_AA31': CDS_PINID='VSS_AA31';
NODE_NAME     U26 AA34
 '@T6G_MB_LIB.T6G(SCH_1):PAGE58_I12@PURE_QUANTA.GENOA_SP5(CHIPS)':
 'VSS_AA34': CDS_PINID='VSS_AA34';
NODE_NAME     U26 AA35
 '@T6G_MB_LIB.T6G(SCH_1):PAGE58_I12@PURE_QUANTA.GENOA_SP5(CHIPS)':
 'VSS_AA35': CDS_PINID='VSS_AA35';
NODE_NAME     U26 AA36
 '@T6G_MB_LIB.T6G(SCH_1):PAGE58_I12@PURE_QUANTA.GENOA_SP5(CHIPS)':
 'VSS_AA36': CDS_PINID='VSS_AA36';
NODE_NAME     U26 AA40
 '@T6G_MB_LIB.T6G(SCH_1):PAGE58_I12@PURE_QUANTA.GENOA_SP5(CHIPS)':
 'VSS_AA40': CDS_PINID='VSS_AA40';
NODE_NAME     U26 AA41
 '@T6G_MB_LIB.T6G(SCH_1):PAGE58_I12@PURE_QUANTA.GENOA_SP5(CHIPS)':
 'VSS_AA41': CDS_PINID='VSS_AA41';
NODE_NAME     U26 AA45
 '@T6G_MB_LIB.T6G(SCH_1):PAGE58_I12@PURE_QUANTA.GENOA_SP5(CHIPS)':
 'VSS_AA45': CDS_PINID='VSS_AA45';
NODE_NAME     U26 AA56
 '@T6G_MB_LIB.T6G(SCH_1):PAGE58_I12@PURE_QUANTA.GENOA_SP5(CHIPS)':
 'VSS_AA56': CDS_PINID='VSS_AA56';
NODE_NAME     U26 AA58
 '@T6G_MB_LIB.T6G(SCH_1):PAGE58_I12@PURE_QUANTA.GENOA_SP5(CHIPS)':
 'VSS_AA58': CDS_PINID='VSS_AA58';
NODE_NAME     U26 AA61
 '@T6G_MB_LIB.T6G(SCH_1):PAGE58_I12@PURE_QUANTA.GENOA_SP5(CHIPS)':
 'VSS_AA61': CDS_PINID='VSS_AA61';
NODE_NAME     U26 AA63
 '@T6G_MB_LIB.T6G(SCH_1):PAGE58_I12@PURE_QUANTA.GENOA_SP5(CHIPS)':
 'VSS_AA63': CDS_PINID='VSS_AA63';
NODE_NAME     U26 AA65
 '@T6G_MB_LIB.T6G(SCH_1):PAGE58_I12@PURE_QUANTA.GENOA_SP5(CHIPS)':
 'VSS_AA65': CDS_PINID='VSS_AA65';
NODE_NAME     U26 AA68
 '@T6G_MB_LIB.T6G(SCH_1):PAGE58_I12@PURE_QUANTA.GENOA_SP5(CHIPS)':
 'VSS_AA68': CDS_PINID='VSS_AA68';
NODE_NAME     U26 AA70
 '@T6G_MB_LIB.T6G(SCH_1):PAGE58_I12@PURE_QUANTA.GENOA_SP5(CHIPS)':
 'VSS_AA70': CDS_PINID='VSS_AA70';
NODE_NAME     U26 AA75
 '@T6G_MB_LIB.T6G(SCH_1):PAGE58_I12@PURE_QUANTA.GENOA_SP5(CHIPS)':
 'VSS_AA75': CDS_PINID='VSS_AA75';
NODE_NAME     U26 AB3
 '@T6G_MB_LIB.T6G(SCH_1):PAGE58_I12@PURE_QUANTA.GENOA_SP5(CHIPS)':
 'VSS_AB3': CDS_PINID='VSS_AB3';
NODE_NAME     U26 AB5
 '@T6G_MB_LIB.T6G(SCH_1):PAGE58_I12@PURE_QUANTA.GENOA_SP5(CHIPS)':
 'VSS_AB5': CDS_PINID='VSS_AB5';
NODE_NAME     U26 AB8
 '@T6G_MB_LIB.T6G(SCH_1):PAGE58_I12@PURE_QUANTA.GENOA_SP5(CHIPS)':
 'VSS_AB8': CDS_PINID='VSS_AB8';
NODE_NAME     U26 AB10
 '@T6G_MB_LIB.T6G(SCH_1):PAGE58_I12@PURE_QUANTA.GENOA_SP5(CHIPS)':
 'VSS_AB10': CDS_PINID='VSS_AB10';
NODE_NAME     U26 AB12
 '@T6G_MB_LIB.T6G(SCH_1):PAGE58_I12@PURE_QUANTA.GENOA_SP5(CHIPS)':
 'VSS_AB12': CDS_PINID='VSS_AB12';
NODE_NAME     U26 AB15
 '@T6G_MB_LIB.T6G(SCH_1):PAGE58_I12@PURE_QUANTA.GENOA_SP5(CHIPS)':
 'VSS_AB15': CDS_PINID='VSS_AB15';
NODE_NAME     U26 AB17
 '@T6G_MB_LIB.T6G(SCH_1):PAGE58_I12@PURE_QUANTA.GENOA_SP5(CHIPS)':
 'VSS_AB17': CDS_PINID='VSS_AB17';
NODE_NAME     U26 AB19
 '@T6G_MB_LIB.T6G(SCH_1):PAGE58_I12@PURE_QUANTA.GENOA_SP5(CHIPS)':
 'VSS_AB19': CDS_PINID='VSS_AB19';
NODE_NAME     U26 AB22
 '@T6G_MB_LIB.T6G(SCH_1):PAGE58_I12@PURE_QUANTA.GENOA_SP5(CHIPS)':
 'VSS_AB22': CDS_PINID='VSS_AB22';
NODE_NAME     U26 AB25
 '@T6G_MB_LIB.T6G(SCH_1):PAGE58_I12@PURE_QUANTA.GENOA_SP5(CHIPS)':
 'VSS_AB25': CDS_PINID='VSS_AB25';
NODE_NAME     U26 AB28
 '@T6G_MB_LIB.T6G(SCH_1):PAGE58_I12@PURE_QUANTA.GENOA_SP5(CHIPS)':
 'VSS_AB28': CDS_PINID='VSS_AB28';
NODE_NAME     U26 AB31
 '@T6G_MB_LIB.T6G(SCH_1):PAGE58_I12@PURE_QUANTA.GENOA_SP5(CHIPS)':
 'VSS_AB31': CDS_PINID='VSS_AB31';
NODE_NAME     U26 AB34
 '@T6G_MB_LIB.T6G(SCH_1):PAGE58_I12@PURE_QUANTA.GENOA_SP5(CHIPS)':
 'VSS_AB34': CDS_PINID='VSS_AB34';
NODE_NAME     U26 AB37
 '@T6G_MB_LIB.T6G(SCH_1):PAGE58_I12@PURE_QUANTA.GENOA_SP5(CHIPS)':
 'VSS_AB37': CDS_PINID='VSS_AB37';
NODE_NAME     U26 AB39
 '@T6G_MB_LIB.T6G(SCH_1):PAGE58_I12@PURE_QUANTA.GENOA_SP5(CHIPS)':
 'VSS_AB39': CDS_PINID='VSS_AB39';
NODE_NAME     U26 AB42
 '@T6G_MB_LIB.T6G(SCH_1):PAGE58_I12@PURE_QUANTA.GENOA_SP5(CHIPS)':
 'VSS_AB42': CDS_PINID='VSS_AB42';
NODE_NAME     U26 AB45
 '@T6G_MB_LIB.T6G(SCH_1):PAGE58_I12@PURE_QUANTA.GENOA_SP5(CHIPS)':
 'VSS_AB45': CDS_PINID='VSS_AB45';
NODE_NAME     U26 AB48
 '@T6G_MB_LIB.T6G(SCH_1):PAGE58_I12@PURE_QUANTA.GENOA_SP5(CHIPS)':
 'VSS_AB48': CDS_PINID='VSS_AB48';
NODE_NAME     U26 AB51
 '@T6G_MB_LIB.T6G(SCH_1):PAGE58_I12@PURE_QUANTA.GENOA_SP5(CHIPS)':
 'VSS_AB51': CDS_PINID='VSS_AB51';
NODE_NAME     U26 AB54
 '@T6G_MB_LIB.T6G(SCH_1):PAGE58_I12@PURE_QUANTA.GENOA_SP5(CHIPS)':
 'VSS_AB54': CDS_PINID='VSS_AB54';
NODE_NAME     U26 AB57
 '@T6G_MB_LIB.T6G(SCH_1):PAGE58_I12@PURE_QUANTA.GENOA_SP5(CHIPS)':
 'VSS_AB57': CDS_PINID='VSS_AB57';
NODE_NAME     U26 AB59
 '@T6G_MB_LIB.T6G(SCH_1):PAGE58_I12@PURE_QUANTA.GENOA_SP5(CHIPS)':
 'VSS_AB59': CDS_PINID='VSS_AB59';
NODE_NAME     U26 AB61
 '@T6G_MB_LIB.T6G(SCH_1):PAGE58_I12@PURE_QUANTA.GENOA_SP5(CHIPS)':
 'VSS_AB61': CDS_PINID='VSS_AB61';
NODE_NAME     U26 AB64
 '@T6G_MB_LIB.T6G(SCH_1):PAGE58_I12@PURE_QUANTA.GENOA_SP5(CHIPS)':
 'VSS_AB64': CDS_PINID='VSS_AB64';
NODE_NAME     U26 AB66
 '@T6G_MB_LIB.T6G(SCH_1):PAGE58_I12@PURE_QUANTA.GENOA_SP5(CHIPS)':
 'VSS_AB66': CDS_PINID='VSS_AB66';
NODE_NAME     U26 AB68
 '@T6G_MB_LIB.T6G(SCH_1):PAGE58_I12@PURE_QUANTA.GENOA_SP5(CHIPS)':
 'VSS_AB68': CDS_PINID='VSS_AB68';
NODE_NAME     U26 AB71
 '@T6G_MB_LIB.T6G(SCH_1):PAGE58_I12@PURE_QUANTA.GENOA_SP5(CHIPS)':
 'VSS_AB71': CDS_PINID='VSS_AB71';
NODE_NAME     U26 AB73
 '@T6G_MB_LIB.T6G(SCH_1):PAGE58_I12@PURE_QUANTA.GENOA_SP5(CHIPS)':
 'VSS_AB73': CDS_PINID='VSS_AB73';
NODE_NAME     U26 AC1
 '@T6G_MB_LIB.T6G(SCH_1):PAGE58_I12@PURE_QUANTA.GENOA_SP5(CHIPS)':
 'VSS_AC1': CDS_PINID='VSS_AC1';
NODE_NAME     U26 AC6
 '@T6G_MB_LIB.T6G(SCH_1):PAGE58_I12@PURE_QUANTA.GENOA_SP5(CHIPS)':
 'VSS_AC6': CDS_PINID='VSS_AC6';
NODE_NAME     U26 AC8
 '@T6G_MB_LIB.T6G(SCH_1):PAGE58_I12@PURE_QUANTA.GENOA_SP5(CHIPS)':
 'VSS_AC8': CDS_PINID='VSS_AC8';
NODE_NAME     U26 AC13
 '@T6G_MB_LIB.T6G(SCH_1):PAGE58_I12@PURE_QUANTA.GENOA_SP5(CHIPS)':
 'VSS_AC13': CDS_PINID='VSS_AC13';
NODE_NAME     U26 AC15
 '@T6G_MB_LIB.T6G(SCH_1):PAGE58_I12@PURE_QUANTA.GENOA_SP5(CHIPS)':
 'VSS_AC15': CDS_PINID='VSS_AC15';
NODE_NAME     U26 AC20
 '@T6G_MB_LIB.T6G(SCH_1):PAGE58_I12@PURE_QUANTA.GENOA_SP5(CHIPS)':
 'VSS_AC20': CDS_PINID='VSS_AC20';
NODE_NAME     U26 AC22
 '@T6G_MB_LIB.T6G(SCH_1):PAGE58_I12@PURE_QUANTA.GENOA_SP5(CHIPS)':
 'VSS_AC22': CDS_PINID='VSS_AC22';
NODE_NAME     U26 AC25
 '@T6G_MB_LIB.T6G(SCH_1):PAGE58_I12@PURE_QUANTA.GENOA_SP5(CHIPS)':
 'VSS_AC25': CDS_PINID='VSS_AC25';
NODE_NAME     U26 AC28
 '@T6G_MB_LIB.T6G(SCH_1):PAGE58_I12@PURE_QUANTA.GENOA_SP5(CHIPS)':
 'VSS_AC28': CDS_PINID='VSS_AC28';
NODE_NAME     U26 AC31
 '@T6G_MB_LIB.T6G(SCH_1):PAGE58_I12@PURE_QUANTA.GENOA_SP5(CHIPS)':
 'VSS_AC31': CDS_PINID='VSS_AC31';
NODE_NAME     U26 AC34
 '@T6G_MB_LIB.T6G(SCH_1):PAGE58_I12@PURE_QUANTA.GENOA_SP5(CHIPS)':
 'VSS_AC34': CDS_PINID='VSS_AC34';
NODE_NAME     U26 AC42
 '@T6G_MB_LIB.T6G(SCH_1):PAGE58_I12@PURE_QUANTA.GENOA_SP5(CHIPS)':
 'VSS_AC42': CDS_PINID='VSS_AC42';
NODE_NAME     U26 AC45
 '@T6G_MB_LIB.T6G(SCH_1):PAGE58_I12@PURE_QUANTA.GENOA_SP5(CHIPS)':
 'VSS_AC45': CDS_PINID='VSS_AC45';
NODE_NAME     U26 AC48
 '@T6G_MB_LIB.T6G(SCH_1):PAGE58_I12@PURE_QUANTA.GENOA_SP5(CHIPS)':
 'VSS_AC48': CDS_PINID='VSS_AC48';
NODE_NAME     U26 AC51
 '@T6G_MB_LIB.T6G(SCH_1):PAGE58_I12@PURE_QUANTA.GENOA_SP5(CHIPS)':
 'VSS_AC51': CDS_PINID='VSS_AC51';
NODE_NAME     U26 AC54
 '@T6G_MB_LIB.T6G(SCH_1):PAGE58_I12@PURE_QUANTA.GENOA_SP5(CHIPS)':
 'VSS_AC54': CDS_PINID='VSS_AC54';
NODE_NAME     U26 AC56
 '@T6G_MB_LIB.T6G(SCH_1):PAGE58_I12@PURE_QUANTA.GENOA_SP5(CHIPS)':
 'VSS_AC56': CDS_PINID='VSS_AC56';
NODE_NAME     U26 AC61
 '@T6G_MB_LIB.T6G(SCH_1):PAGE58_I12@PURE_QUANTA.GENOA_SP5(CHIPS)':
 'VSS_AC61': CDS_PINID='VSS_AC61';
NODE_NAME     U26 AC63
 '@T6G_MB_LIB.T6G(SCH_1):PAGE58_I12@PURE_QUANTA.GENOA_SP5(CHIPS)':
 'VSS_AC63': CDS_PINID='VSS_AC63';
NODE_NAME     U26 AC68
 '@T6G_MB_LIB.T6G(SCH_1):PAGE58_I12@PURE_QUANTA.GENOA_SP5(CHIPS)':
 'VSS_AC68': CDS_PINID='VSS_AC68';
NODE_NAME     U26 AC70
 '@T6G_MB_LIB.T6G(SCH_1):PAGE58_I12@PURE_QUANTA.GENOA_SP5(CHIPS)':
 'VSS_AC70': CDS_PINID='VSS_AC70';
NODE_NAME     U26 AC75
 '@T6G_MB_LIB.T6G(SCH_1):PAGE58_I12@PURE_QUANTA.GENOA_SP5(CHIPS)':
 'VSS_AC75': CDS_PINID='VSS_AC75';
NODE_NAME     U26 AD3
 '@T6G_MB_LIB.T6G(SCH_1):PAGE58_I12@PURE_QUANTA.GENOA_SP5(CHIPS)':
 'VSS_AD3': CDS_PINID='VSS_AD3';
NODE_NAME     U26 AD5
 '@T6G_MB_LIB.T6G(SCH_1):PAGE58_I12@PURE_QUANTA.GENOA_SP5(CHIPS)':
 'VSS_AD5': CDS_PINID='VSS_AD5';
NODE_NAME     U26 AD8
 '@T6G_MB_LIB.T6G(SCH_1):PAGE58_I12@PURE_QUANTA.GENOA_SP5(CHIPS)':
 'VSS_AD8': CDS_PINID='VSS_AD8';
NODE_NAME     U26 AD10
 '@T6G_MB_LIB.T6G(SCH_1):PAGE58_I12@PURE_QUANTA.GENOA_SP5(CHIPS)':
 'VSS_AD10': CDS_PINID='VSS_AD10';
NODE_NAME     U26 AD12
 '@T6G_MB_LIB.T6G(SCH_1):PAGE58_I12@PURE_QUANTA.GENOA_SP5(CHIPS)':
 'VSS_AD12': CDS_PINID='VSS_AD12';
NODE_NAME     U26 AD15
 '@T6G_MB_LIB.T6G(SCH_1):PAGE58_I12@PURE_QUANTA.GENOA_SP5(CHIPS)':
 'VSS_AD15': CDS_PINID='VSS_AD15';
NODE_NAME     U26 AD17
 '@T6G_MB_LIB.T6G(SCH_1):PAGE58_I12@PURE_QUANTA.GENOA_SP5(CHIPS)':
 'VSS_AD17': CDS_PINID='VSS_AD17';
NODE_NAME     U26 AD19
 '@T6G_MB_LIB.T6G(SCH_1):PAGE58_I12@PURE_QUANTA.GENOA_SP5(CHIPS)':
 'VSS_AD19': CDS_PINID='VSS_AD19';
NODE_NAME     U26 AD23
 '@T6G_MB_LIB.T6G(SCH_1):PAGE58_I12@PURE_QUANTA.GENOA_SP5(CHIPS)':
 'VSS_AD23': CDS_PINID='VSS_AD23';
NODE_NAME     U26 AD24
 '@T6G_MB_LIB.T6G(SCH_1):PAGE58_I12@PURE_QUANTA.GENOA_SP5(CHIPS)':
 'VSS_AD24': CDS_PINID='VSS_AD24';
NODE_NAME     U26 AD25
 '@T6G_MB_LIB.T6G(SCH_1):PAGE58_I12@PURE_QUANTA.GENOA_SP5(CHIPS)':
 'VSS_AD25': CDS_PINID='VSS_AD25';
NODE_NAME     U26 AD26
 '@T6G_MB_LIB.T6G(SCH_1):PAGE58_I12@PURE_QUANTA.GENOA_SP5(CHIPS)':
 'VSS_AD26': CDS_PINID='VSS_AD26';
NODE_NAME     U26 AD27
 '@T6G_MB_LIB.T6G(SCH_1):PAGE58_I12@PURE_QUANTA.GENOA_SP5(CHIPS)':
 'VSS_AD27': CDS_PINID='VSS_AD27';
NODE_NAME     U26 AD28
 '@T6G_MB_LIB.T6G(SCH_1):PAGE58_I12@PURE_QUANTA.GENOA_SP5(CHIPS)':
 'VSS_AD28': CDS_PINID='VSS_AD28';
NODE_NAME     U26 AD29
 '@T6G_MB_LIB.T6G(SCH_1):PAGE58_I12@PURE_QUANTA.GENOA_SP5(CHIPS)':
 'VSS_AD29': CDS_PINID='VSS_AD29';
NODE_NAME     U26 AD30
 '@T6G_MB_LIB.T6G(SCH_1):PAGE58_I12@PURE_QUANTA.GENOA_SP5(CHIPS)':
 'VSS_AD30': CDS_PINID='VSS_AD30';
NODE_NAME     U26 AD32
 '@T6G_MB_LIB.T6G(SCH_1):PAGE58_I12@PURE_QUANTA.GENOA_SP5(CHIPS)':
 'VSS_AD32': CDS_PINID='VSS_AD32';
NODE_NAME     U26 AD33
 '@T6G_MB_LIB.T6G(SCH_1):PAGE58_I12@PURE_QUANTA.GENOA_SP5(CHIPS)':
 'VSS_AD33': CDS_PINID='VSS_AD33';
NODE_NAME     U26 AD34
 '@T6G_MB_LIB.T6G(SCH_1):PAGE58_I12@PURE_QUANTA.GENOA_SP5(CHIPS)':
 'VSS_AD34': CDS_PINID='VSS_AD34';
NODE_NAME     U26 AD37
 '@T6G_MB_LIB.T6G(SCH_1):PAGE58_I12@PURE_QUANTA.GENOA_SP5(CHIPS)':
 'VSS_AD37': CDS_PINID='VSS_AD37';
NODE_NAME     U26 AD39
 '@T6G_MB_LIB.T6G(SCH_1):PAGE58_I12@PURE_QUANTA.GENOA_SP5(CHIPS)':
 'VSS_AD39': CDS_PINID='VSS_AD39';
NODE_NAME     U26 AD42
 '@T6G_MB_LIB.T6G(SCH_1):PAGE58_I12@PURE_QUANTA.GENOA_SP5(CHIPS)':
 'VSS_AD42': CDS_PINID='VSS_AD42';
NODE_NAME     U26 AD43
 '@T6G_MB_LIB.T6G(SCH_1):PAGE58_I12@PURE_QUANTA.GENOA_SP5(CHIPS)':
 'VSS_AD43': CDS_PINID='VSS_AD43';
NODE_NAME     U26 AD44
 '@T6G_MB_LIB.T6G(SCH_1):PAGE58_I12@PURE_QUANTA.GENOA_SP5(CHIPS)':
 'VSS_AD44': CDS_PINID='VSS_AD44';
NODE_NAME     U26 AD45
 '@T6G_MB_LIB.T6G(SCH_1):PAGE58_I12@PURE_QUANTA.GENOA_SP5(CHIPS)':
 'VSS_AD45': CDS_PINID='VSS_AD45';
NODE_NAME     U26 AD46
 '@T6G_MB_LIB.T6G(SCH_1):PAGE58_I12@PURE_QUANTA.GENOA_SP5(CHIPS)':
 'VSS_AD46': CDS_PINID='VSS_AD46';
NODE_NAME     U26 AD47
 '@T6G_MB_LIB.T6G(SCH_1):PAGE58_I12@PURE_QUANTA.GENOA_SP5(CHIPS)':
 'VSS_AD47': CDS_PINID='VSS_AD47';
NODE_NAME     U26 AD48
 '@T6G_MB_LIB.T6G(SCH_1):PAGE58_I12@PURE_QUANTA.GENOA_SP5(CHIPS)':
 'VSS_AD48': CDS_PINID='VSS_AD48';
NODE_NAME     U26 T66
 '@T6G_MB_LIB.T6G(SCH_1):PAGE58_I12@PURE_QUANTA.GENOA_SP5(CHIPS)':
 'VSS_T66': CDS_PINID='VSS_T66';
NODE_NAME     U26 T68
 '@T6G_MB_LIB.T6G(SCH_1):PAGE58_I12@PURE_QUANTA.GENOA_SP5(CHIPS)':
 'VSS_T68': CDS_PINID='VSS_T68';
NODE_NAME     U26 T71
 '@T6G_MB_LIB.T6G(SCH_1):PAGE58_I12@PURE_QUANTA.GENOA_SP5(CHIPS)':
 'VSS_T71': CDS_PINID='VSS_T71';
NODE_NAME     U26 T73
 '@T6G_MB_LIB.T6G(SCH_1):PAGE58_I12@PURE_QUANTA.GENOA_SP5(CHIPS)':
 'VSS_T73': CDS_PINID='VSS_T73';
NODE_NAME     U26 U1
 '@T6G_MB_LIB.T6G(SCH_1):PAGE58_I12@PURE_QUANTA.GENOA_SP5(CHIPS)':
 'VSS_U1': CDS_PINID='VSS_U1';
NODE_NAME     U26 U6
 '@T6G_MB_LIB.T6G(SCH_1):PAGE58_I12@PURE_QUANTA.GENOA_SP5(CHIPS)':
 'VSS_U6': CDS_PINID='VSS_U6';
NODE_NAME     U26 U8
 '@T6G_MB_LIB.T6G(SCH_1):PAGE58_I12@PURE_QUANTA.GENOA_SP5(CHIPS)':
 'VSS_U8': CDS_PINID='VSS_U8';
NODE_NAME     U26 U13
 '@T6G_MB_LIB.T6G(SCH_1):PAGE58_I12@PURE_QUANTA.GENOA_SP5(CHIPS)':
 'VSS_U13': CDS_PINID='VSS_U13';
NODE_NAME     U26 U15
 '@T6G_MB_LIB.T6G(SCH_1):PAGE58_I12@PURE_QUANTA.GENOA_SP5(CHIPS)':
 'VSS_U15': CDS_PINID='VSS_U15';
NODE_NAME     U26 U20
 '@T6G_MB_LIB.T6G(SCH_1):PAGE58_I12@PURE_QUANTA.GENOA_SP5(CHIPS)':
 'VSS_U20': CDS_PINID='VSS_U20';
NODE_NAME     U26 U22
 '@T6G_MB_LIB.T6G(SCH_1):PAGE58_I12@PURE_QUANTA.GENOA_SP5(CHIPS)':
 'VSS_U22': CDS_PINID='VSS_U22';
NODE_NAME     U26 U25
 '@T6G_MB_LIB.T6G(SCH_1):PAGE58_I12@PURE_QUANTA.GENOA_SP5(CHIPS)':
 'VSS_U25': CDS_PINID='VSS_U25';
NODE_NAME     U26 U28
 '@T6G_MB_LIB.T6G(SCH_1):PAGE58_I12@PURE_QUANTA.GENOA_SP5(CHIPS)':
 'VSS_U28': CDS_PINID='VSS_U28';
NODE_NAME     U26 U31
 '@T6G_MB_LIB.T6G(SCH_1):PAGE58_I12@PURE_QUANTA.GENOA_SP5(CHIPS)':
 'VSS_U31': CDS_PINID='VSS_U31';
NODE_NAME     U26 U34
 '@T6G_MB_LIB.T6G(SCH_1):PAGE58_I12@PURE_QUANTA.GENOA_SP5(CHIPS)':
 'VSS_U34': CDS_PINID='VSS_U34';
NODE_NAME     U26 U42
 '@T6G_MB_LIB.T6G(SCH_1):PAGE58_I12@PURE_QUANTA.GENOA_SP5(CHIPS)':
 'VSS_U42': CDS_PINID='VSS_U42';
NODE_NAME     U26 U45
 '@T6G_MB_LIB.T6G(SCH_1):PAGE58_I12@PURE_QUANTA.GENOA_SP5(CHIPS)':
 'VSS_U45': CDS_PINID='VSS_U45';
NODE_NAME     U26 U48
 '@T6G_MB_LIB.T6G(SCH_1):PAGE58_I12@PURE_QUANTA.GENOA_SP5(CHIPS)':
 'VSS_U48': CDS_PINID='VSS_U48';
NODE_NAME     U26 U51
 '@T6G_MB_LIB.T6G(SCH_1):PAGE58_I12@PURE_QUANTA.GENOA_SP5(CHIPS)':
 'VSS_U51': CDS_PINID='VSS_U51';
NODE_NAME     U26 U54
 '@T6G_MB_LIB.T6G(SCH_1):PAGE58_I12@PURE_QUANTA.GENOA_SP5(CHIPS)':
 'VSS_U54': CDS_PINID='VSS_U54';
NODE_NAME     U26 U56
 '@T6G_MB_LIB.T6G(SCH_1):PAGE58_I12@PURE_QUANTA.GENOA_SP5(CHIPS)':
 'VSS_U56': CDS_PINID='VSS_U56';
NODE_NAME     U26 U61
 '@T6G_MB_LIB.T6G(SCH_1):PAGE58_I12@PURE_QUANTA.GENOA_SP5(CHIPS)':
 'VSS_U61': CDS_PINID='VSS_U61';
NODE_NAME     U26 U63
 '@T6G_MB_LIB.T6G(SCH_1):PAGE58_I12@PURE_QUANTA.GENOA_SP5(CHIPS)':
 'VSS_U63': CDS_PINID='VSS_U63';
NODE_NAME     U26 U68
 '@T6G_MB_LIB.T6G(SCH_1):PAGE58_I12@PURE_QUANTA.GENOA_SP5(CHIPS)':
 'VSS_U68': CDS_PINID='VSS_U68';
NODE_NAME     U26 U70
 '@T6G_MB_LIB.T6G(SCH_1):PAGE58_I12@PURE_QUANTA.GENOA_SP5(CHIPS)':
 'VSS_U70': CDS_PINID='VSS_U70';
NODE_NAME     U26 U75
 '@T6G_MB_LIB.T6G(SCH_1):PAGE58_I12@PURE_QUANTA.GENOA_SP5(CHIPS)':
 'VSS_U75': CDS_PINID='VSS_U75';
NODE_NAME     U26 V3
 '@T6G_MB_LIB.T6G(SCH_1):PAGE58_I12@PURE_QUANTA.GENOA_SP5(CHIPS)':
 'VSS_V3': CDS_PINID='VSS_V3';
NODE_NAME     U26 V5
 '@T6G_MB_LIB.T6G(SCH_1):PAGE58_I12@PURE_QUANTA.GENOA_SP5(CHIPS)':
 'VSS_V5': CDS_PINID='VSS_V5';
NODE_NAME     U26 V8
 '@T6G_MB_LIB.T6G(SCH_1):PAGE58_I12@PURE_QUANTA.GENOA_SP5(CHIPS)':
 'VSS_V8': CDS_PINID='VSS_V8';
NODE_NAME     U26 V10
 '@T6G_MB_LIB.T6G(SCH_1):PAGE58_I12@PURE_QUANTA.GENOA_SP5(CHIPS)':
 'VSS_V10': CDS_PINID='VSS_V10';
NODE_NAME     U26 V12
 '@T6G_MB_LIB.T6G(SCH_1):PAGE58_I12@PURE_QUANTA.GENOA_SP5(CHIPS)':
 'VSS_V12': CDS_PINID='VSS_V12';
NODE_NAME     U26 V15
 '@T6G_MB_LIB.T6G(SCH_1):PAGE58_I12@PURE_QUANTA.GENOA_SP5(CHIPS)':
 'VSS_V15': CDS_PINID='VSS_V15';
NODE_NAME     U26 V17
 '@T6G_MB_LIB.T6G(SCH_1):PAGE58_I12@PURE_QUANTA.GENOA_SP5(CHIPS)':
 'VSS_V17': CDS_PINID='VSS_V17';
NODE_NAME     U26 V19
 '@T6G_MB_LIB.T6G(SCH_1):PAGE58_I12@PURE_QUANTA.GENOA_SP5(CHIPS)':
 'VSS_V19': CDS_PINID='VSS_V19';
NODE_NAME     U26 V23
 '@T6G_MB_LIB.T6G(SCH_1):PAGE58_I12@PURE_QUANTA.GENOA_SP5(CHIPS)':
 'VSS_V23': CDS_PINID='VSS_V23';
NODE_NAME     U26 V24
 '@T6G_MB_LIB.T6G(SCH_1):PAGE58_I12@PURE_QUANTA.GENOA_SP5(CHIPS)':
 'VSS_V24': CDS_PINID='VSS_V24';
NODE_NAME     U26 V25
 '@T6G_MB_LIB.T6G(SCH_1):PAGE58_I12@PURE_QUANTA.GENOA_SP5(CHIPS)':
 'VSS_V25': CDS_PINID='VSS_V25';
NODE_NAME     U26 V26
 '@T6G_MB_LIB.T6G(SCH_1):PAGE58_I12@PURE_QUANTA.GENOA_SP5(CHIPS)':
 'VSS_V26': CDS_PINID='VSS_V26';
NODE_NAME     U26 V28
 '@T6G_MB_LIB.T6G(SCH_1):PAGE58_I12@PURE_QUANTA.GENOA_SP5(CHIPS)':
 'VSS_V28': CDS_PINID='VSS_V28';
NODE_NAME     U26 V29
 '@T6G_MB_LIB.T6G(SCH_1):PAGE58_I12@PURE_QUANTA.GENOA_SP5(CHIPS)':
 'VSS_V29': CDS_PINID='VSS_V29';
NODE_NAME     U26 V30
 '@T6G_MB_LIB.T6G(SCH_1):PAGE58_I12@PURE_QUANTA.GENOA_SP5(CHIPS)':
 'VSS_V30': CDS_PINID='VSS_V30';
NODE_NAME     U26 V31
 '@T6G_MB_LIB.T6G(SCH_1):PAGE58_I12@PURE_QUANTA.GENOA_SP5(CHIPS)':
 'VSS_V31': CDS_PINID='VSS_V31';
NODE_NAME     U26 V32
 '@T6G_MB_LIB.T6G(SCH_1):PAGE58_I12@PURE_QUANTA.GENOA_SP5(CHIPS)':
 'VSS_V32': CDS_PINID='VSS_V32';
NODE_NAME     U26 V33
 '@T6G_MB_LIB.T6G(SCH_1):PAGE58_I12@PURE_QUANTA.GENOA_SP5(CHIPS)':
 'VSS_V33': CDS_PINID='VSS_V33';
NODE_NAME     U26 V34
 '@T6G_MB_LIB.T6G(SCH_1):PAGE58_I12@PURE_QUANTA.GENOA_SP5(CHIPS)':
 'VSS_V34': CDS_PINID='VSS_V34';
NODE_NAME     U26 V37
 '@T6G_MB_LIB.T6G(SCH_1):PAGE58_I12@PURE_QUANTA.GENOA_SP5(CHIPS)':
 'VSS_V37': CDS_PINID='VSS_V37';
NODE_NAME     U26 V39
 '@T6G_MB_LIB.T6G(SCH_1):PAGE58_I12@PURE_QUANTA.GENOA_SP5(CHIPS)':
 'VSS_V39': CDS_PINID='VSS_V39';
NODE_NAME     U26 V42
 '@T6G_MB_LIB.T6G(SCH_1):PAGE58_I12@PURE_QUANTA.GENOA_SP5(CHIPS)':
 'VSS_V42': CDS_PINID='VSS_V42';
NODE_NAME     U26 V43
 '@T6G_MB_LIB.T6G(SCH_1):PAGE58_I12@PURE_QUANTA.GENOA_SP5(CHIPS)':
 'VSS_V43': CDS_PINID='VSS_V43';
NODE_NAME     U26 V44
 '@T6G_MB_LIB.T6G(SCH_1):PAGE58_I12@PURE_QUANTA.GENOA_SP5(CHIPS)':
 'VSS_V44': CDS_PINID='VSS_V44';
NODE_NAME     U26 V45
 '@T6G_MB_LIB.T6G(SCH_1):PAGE58_I12@PURE_QUANTA.GENOA_SP5(CHIPS)':
 'VSS_V45': CDS_PINID='VSS_V45';
NODE_NAME     U26 V46
 '@T6G_MB_LIB.T6G(SCH_1):PAGE58_I12@PURE_QUANTA.GENOA_SP5(CHIPS)':
 'VSS_V46': CDS_PINID='VSS_V46';
NODE_NAME     U26 V47
 '@T6G_MB_LIB.T6G(SCH_1):PAGE58_I12@PURE_QUANTA.GENOA_SP5(CHIPS)':
 'VSS_V47': CDS_PINID='VSS_V47';
NODE_NAME     U26 V48
 '@T6G_MB_LIB.T6G(SCH_1):PAGE58_I12@PURE_QUANTA.GENOA_SP5(CHIPS)':
 'VSS_V48': CDS_PINID='VSS_V48';
NODE_NAME     U26 V49
 '@T6G_MB_LIB.T6G(SCH_1):PAGE58_I12@PURE_QUANTA.GENOA_SP5(CHIPS)':
 'VSS_V49': CDS_PINID='VSS_V49';
NODE_NAME     U26 V50
 '@T6G_MB_LIB.T6G(SCH_1):PAGE58_I12@PURE_QUANTA.GENOA_SP5(CHIPS)':
 'VSS_V50': CDS_PINID='VSS_V50';
NODE_NAME     U26 V51
 '@T6G_MB_LIB.T6G(SCH_1):PAGE58_I12@PURE_QUANTA.GENOA_SP5(CHIPS)':
 'VSS_V51': CDS_PINID='VSS_V51';
NODE_NAME     U26 V52
 '@T6G_MB_LIB.T6G(SCH_1):PAGE58_I12@PURE_QUANTA.GENOA_SP5(CHIPS)':
 'VSS_V52': CDS_PINID='VSS_V52';
NODE_NAME     U26 V53
 '@T6G_MB_LIB.T6G(SCH_1):PAGE58_I12@PURE_QUANTA.GENOA_SP5(CHIPS)':
 'VSS_V53': CDS_PINID='VSS_V53';
NODE_NAME     U26 V57
 '@T6G_MB_LIB.T6G(SCH_1):PAGE58_I12@PURE_QUANTA.GENOA_SP5(CHIPS)':
 'VSS_V57': CDS_PINID='VSS_V57';
NODE_NAME     U26 V59
 '@T6G_MB_LIB.T6G(SCH_1):PAGE58_I12@PURE_QUANTA.GENOA_SP5(CHIPS)':
 'VSS_V59': CDS_PINID='VSS_V59';
NODE_NAME     U26 V61
 '@T6G_MB_LIB.T6G(SCH_1):PAGE58_I12@PURE_QUANTA.GENOA_SP5(CHIPS)':
 'VSS_V61': CDS_PINID='VSS_V61';
NODE_NAME     U26 V64
 '@T6G_MB_LIB.T6G(SCH_1):PAGE58_I12@PURE_QUANTA.GENOA_SP5(CHIPS)':
 'VSS_V64': CDS_PINID='VSS_V64';
NODE_NAME     U26 V66
 '@T6G_MB_LIB.T6G(SCH_1):PAGE58_I12@PURE_QUANTA.GENOA_SP5(CHIPS)':
 'VSS_V66': CDS_PINID='VSS_V66';
NODE_NAME     U26 V71
 '@T6G_MB_LIB.T6G(SCH_1):PAGE58_I12@PURE_QUANTA.GENOA_SP5(CHIPS)':
 'VSS_V71': CDS_PINID='VSS_V71';
NODE_NAME     U26 V73
 '@T6G_MB_LIB.T6G(SCH_1):PAGE58_I12@PURE_QUANTA.GENOA_SP5(CHIPS)':
 'VSS_V73': CDS_PINID='VSS_V73';
NODE_NAME     U26 W1
 '@T6G_MB_LIB.T6G(SCH_1):PAGE58_I12@PURE_QUANTA.GENOA_SP5(CHIPS)':
 'VSS_W1': CDS_PINID='VSS_W1';
NODE_NAME     U26 W4
 '@T6G_MB_LIB.T6G(SCH_1):PAGE58_I12@PURE_QUANTA.GENOA_SP5(CHIPS)':
 'VSS_W4': CDS_PINID='VSS_W4';
NODE_NAME     U26 W6
 '@T6G_MB_LIB.T6G(SCH_1):PAGE58_I12@PURE_QUANTA.GENOA_SP5(CHIPS)':
 'VSS_W6': CDS_PINID='VSS_W6';
NODE_NAME     U26 W8
 '@T6G_MB_LIB.T6G(SCH_1):PAGE58_I12@PURE_QUANTA.GENOA_SP5(CHIPS)':
 'VSS_W8': CDS_PINID='VSS_W8';
NODE_NAME     U26 W11
 '@T6G_MB_LIB.T6G(SCH_1):PAGE58_I12@PURE_QUANTA.GENOA_SP5(CHIPS)':
 'VSS_W11': CDS_PINID='VSS_W11';
NODE_NAME     U26 W13
 '@T6G_MB_LIB.T6G(SCH_1):PAGE58_I12@PURE_QUANTA.GENOA_SP5(CHIPS)':
 'VSS_W13': CDS_PINID='VSS_W13';
NODE_NAME     U26 W15
 '@T6G_MB_LIB.T6G(SCH_1):PAGE58_I12@PURE_QUANTA.GENOA_SP5(CHIPS)':
 'VSS_W15': CDS_PINID='VSS_W15';
NODE_NAME     U26 W18
 '@T6G_MB_LIB.T6G(SCH_1):PAGE58_I12@PURE_QUANTA.GENOA_SP5(CHIPS)':
 'VSS_W18': CDS_PINID='VSS_W18';
NODE_NAME     U26 W20
 '@T6G_MB_LIB.T6G(SCH_1):PAGE58_I12@PURE_QUANTA.GENOA_SP5(CHIPS)':
 'VSS_W20': CDS_PINID='VSS_W20';
NODE_NAME     U26 W22
 '@T6G_MB_LIB.T6G(SCH_1):PAGE58_I12@PURE_QUANTA.GENOA_SP5(CHIPS)':
 'VSS_W22': CDS_PINID='VSS_W22';
NODE_NAME     U26 W25
 '@T6G_MB_LIB.T6G(SCH_1):PAGE58_I12@PURE_QUANTA.GENOA_SP5(CHIPS)':
 'VSS_W25': CDS_PINID='VSS_W25';
NODE_NAME     U26 W28
 '@T6G_MB_LIB.T6G(SCH_1):PAGE58_I12@PURE_QUANTA.GENOA_SP5(CHIPS)':
 'VSS_W28': CDS_PINID='VSS_W28';
NODE_NAME     U26 W34
 '@T6G_MB_LIB.T6G(SCH_1):PAGE58_I12@PURE_QUANTA.GENOA_SP5(CHIPS)':
 'VSS_W34': CDS_PINID='VSS_W34';
NODE_NAME     U26 W35
 '@T6G_MB_LIB.T6G(SCH_1):PAGE58_I12@PURE_QUANTA.GENOA_SP5(CHIPS)':
 'VSS_W35': CDS_PINID='VSS_W35';
NODE_NAME     U26 W36
 '@T6G_MB_LIB.T6G(SCH_1):PAGE58_I12@PURE_QUANTA.GENOA_SP5(CHIPS)':
 'VSS_W36': CDS_PINID='VSS_W36';
NODE_NAME     U26 W40
 '@T6G_MB_LIB.T6G(SCH_1):PAGE58_I12@PURE_QUANTA.GENOA_SP5(CHIPS)':
 'VSS_W40': CDS_PINID='VSS_W40';
NODE_NAME     U26 W41
 '@T6G_MB_LIB.T6G(SCH_1):PAGE58_I12@PURE_QUANTA.GENOA_SP5(CHIPS)':
 'VSS_W41': CDS_PINID='VSS_W41';
NODE_NAME     U26 W42
 '@T6G_MB_LIB.T6G(SCH_1):PAGE58_I12@PURE_QUANTA.GENOA_SP5(CHIPS)':
 'VSS_W42': CDS_PINID='VSS_W42';
NODE_NAME     U26 W45
 '@T6G_MB_LIB.T6G(SCH_1):PAGE58_I12@PURE_QUANTA.GENOA_SP5(CHIPS)':
 'VSS_W45': CDS_PINID='VSS_W45';
NODE_NAME     U26 W48
 '@T6G_MB_LIB.T6G(SCH_1):PAGE58_I12@PURE_QUANTA.GENOA_SP5(CHIPS)':
 'VSS_W48': CDS_PINID='VSS_W48';
NODE_NAME     U26 W51
 '@T6G_MB_LIB.T6G(SCH_1):PAGE58_I12@PURE_QUANTA.GENOA_SP5(CHIPS)':
 'VSS_W51': CDS_PINID='VSS_W51';
NODE_NAME     U26 W54
 '@T6G_MB_LIB.T6G(SCH_1):PAGE58_I12@PURE_QUANTA.GENOA_SP5(CHIPS)':
 'VSS_W54': CDS_PINID='VSS_W54';
NODE_NAME     U26 W56
 '@T6G_MB_LIB.T6G(SCH_1):PAGE58_I12@PURE_QUANTA.GENOA_SP5(CHIPS)':
 'VSS_W56': CDS_PINID='VSS_W56';
NODE_NAME     U26 W58
 '@T6G_MB_LIB.T6G(SCH_1):PAGE58_I12@PURE_QUANTA.GENOA_SP5(CHIPS)':
 'VSS_W58': CDS_PINID='VSS_W58';
NODE_NAME     U26 W61
 '@T6G_MB_LIB.T6G(SCH_1):PAGE58_I12@PURE_QUANTA.GENOA_SP5(CHIPS)':
 'VSS_W61': CDS_PINID='VSS_W61';
NODE_NAME     U26 W63
 '@T6G_MB_LIB.T6G(SCH_1):PAGE58_I12@PURE_QUANTA.GENOA_SP5(CHIPS)':
 'VSS_W63': CDS_PINID='VSS_W63';
NODE_NAME     U26 W65
 '@T6G_MB_LIB.T6G(SCH_1):PAGE58_I12@PURE_QUANTA.GENOA_SP5(CHIPS)':
 'VSS_W65': CDS_PINID='VSS_W65';
NODE_NAME     U26 W68
 '@T6G_MB_LIB.T6G(SCH_1):PAGE58_I12@PURE_QUANTA.GENOA_SP5(CHIPS)':
 'VSS_W68': CDS_PINID='VSS_W68';
NODE_NAME     U26 W70
 '@T6G_MB_LIB.T6G(SCH_1):PAGE58_I12@PURE_QUANTA.GENOA_SP5(CHIPS)':
 'VSS_W70': CDS_PINID='VSS_W70';
NODE_NAME     U26 W72
 '@T6G_MB_LIB.T6G(SCH_1):PAGE58_I12@PURE_QUANTA.GENOA_SP5(CHIPS)':
 'VSS_W72': CDS_PINID='VSS_W72';
NODE_NAME     U26 W75
 '@T6G_MB_LIB.T6G(SCH_1):PAGE58_I12@PURE_QUANTA.GENOA_SP5(CHIPS)':
 'VSS_W75': CDS_PINID='VSS_W75';
NODE_NAME     U26 Y3
 '@T6G_MB_LIB.T6G(SCH_1):PAGE58_I12@PURE_QUANTA.GENOA_SP5(CHIPS)':
 'VSS_Y3': CDS_PINID='VSS_Y3';
NODE_NAME     U26 Y8
 '@T6G_MB_LIB.T6G(SCH_1):PAGE58_I12@PURE_QUANTA.GENOA_SP5(CHIPS)':
 'VSS_Y8': CDS_PINID='VSS_Y8';
NODE_NAME     U26 Y10
 '@T6G_MB_LIB.T6G(SCH_1):PAGE58_I12@PURE_QUANTA.GENOA_SP5(CHIPS)':
 'VSS_Y10': CDS_PINID='VSS_Y10';
NODE_NAME     U26 Y15
 '@T6G_MB_LIB.T6G(SCH_1):PAGE58_I12@PURE_QUANTA.GENOA_SP5(CHIPS)':
 'VSS_Y15': CDS_PINID='VSS_Y15';
NODE_NAME     U26 Y17
 '@T6G_MB_LIB.T6G(SCH_1):PAGE58_I12@PURE_QUANTA.GENOA_SP5(CHIPS)':
 'VSS_Y17': CDS_PINID='VSS_Y17';
NODE_NAME     U26 Y22
 '@T6G_MB_LIB.T6G(SCH_1):PAGE58_I12@PURE_QUANTA.GENOA_SP5(CHIPS)':
 'VSS_Y22': CDS_PINID='VSS_Y22';
NODE_NAME     U26 Y23
 '@T6G_MB_LIB.T6G(SCH_1):PAGE58_I12@PURE_QUANTA.GENOA_SP5(CHIPS)':
 'VSS_Y23': CDS_PINID='VSS_Y23';
NODE_NAME     U26 Y24
 '@T6G_MB_LIB.T6G(SCH_1):PAGE58_I12@PURE_QUANTA.GENOA_SP5(CHIPS)':
 'VSS_Y24': CDS_PINID='VSS_Y24';
NODE_NAME     U26 Y25
 '@T6G_MB_LIB.T6G(SCH_1):PAGE58_I12@PURE_QUANTA.GENOA_SP5(CHIPS)':
 'VSS_Y25': CDS_PINID='VSS_Y25';
NODE_NAME     U26 Y26
 '@T6G_MB_LIB.T6G(SCH_1):PAGE58_I12@PURE_QUANTA.GENOA_SP5(CHIPS)':
 'VSS_Y26': CDS_PINID='VSS_Y26';
NODE_NAME     U26 Y27
 '@T6G_MB_LIB.T6G(SCH_1):PAGE58_I12@PURE_QUANTA.GENOA_SP5(CHIPS)':
 'VSS_Y27': CDS_PINID='VSS_Y27';
NODE_NAME     U26 Y28
 '@T6G_MB_LIB.T6G(SCH_1):PAGE58_I12@PURE_QUANTA.GENOA_SP5(CHIPS)':
 'VSS_Y28': CDS_PINID='VSS_Y28';
NODE_NAME     U26 Y31
 '@T6G_MB_LIB.T6G(SCH_1):PAGE58_I12@PURE_QUANTA.GENOA_SP5(CHIPS)':
 'VSS_Y31': CDS_PINID='VSS_Y31';
NODE_NAME     U26 Y32
 '@T6G_MB_LIB.T6G(SCH_1):PAGE58_I12@PURE_QUANTA.GENOA_SP5(CHIPS)':
 'VSS_Y32': CDS_PINID='VSS_Y32';
NODE_NAME     U26 Y33
 '@T6G_MB_LIB.T6G(SCH_1):PAGE58_I12@PURE_QUANTA.GENOA_SP5(CHIPS)':
 'VSS_Y33': CDS_PINID='VSS_Y33';
NODE_NAME     U26 Y34
 '@T6G_MB_LIB.T6G(SCH_1):PAGE58_I12@PURE_QUANTA.GENOA_SP5(CHIPS)':
 'VSS_Y34': CDS_PINID='VSS_Y34';
NODE_NAME     U26 Y37
 '@T6G_MB_LIB.T6G(SCH_1):PAGE58_I12@PURE_QUANTA.GENOA_SP5(CHIPS)':
 'VSS_Y37': CDS_PINID='VSS_Y37';
NODE_NAME     U26 Y39
 '@T6G_MB_LIB.T6G(SCH_1):PAGE58_I12@PURE_QUANTA.GENOA_SP5(CHIPS)':
 'VSS_Y39': CDS_PINID='VSS_Y39';
NODE_NAME     U26 Y42
 '@T6G_MB_LIB.T6G(SCH_1):PAGE58_I12@PURE_QUANTA.GENOA_SP5(CHIPS)':
 'VSS_Y42': CDS_PINID='VSS_Y42';
NODE_NAME     U26 Y43
 '@T6G_MB_LIB.T6G(SCH_1):PAGE58_I12@PURE_QUANTA.GENOA_SP5(CHIPS)':
 'VSS_Y43': CDS_PINID='VSS_Y43';
NODE_NAME     U26 Y44
 '@T6G_MB_LIB.T6G(SCH_1):PAGE58_I12@PURE_QUANTA.GENOA_SP5(CHIPS)':
 'VSS_Y44': CDS_PINID='VSS_Y44';
NODE_NAME     U26 Y45
 '@T6G_MB_LIB.T6G(SCH_1):PAGE58_I12@PURE_QUANTA.GENOA_SP5(CHIPS)':
 'VSS_Y45': CDS_PINID='VSS_Y45';
NODE_NAME     U26 Y48
 '@T6G_MB_LIB.T6G(SCH_1):PAGE58_I12@PURE_QUANTA.GENOA_SP5(CHIPS)':
 'VSS_Y48': CDS_PINID='VSS_Y48';
NODE_NAME     U26 Y49
 '@T6G_MB_LIB.T6G(SCH_1):PAGE58_I12@PURE_QUANTA.GENOA_SP5(CHIPS)':
 'VSS_Y49': CDS_PINID='VSS_Y49';
NODE_NAME     U26 Y50
 '@T6G_MB_LIB.T6G(SCH_1):PAGE58_I12@PURE_QUANTA.GENOA_SP5(CHIPS)':
 'VSS_Y50': CDS_PINID='VSS_Y50';
NODE_NAME     U26 Y51
 '@T6G_MB_LIB.T6G(SCH_1):PAGE58_I12@PURE_QUANTA.GENOA_SP5(CHIPS)':
 'VSS_Y51': CDS_PINID='VSS_Y51';
NODE_NAME     U26 Y52
 '@T6G_MB_LIB.T6G(SCH_1):PAGE58_I12@PURE_QUANTA.GENOA_SP5(CHIPS)':
 'VSS_Y52': CDS_PINID='VSS_Y52';
NODE_NAME     U26 Y53
 '@T6G_MB_LIB.T6G(SCH_1):PAGE58_I12@PURE_QUANTA.GENOA_SP5(CHIPS)':
 'VSS_Y53': CDS_PINID='VSS_Y53';
NODE_NAME     U26 Y54
 '@T6G_MB_LIB.T6G(SCH_1):PAGE58_I12@PURE_QUANTA.GENOA_SP5(CHIPS)':
 'VSS_Y54': CDS_PINID='VSS_Y54';
NODE_NAME     U26 Y59
 '@T6G_MB_LIB.T6G(SCH_1):PAGE58_I12@PURE_QUANTA.GENOA_SP5(CHIPS)':
 'VSS_Y59': CDS_PINID='VSS_Y59';
NODE_NAME     U26 Y61
 '@T6G_MB_LIB.T6G(SCH_1):PAGE58_I12@PURE_QUANTA.GENOA_SP5(CHIPS)':
 'VSS_Y61': CDS_PINID='VSS_Y61';
NODE_NAME     U26 Y66
 '@T6G_MB_LIB.T6G(SCH_1):PAGE58_I12@PURE_QUANTA.GENOA_SP5(CHIPS)':
 'VSS_Y66': CDS_PINID='VSS_Y66';
NODE_NAME     U26 Y68
 '@T6G_MB_LIB.T6G(SCH_1):PAGE58_I12@PURE_QUANTA.GENOA_SP5(CHIPS)':
 'VSS_Y68': CDS_PINID='VSS_Y68';
NODE_NAME     U26 Y73
 '@T6G_MB_LIB.T6G(SCH_1):PAGE58_I12@PURE_QUANTA.GENOA_SP5(CHIPS)':
 'VSS_Y73': CDS_PINID='VSS_Y73';
NODE_NAME     U26 J15
 '@T6G_MB_LIB.T6G(SCH_1):PAGE58_I15@PURE_QUANTA.GENOA_SP5(CHIPS)':
 'VSS_J15': CDS_PINID='VSS_J15';
NODE_NAME     U26 J18
 '@T6G_MB_LIB.T6G(SCH_1):PAGE58_I15@PURE_QUANTA.GENOA_SP5(CHIPS)':
 'VSS_J18': CDS_PINID='VSS_J18';
NODE_NAME     U26 J20
 '@T6G_MB_LIB.T6G(SCH_1):PAGE58_I15@PURE_QUANTA.GENOA_SP5(CHIPS)':
 'VSS_J20': CDS_PINID='VSS_J20';
NODE_NAME     U26 J22
 '@T6G_MB_LIB.T6G(SCH_1):PAGE58_I15@PURE_QUANTA.GENOA_SP5(CHIPS)':
 'VSS_J22': CDS_PINID='VSS_J22';
NODE_NAME     U26 J25
 '@T6G_MB_LIB.T6G(SCH_1):PAGE58_I15@PURE_QUANTA.GENOA_SP5(CHIPS)':
 'VSS_J25': CDS_PINID='VSS_J25';
NODE_NAME     U26 J28
 '@T6G_MB_LIB.T6G(SCH_1):PAGE58_I15@PURE_QUANTA.GENOA_SP5(CHIPS)':
 'VSS_J28': CDS_PINID='VSS_J28';
NODE_NAME     U26 J31
 '@T6G_MB_LIB.T6G(SCH_1):PAGE58_I15@PURE_QUANTA.GENOA_SP5(CHIPS)':
 'VSS_J31': CDS_PINID='VSS_J31';
NODE_NAME     U26 J34
 '@T6G_MB_LIB.T6G(SCH_1):PAGE58_I15@PURE_QUANTA.GENOA_SP5(CHIPS)':
 'VSS_J34': CDS_PINID='VSS_J34';
NODE_NAME     U26 J42
 '@T6G_MB_LIB.T6G(SCH_1):PAGE58_I15@PURE_QUANTA.GENOA_SP5(CHIPS)':
 'VSS_J42': CDS_PINID='VSS_J42';
NODE_NAME     U26 J45
 '@T6G_MB_LIB.T6G(SCH_1):PAGE58_I15@PURE_QUANTA.GENOA_SP5(CHIPS)':
 'VSS_J45': CDS_PINID='VSS_J45';
NODE_NAME     U26 J48
 '@T6G_MB_LIB.T6G(SCH_1):PAGE58_I15@PURE_QUANTA.GENOA_SP5(CHIPS)':
 'VSS_J48': CDS_PINID='VSS_J48';
NODE_NAME     U26 J51
 '@T6G_MB_LIB.T6G(SCH_1):PAGE58_I15@PURE_QUANTA.GENOA_SP5(CHIPS)':
 'VSS_J51': CDS_PINID='VSS_J51';
NODE_NAME     U26 J54
 '@T6G_MB_LIB.T6G(SCH_1):PAGE58_I15@PURE_QUANTA.GENOA_SP5(CHIPS)':
 'VSS_J54': CDS_PINID='VSS_J54';
NODE_NAME     U26 J56
 '@T6G_MB_LIB.T6G(SCH_1):PAGE58_I15@PURE_QUANTA.GENOA_SP5(CHIPS)':
 'VSS_J56': CDS_PINID='VSS_J56';
NODE_NAME     U26 J58
 '@T6G_MB_LIB.T6G(SCH_1):PAGE58_I15@PURE_QUANTA.GENOA_SP5(CHIPS)':
 'VSS_J58': CDS_PINID='VSS_J58';
NODE_NAME     U26 J61
 '@T6G_MB_LIB.T6G(SCH_1):PAGE58_I15@PURE_QUANTA.GENOA_SP5(CHIPS)':
 'VSS_J61': CDS_PINID='VSS_J61';
NODE_NAME     U26 J63
 '@T6G_MB_LIB.T6G(SCH_1):PAGE58_I15@PURE_QUANTA.GENOA_SP5(CHIPS)':
 'VSS_J63': CDS_PINID='VSS_J63';
NODE_NAME     U26 J65
 '@T6G_MB_LIB.T6G(SCH_1):PAGE58_I15@PURE_QUANTA.GENOA_SP5(CHIPS)':
 'VSS_J65': CDS_PINID='VSS_J65';
NODE_NAME     U26 J68
 '@T6G_MB_LIB.T6G(SCH_1):PAGE58_I15@PURE_QUANTA.GENOA_SP5(CHIPS)':
 'VSS_J68': CDS_PINID='VSS_J68';
NODE_NAME     U26 J70
 '@T6G_MB_LIB.T6G(SCH_1):PAGE58_I15@PURE_QUANTA.GENOA_SP5(CHIPS)':
 'VSS_J70': CDS_PINID='VSS_J70';
NODE_NAME     U26 J72
 '@T6G_MB_LIB.T6G(SCH_1):PAGE58_I15@PURE_QUANTA.GENOA_SP5(CHIPS)':
 'VSS_J72': CDS_PINID='VSS_J72';
NODE_NAME     U26 J75
 '@T6G_MB_LIB.T6G(SCH_1):PAGE58_I15@PURE_QUANTA.GENOA_SP5(CHIPS)':
 'VSS_J75': CDS_PINID='VSS_J75';
NODE_NAME     U26 K3
 '@T6G_MB_LIB.T6G(SCH_1):PAGE58_I15@PURE_QUANTA.GENOA_SP5(CHIPS)':
 'VSS_K3': CDS_PINID='VSS_K3';
NODE_NAME     U26 K5
 '@T6G_MB_LIB.T6G(SCH_1):PAGE58_I15@PURE_QUANTA.GENOA_SP5(CHIPS)':
 'VSS_K5': CDS_PINID='VSS_K5';
NODE_NAME     U26 K8
 '@T6G_MB_LIB.T6G(SCH_1):PAGE58_I15@PURE_QUANTA.GENOA_SP5(CHIPS)':
 'VSS_K8': CDS_PINID='VSS_K8';
NODE_NAME     U26 K10
 '@T6G_MB_LIB.T6G(SCH_1):PAGE58_I15@PURE_QUANTA.GENOA_SP5(CHIPS)':
 'VSS_K10': CDS_PINID='VSS_K10';
NODE_NAME     U26 K12
 '@T6G_MB_LIB.T6G(SCH_1):PAGE58_I15@PURE_QUANTA.GENOA_SP5(CHIPS)':
 'VSS_K12': CDS_PINID='VSS_K12';
NODE_NAME     U26 K15
 '@T6G_MB_LIB.T6G(SCH_1):PAGE58_I15@PURE_QUANTA.GENOA_SP5(CHIPS)':
 'VSS_K15': CDS_PINID='VSS_K15';
NODE_NAME     U26 K17
 '@T6G_MB_LIB.T6G(SCH_1):PAGE58_I15@PURE_QUANTA.GENOA_SP5(CHIPS)':
 'VSS_K17': CDS_PINID='VSS_K17';
NODE_NAME     U26 K19
 '@T6G_MB_LIB.T6G(SCH_1):PAGE58_I15@PURE_QUANTA.GENOA_SP5(CHIPS)':
 'VSS_K19': CDS_PINID='VSS_K19';
NODE_NAME     U26 K24
 '@T6G_MB_LIB.T6G(SCH_1):PAGE58_I15@PURE_QUANTA.GENOA_SP5(CHIPS)':
 'VSS_K24': CDS_PINID='VSS_K24';
NODE_NAME     U26 K25
 '@T6G_MB_LIB.T6G(SCH_1):PAGE58_I15@PURE_QUANTA.GENOA_SP5(CHIPS)':
 'VSS_K25': CDS_PINID='VSS_K25';
NODE_NAME     U26 K26
 '@T6G_MB_LIB.T6G(SCH_1):PAGE58_I15@PURE_QUANTA.GENOA_SP5(CHIPS)':
 'VSS_K26': CDS_PINID='VSS_K26';
NODE_NAME     U26 K27
 '@T6G_MB_LIB.T6G(SCH_1):PAGE58_I15@PURE_QUANTA.GENOA_SP5(CHIPS)':
 'VSS_K27': CDS_PINID='VSS_K27';
NODE_NAME     U26 K28
 '@T6G_MB_LIB.T6G(SCH_1):PAGE58_I15@PURE_QUANTA.GENOA_SP5(CHIPS)':
 'VSS_K28': CDS_PINID='VSS_K28';
NODE_NAME     U26 K29
 '@T6G_MB_LIB.T6G(SCH_1):PAGE58_I15@PURE_QUANTA.GENOA_SP5(CHIPS)':
 'VSS_K29': CDS_PINID='VSS_K29';
NODE_NAME     U26 K30
 '@T6G_MB_LIB.T6G(SCH_1):PAGE58_I15@PURE_QUANTA.GENOA_SP5(CHIPS)':
 'VSS_K30': CDS_PINID='VSS_K30';
NODE_NAME     U26 K31
 '@T6G_MB_LIB.T6G(SCH_1):PAGE58_I15@PURE_QUANTA.GENOA_SP5(CHIPS)':
 'VSS_K31': CDS_PINID='VSS_K31';
NODE_NAME     U26 K32
 '@T6G_MB_LIB.T6G(SCH_1):PAGE58_I15@PURE_QUANTA.GENOA_SP5(CHIPS)':
 'VSS_K32': CDS_PINID='VSS_K32';
NODE_NAME     U26 K33
 '@T6G_MB_LIB.T6G(SCH_1):PAGE58_I15@PURE_QUANTA.GENOA_SP5(CHIPS)':
 'VSS_K33': CDS_PINID='VSS_K33';
NODE_NAME     U26 K34
 '@T6G_MB_LIB.T6G(SCH_1):PAGE58_I15@PURE_QUANTA.GENOA_SP5(CHIPS)':
 'VSS_K34': CDS_PINID='VSS_K34';
NODE_NAME     U26 K37
 '@T6G_MB_LIB.T6G(SCH_1):PAGE58_I15@PURE_QUANTA.GENOA_SP5(CHIPS)':
 'VSS_K37': CDS_PINID='VSS_K37';
NODE_NAME     U26 K39
 '@T6G_MB_LIB.T6G(SCH_1):PAGE58_I15@PURE_QUANTA.GENOA_SP5(CHIPS)':
 'VSS_K39': CDS_PINID='VSS_K39';
NODE_NAME     U26 K42
 '@T6G_MB_LIB.T6G(SCH_1):PAGE58_I15@PURE_QUANTA.GENOA_SP5(CHIPS)':
 'VSS_K42': CDS_PINID='VSS_K42';
NODE_NAME     U26 K43
 '@T6G_MB_LIB.T6G(SCH_1):PAGE58_I15@PURE_QUANTA.GENOA_SP5(CHIPS)':
 'VSS_K43': CDS_PINID='VSS_K43';
NODE_NAME     U26 K44
 '@T6G_MB_LIB.T6G(SCH_1):PAGE58_I15@PURE_QUANTA.GENOA_SP5(CHIPS)':
 'VSS_K44': CDS_PINID='VSS_K44';
NODE_NAME     U26 K45
 '@T6G_MB_LIB.T6G(SCH_1):PAGE58_I15@PURE_QUANTA.GENOA_SP5(CHIPS)':
 'VSS_K45': CDS_PINID='VSS_K45';
NODE_NAME     U26 K46
 '@T6G_MB_LIB.T6G(SCH_1):PAGE58_I15@PURE_QUANTA.GENOA_SP5(CHIPS)':
 'VSS_K46': CDS_PINID='VSS_K46';
NODE_NAME     U26 K47
 '@T6G_MB_LIB.T6G(SCH_1):PAGE58_I15@PURE_QUANTA.GENOA_SP5(CHIPS)':
 'VSS_K47': CDS_PINID='VSS_K47';
NODE_NAME     U26 K48
 '@T6G_MB_LIB.T6G(SCH_1):PAGE58_I15@PURE_QUANTA.GENOA_SP5(CHIPS)':
 'VSS_K48': CDS_PINID='VSS_K48';
NODE_NAME     U26 K49
 '@T6G_MB_LIB.T6G(SCH_1):PAGE58_I15@PURE_QUANTA.GENOA_SP5(CHIPS)':
 'VSS_K49': CDS_PINID='VSS_K49';
NODE_NAME     U26 K50
 '@T6G_MB_LIB.T6G(SCH_1):PAGE58_I15@PURE_QUANTA.GENOA_SP5(CHIPS)':
 'VSS_K50': CDS_PINID='VSS_K50';
NODE_NAME     U26 K51
 '@T6G_MB_LIB.T6G(SCH_1):PAGE58_I15@PURE_QUANTA.GENOA_SP5(CHIPS)':
 'VSS_K51': CDS_PINID='VSS_K51';
NODE_NAME     U26 K52
 '@T6G_MB_LIB.T6G(SCH_1):PAGE58_I15@PURE_QUANTA.GENOA_SP5(CHIPS)':
 'VSS_K52': CDS_PINID='VSS_K52';
NODE_NAME     U26 K53
 '@T6G_MB_LIB.T6G(SCH_1):PAGE58_I15@PURE_QUANTA.GENOA_SP5(CHIPS)':
 'VSS_K53': CDS_PINID='VSS_K53';
NODE_NAME     U26 K57
 '@T6G_MB_LIB.T6G(SCH_1):PAGE58_I15@PURE_QUANTA.GENOA_SP5(CHIPS)':
 'VSS_K57': CDS_PINID='VSS_K57';
NODE_NAME     U26 K61
 '@T6G_MB_LIB.T6G(SCH_1):PAGE58_I15@PURE_QUANTA.GENOA_SP5(CHIPS)':
 'VSS_K61': CDS_PINID='VSS_K61';
NODE_NAME     U26 K64
 '@T6G_MB_LIB.T6G(SCH_1):PAGE58_I15@PURE_QUANTA.GENOA_SP5(CHIPS)':
 'VSS_K64': CDS_PINID='VSS_K64';
NODE_NAME     U26 K66
 '@T6G_MB_LIB.T6G(SCH_1):PAGE58_I15@PURE_QUANTA.GENOA_SP5(CHIPS)':
 'VSS_K66': CDS_PINID='VSS_K66';
NODE_NAME     U26 K68
 '@T6G_MB_LIB.T6G(SCH_1):PAGE58_I15@PURE_QUANTA.GENOA_SP5(CHIPS)':
 'VSS_K68': CDS_PINID='VSS_K68';
NODE_NAME     U26 K71
 '@T6G_MB_LIB.T6G(SCH_1):PAGE58_I15@PURE_QUANTA.GENOA_SP5(CHIPS)':
 'VSS_K71': CDS_PINID='VSS_K71';
NODE_NAME     U26 K73
 '@T6G_MB_LIB.T6G(SCH_1):PAGE58_I15@PURE_QUANTA.GENOA_SP5(CHIPS)':
 'VSS_K73': CDS_PINID='VSS_K73';
NODE_NAME     U26 L1
 '@T6G_MB_LIB.T6G(SCH_1):PAGE58_I15@PURE_QUANTA.GENOA_SP5(CHIPS)':
 'VSS_L1': CDS_PINID='VSS_L1';
NODE_NAME     U26 L6
 '@T6G_MB_LIB.T6G(SCH_1):PAGE58_I15@PURE_QUANTA.GENOA_SP5(CHIPS)':
 'VSS_L6': CDS_PINID='VSS_L6';
NODE_NAME     U26 L8
 '@T6G_MB_LIB.T6G(SCH_1):PAGE58_I15@PURE_QUANTA.GENOA_SP5(CHIPS)':
 'VSS_L8': CDS_PINID='VSS_L8';
NODE_NAME     U26 L13
 '@T6G_MB_LIB.T6G(SCH_1):PAGE58_I15@PURE_QUANTA.GENOA_SP5(CHIPS)':
 'VSS_L13': CDS_PINID='VSS_L13';
NODE_NAME     U26 L15
 '@T6G_MB_LIB.T6G(SCH_1):PAGE58_I15@PURE_QUANTA.GENOA_SP5(CHIPS)':
 'VSS_L15': CDS_PINID='VSS_L15';
NODE_NAME     U26 L20
 '@T6G_MB_LIB.T6G(SCH_1):PAGE58_I15@PURE_QUANTA.GENOA_SP5(CHIPS)':
 'VSS_L20': CDS_PINID='VSS_L20';
NODE_NAME     U26 L22
 '@T6G_MB_LIB.T6G(SCH_1):PAGE58_I15@PURE_QUANTA.GENOA_SP5(CHIPS)':
 'VSS_L22': CDS_PINID='VSS_L22';
NODE_NAME     U26 L25
 '@T6G_MB_LIB.T6G(SCH_1):PAGE58_I15@PURE_QUANTA.GENOA_SP5(CHIPS)':
 'VSS_L25': CDS_PINID='VSS_L25';
NODE_NAME     U26 L28
 '@T6G_MB_LIB.T6G(SCH_1):PAGE58_I15@PURE_QUANTA.GENOA_SP5(CHIPS)':
 'VSS_L28': CDS_PINID='VSS_L28';
NODE_NAME     U26 L31
 '@T6G_MB_LIB.T6G(SCH_1):PAGE58_I15@PURE_QUANTA.GENOA_SP5(CHIPS)':
 'VSS_L31': CDS_PINID='VSS_L31';
NODE_NAME     U26 L34
 '@T6G_MB_LIB.T6G(SCH_1):PAGE58_I15@PURE_QUANTA.GENOA_SP5(CHIPS)':
 'VSS_L34': CDS_PINID='VSS_L34';
NODE_NAME     U26 L35
 '@T6G_MB_LIB.T6G(SCH_1):PAGE58_I15@PURE_QUANTA.GENOA_SP5(CHIPS)':
 'VSS_L35': CDS_PINID='VSS_L35';
NODE_NAME     U26 L36
 '@T6G_MB_LIB.T6G(SCH_1):PAGE58_I15@PURE_QUANTA.GENOA_SP5(CHIPS)':
 'VSS_L36': CDS_PINID='VSS_L36';
NODE_NAME     U26 L40
 '@T6G_MB_LIB.T6G(SCH_1):PAGE58_I15@PURE_QUANTA.GENOA_SP5(CHIPS)':
 'VSS_L40': CDS_PINID='VSS_L40';
NODE_NAME     U26 L41
 '@T6G_MB_LIB.T6G(SCH_1):PAGE58_I15@PURE_QUANTA.GENOA_SP5(CHIPS)':
 'VSS_L41': CDS_PINID='VSS_L41';
NODE_NAME     U26 L42
 '@T6G_MB_LIB.T6G(SCH_1):PAGE58_I15@PURE_QUANTA.GENOA_SP5(CHIPS)':
 'VSS_L42': CDS_PINID='VSS_L42';
NODE_NAME     U26 L45
 '@T6G_MB_LIB.T6G(SCH_1):PAGE58_I15@PURE_QUANTA.GENOA_SP5(CHIPS)':
 'VSS_L45': CDS_PINID='VSS_L45';
NODE_NAME     U26 L48
 '@T6G_MB_LIB.T6G(SCH_1):PAGE58_I15@PURE_QUANTA.GENOA_SP5(CHIPS)':
 'VSS_L48': CDS_PINID='VSS_L48';
NODE_NAME     U26 L51
 '@T6G_MB_LIB.T6G(SCH_1):PAGE58_I15@PURE_QUANTA.GENOA_SP5(CHIPS)':
 'VSS_L51': CDS_PINID='VSS_L51';
NODE_NAME     U26 L54
 '@T6G_MB_LIB.T6G(SCH_1):PAGE58_I15@PURE_QUANTA.GENOA_SP5(CHIPS)':
 'VSS_L54': CDS_PINID='VSS_L54';
NODE_NAME     U26 L56
 '@T6G_MB_LIB.T6G(SCH_1):PAGE58_I15@PURE_QUANTA.GENOA_SP5(CHIPS)':
 'VSS_L56': CDS_PINID='VSS_L56';
NODE_NAME     U26 L61
 '@T6G_MB_LIB.T6G(SCH_1):PAGE58_I15@PURE_QUANTA.GENOA_SP5(CHIPS)':
 'VSS_L61': CDS_PINID='VSS_L61';
NODE_NAME     U26 L63
 '@T6G_MB_LIB.T6G(SCH_1):PAGE58_I15@PURE_QUANTA.GENOA_SP5(CHIPS)':
 'VSS_L63': CDS_PINID='VSS_L63';
NODE_NAME     U26 L68
 '@T6G_MB_LIB.T6G(SCH_1):PAGE58_I15@PURE_QUANTA.GENOA_SP5(CHIPS)':
 'VSS_L68': CDS_PINID='VSS_L68';
NODE_NAME     U26 L70
 '@T6G_MB_LIB.T6G(SCH_1):PAGE58_I15@PURE_QUANTA.GENOA_SP5(CHIPS)':
 'VSS_L70': CDS_PINID='VSS_L70';
NODE_NAME     U26 L75
 '@T6G_MB_LIB.T6G(SCH_1):PAGE58_I15@PURE_QUANTA.GENOA_SP5(CHIPS)':
 'VSS_L75': CDS_PINID='VSS_L75';
NODE_NAME     U26 M3
 '@T6G_MB_LIB.T6G(SCH_1):PAGE58_I15@PURE_QUANTA.GENOA_SP5(CHIPS)':
 'VSS_M3': CDS_PINID='VSS_M3';
NODE_NAME     U26 M5
 '@T6G_MB_LIB.T6G(SCH_1):PAGE58_I15@PURE_QUANTA.GENOA_SP5(CHIPS)':
 'VSS_M5': CDS_PINID='VSS_M5';
NODE_NAME     U26 M8
 '@T6G_MB_LIB.T6G(SCH_1):PAGE58_I15@PURE_QUANTA.GENOA_SP5(CHIPS)':
 'VSS_M8': CDS_PINID='VSS_M8';
NODE_NAME     U26 M10
 '@T6G_MB_LIB.T6G(SCH_1):PAGE58_I15@PURE_QUANTA.GENOA_SP5(CHIPS)':
 'VSS_M10': CDS_PINID='VSS_M10';
NODE_NAME     U26 M12
 '@T6G_MB_LIB.T6G(SCH_1):PAGE58_I15@PURE_QUANTA.GENOA_SP5(CHIPS)':
 'VSS_M12': CDS_PINID='VSS_M12';
NODE_NAME     U26 M15
 '@T6G_MB_LIB.T6G(SCH_1):PAGE58_I15@PURE_QUANTA.GENOA_SP5(CHIPS)':
 'VSS_M15': CDS_PINID='VSS_M15';
NODE_NAME     U26 M17
 '@T6G_MB_LIB.T6G(SCH_1):PAGE58_I15@PURE_QUANTA.GENOA_SP5(CHIPS)':
 'VSS_M17': CDS_PINID='VSS_M17';
NODE_NAME     U26 M19
 '@T6G_MB_LIB.T6G(SCH_1):PAGE58_I15@PURE_QUANTA.GENOA_SP5(CHIPS)':
 'VSS_M19': CDS_PINID='VSS_M19';
NODE_NAME     U26 M22
 '@T6G_MB_LIB.T6G(SCH_1):PAGE58_I15@PURE_QUANTA.GENOA_SP5(CHIPS)':
 'VSS_M22': CDS_PINID='VSS_M22';
NODE_NAME     U26 M25
 '@T6G_MB_LIB.T6G(SCH_1):PAGE58_I15@PURE_QUANTA.GENOA_SP5(CHIPS)':
 'VSS_M25': CDS_PINID='VSS_M25';
NODE_NAME     U26 M28
 '@T6G_MB_LIB.T6G(SCH_1):PAGE58_I15@PURE_QUANTA.GENOA_SP5(CHIPS)':
 'VSS_M28': CDS_PINID='VSS_M28';
NODE_NAME     U26 M31
 '@T6G_MB_LIB.T6G(SCH_1):PAGE58_I15@PURE_QUANTA.GENOA_SP5(CHIPS)':
 'VSS_M31': CDS_PINID='VSS_M31';
NODE_NAME     U26 M34
 '@T6G_MB_LIB.T6G(SCH_1):PAGE58_I15@PURE_QUANTA.GENOA_SP5(CHIPS)':
 'VSS_M34': CDS_PINID='VSS_M34';
NODE_NAME     U26 M37
 '@T6G_MB_LIB.T6G(SCH_1):PAGE58_I15@PURE_QUANTA.GENOA_SP5(CHIPS)':
 'VSS_M37': CDS_PINID='VSS_M37';
NODE_NAME     U26 M39
 '@T6G_MB_LIB.T6G(SCH_1):PAGE58_I15@PURE_QUANTA.GENOA_SP5(CHIPS)':
 'VSS_M39': CDS_PINID='VSS_M39';
NODE_NAME     U26 M42
 '@T6G_MB_LIB.T6G(SCH_1):PAGE58_I15@PURE_QUANTA.GENOA_SP5(CHIPS)':
 'VSS_M42': CDS_PINID='VSS_M42';
NODE_NAME     U26 M45
 '@T6G_MB_LIB.T6G(SCH_1):PAGE58_I15@PURE_QUANTA.GENOA_SP5(CHIPS)':
 'VSS_M45': CDS_PINID='VSS_M45';
NODE_NAME     U26 M48
 '@T6G_MB_LIB.T6G(SCH_1):PAGE58_I15@PURE_QUANTA.GENOA_SP5(CHIPS)':
 'VSS_M48': CDS_PINID='VSS_M48';
NODE_NAME     U26 M51
 '@T6G_MB_LIB.T6G(SCH_1):PAGE58_I15@PURE_QUANTA.GENOA_SP5(CHIPS)':
 'VSS_M51': CDS_PINID='VSS_M51';
NODE_NAME     U26 M54
 '@T6G_MB_LIB.T6G(SCH_1):PAGE58_I15@PURE_QUANTA.GENOA_SP5(CHIPS)':
 'VSS_M54': CDS_PINID='VSS_M54';
NODE_NAME     U26 M57
 '@T6G_MB_LIB.T6G(SCH_1):PAGE58_I15@PURE_QUANTA.GENOA_SP5(CHIPS)':
 'VSS_M57': CDS_PINID='VSS_M57';
NODE_NAME     U26 M59
 '@T6G_MB_LIB.T6G(SCH_1):PAGE58_I15@PURE_QUANTA.GENOA_SP5(CHIPS)':
 'VSS_M59': CDS_PINID='VSS_M59';
NODE_NAME     U26 M61
 '@T6G_MB_LIB.T6G(SCH_1):PAGE58_I15@PURE_QUANTA.GENOA_SP5(CHIPS)':
 'VSS_M61': CDS_PINID='VSS_M61';
NODE_NAME     U26 M64
 '@T6G_MB_LIB.T6G(SCH_1):PAGE58_I15@PURE_QUANTA.GENOA_SP5(CHIPS)':
 'VSS_M64': CDS_PINID='VSS_M64';
NODE_NAME     U26 M66
 '@T6G_MB_LIB.T6G(SCH_1):PAGE58_I15@PURE_QUANTA.GENOA_SP5(CHIPS)':
 'VSS_M66': CDS_PINID='VSS_M66';
NODE_NAME     U26 M68
 '@T6G_MB_LIB.T6G(SCH_1):PAGE58_I15@PURE_QUANTA.GENOA_SP5(CHIPS)':
 'VSS_M68': CDS_PINID='VSS_M68';
NODE_NAME     U26 M71
 '@T6G_MB_LIB.T6G(SCH_1):PAGE58_I15@PURE_QUANTA.GENOA_SP5(CHIPS)':
 'VSS_M71': CDS_PINID='VSS_M71';
NODE_NAME     U26 M73
 '@T6G_MB_LIB.T6G(SCH_1):PAGE58_I15@PURE_QUANTA.GENOA_SP5(CHIPS)':
 'VSS_M73': CDS_PINID='VSS_M73';
NODE_NAME     U26 N1
 '@T6G_MB_LIB.T6G(SCH_1):PAGE58_I15@PURE_QUANTA.GENOA_SP5(CHIPS)':
 'VSS_N1': CDS_PINID='VSS_N1';
NODE_NAME     U26 N4
 '@T6G_MB_LIB.T6G(SCH_1):PAGE58_I15@PURE_QUANTA.GENOA_SP5(CHIPS)':
 'VSS_N4': CDS_PINID='VSS_N4';
NODE_NAME     U26 N6
 '@T6G_MB_LIB.T6G(SCH_1):PAGE58_I15@PURE_QUANTA.GENOA_SP5(CHIPS)':
 'VSS_N6': CDS_PINID='VSS_N6';
NODE_NAME     U26 N8
 '@T6G_MB_LIB.T6G(SCH_1):PAGE58_I15@PURE_QUANTA.GENOA_SP5(CHIPS)':
 'VSS_N8': CDS_PINID='VSS_N8';
NODE_NAME     U26 N11
 '@T6G_MB_LIB.T6G(SCH_1):PAGE58_I15@PURE_QUANTA.GENOA_SP5(CHIPS)':
 'VSS_N11': CDS_PINID='VSS_N11';
NODE_NAME     U26 N13
 '@T6G_MB_LIB.T6G(SCH_1):PAGE58_I15@PURE_QUANTA.GENOA_SP5(CHIPS)':
 'VSS_N13': CDS_PINID='VSS_N13';
NODE_NAME     U26 N15
 '@T6G_MB_LIB.T6G(SCH_1):PAGE58_I15@PURE_QUANTA.GENOA_SP5(CHIPS)':
 'VSS_N15': CDS_PINID='VSS_N15';
NODE_NAME     U26 N18
 '@T6G_MB_LIB.T6G(SCH_1):PAGE58_I15@PURE_QUANTA.GENOA_SP5(CHIPS)':
 'VSS_N18': CDS_PINID='VSS_N18';
NODE_NAME     U26 N20
 '@T6G_MB_LIB.T6G(SCH_1):PAGE58_I15@PURE_QUANTA.GENOA_SP5(CHIPS)':
 'VSS_N20': CDS_PINID='VSS_N20';
NODE_NAME     U26 N22
 '@T6G_MB_LIB.T6G(SCH_1):PAGE58_I15@PURE_QUANTA.GENOA_SP5(CHIPS)':
 'VSS_N22': CDS_PINID='VSS_N22';
NODE_NAME     U26 N25
 '@T6G_MB_LIB.T6G(SCH_1):PAGE58_I15@PURE_QUANTA.GENOA_SP5(CHIPS)':
 'VSS_N25': CDS_PINID='VSS_N25';
NODE_NAME     U26 N28
 '@T6G_MB_LIB.T6G(SCH_1):PAGE58_I15@PURE_QUANTA.GENOA_SP5(CHIPS)':
 'VSS_N28': CDS_PINID='VSS_N28';
NODE_NAME     U26 N31
 '@T6G_MB_LIB.T6G(SCH_1):PAGE58_I15@PURE_QUANTA.GENOA_SP5(CHIPS)':
 'VSS_N31': CDS_PINID='VSS_N31';
NODE_NAME     U26 N34
 '@T6G_MB_LIB.T6G(SCH_1):PAGE58_I15@PURE_QUANTA.GENOA_SP5(CHIPS)':
 'VSS_N34': CDS_PINID='VSS_N34';
NODE_NAME     U26 N42
 '@T6G_MB_LIB.T6G(SCH_1):PAGE58_I15@PURE_QUANTA.GENOA_SP5(CHIPS)':
 'VSS_N42': CDS_PINID='VSS_N42';
NODE_NAME     U26 N45
 '@T6G_MB_LIB.T6G(SCH_1):PAGE58_I15@PURE_QUANTA.GENOA_SP5(CHIPS)':
 'VSS_N45': CDS_PINID='VSS_N45';
NODE_NAME     U26 N48
 '@T6G_MB_LIB.T6G(SCH_1):PAGE58_I15@PURE_QUANTA.GENOA_SP5(CHIPS)':
 'VSS_N48': CDS_PINID='VSS_N48';
NODE_NAME     U26 N51
 '@T6G_MB_LIB.T6G(SCH_1):PAGE58_I15@PURE_QUANTA.GENOA_SP5(CHIPS)':
 'VSS_N51': CDS_PINID='VSS_N51';
NODE_NAME     U26 N54
 '@T6G_MB_LIB.T6G(SCH_1):PAGE58_I15@PURE_QUANTA.GENOA_SP5(CHIPS)':
 'VSS_N54': CDS_PINID='VSS_N54';
NODE_NAME     U26 N56
 '@T6G_MB_LIB.T6G(SCH_1):PAGE58_I15@PURE_QUANTA.GENOA_SP5(CHIPS)':
 'VSS_N56': CDS_PINID='VSS_N56';
NODE_NAME     U26 N58
 '@T6G_MB_LIB.T6G(SCH_1):PAGE58_I15@PURE_QUANTA.GENOA_SP5(CHIPS)':
 'VSS_N58': CDS_PINID='VSS_N58';
NODE_NAME     U26 N61
 '@T6G_MB_LIB.T6G(SCH_1):PAGE58_I15@PURE_QUANTA.GENOA_SP5(CHIPS)':
 'VSS_N61': CDS_PINID='VSS_N61';
NODE_NAME     U26 N63
 '@T6G_MB_LIB.T6G(SCH_1):PAGE58_I15@PURE_QUANTA.GENOA_SP5(CHIPS)':
 'VSS_N63': CDS_PINID='VSS_N63';
NODE_NAME     U26 N65
 '@T6G_MB_LIB.T6G(SCH_1):PAGE58_I15@PURE_QUANTA.GENOA_SP5(CHIPS)':
 'VSS_N65': CDS_PINID='VSS_N65';
NODE_NAME     U26 N68
 '@T6G_MB_LIB.T6G(SCH_1):PAGE58_I15@PURE_QUANTA.GENOA_SP5(CHIPS)':
 'VSS_N68': CDS_PINID='VSS_N68';
NODE_NAME     U26 N70
 '@T6G_MB_LIB.T6G(SCH_1):PAGE58_I15@PURE_QUANTA.GENOA_SP5(CHIPS)':
 'VSS_N70': CDS_PINID='VSS_N70';
NODE_NAME     U26 N72
 '@T6G_MB_LIB.T6G(SCH_1):PAGE58_I15@PURE_QUANTA.GENOA_SP5(CHIPS)':
 'VSS_N72': CDS_PINID='VSS_N72';
NODE_NAME     U26 N75
 '@T6G_MB_LIB.T6G(SCH_1):PAGE58_I15@PURE_QUANTA.GENOA_SP5(CHIPS)':
 'VSS_N75': CDS_PINID='VSS_N75';
NODE_NAME     U26 P3
 '@T6G_MB_LIB.T6G(SCH_1):PAGE58_I15@PURE_QUANTA.GENOA_SP5(CHIPS)':
 'VSS_P3': CDS_PINID='VSS_P3';
NODE_NAME     U26 P8
 '@T6G_MB_LIB.T6G(SCH_1):PAGE58_I15@PURE_QUANTA.GENOA_SP5(CHIPS)':
 'VSS_P8': CDS_PINID='VSS_P8';
NODE_NAME     U26 P10
 '@T6G_MB_LIB.T6G(SCH_1):PAGE58_I15@PURE_QUANTA.GENOA_SP5(CHIPS)':
 'VSS_P10': CDS_PINID='VSS_P10';
NODE_NAME     U26 P15
 '@T6G_MB_LIB.T6G(SCH_1):PAGE58_I15@PURE_QUANTA.GENOA_SP5(CHIPS)':
 'VSS_P15': CDS_PINID='VSS_P15';
NODE_NAME     U26 P17
 '@T6G_MB_LIB.T6G(SCH_1):PAGE58_I15@PURE_QUANTA.GENOA_SP5(CHIPS)':
 'VSS_P17': CDS_PINID='VSS_P17';
NODE_NAME     U26 P23
 '@T6G_MB_LIB.T6G(SCH_1):PAGE58_I15@PURE_QUANTA.GENOA_SP5(CHIPS)':
 'VSS_P23': CDS_PINID='VSS_P23';
NODE_NAME     U26 P24
 '@T6G_MB_LIB.T6G(SCH_1):PAGE58_I15@PURE_QUANTA.GENOA_SP5(CHIPS)':
 'VSS_P24': CDS_PINID='VSS_P24';
NODE_NAME     U26 P26
 '@T6G_MB_LIB.T6G(SCH_1):PAGE58_I15@PURE_QUANTA.GENOA_SP5(CHIPS)':
 'VSS_P26': CDS_PINID='VSS_P26';
NODE_NAME     U26 P27
 '@T6G_MB_LIB.T6G(SCH_1):PAGE58_I15@PURE_QUANTA.GENOA_SP5(CHIPS)':
 'VSS_P27': CDS_PINID='VSS_P27';
NODE_NAME     U26 P28
 '@T6G_MB_LIB.T6G(SCH_1):PAGE58_I15@PURE_QUANTA.GENOA_SP5(CHIPS)':
 'VSS_P28': CDS_PINID='VSS_P28';
NODE_NAME     U26 P29
 '@T6G_MB_LIB.T6G(SCH_1):PAGE58_I15@PURE_QUANTA.GENOA_SP5(CHIPS)':
 'VSS_P29': CDS_PINID='VSS_P29';
NODE_NAME     U26 P30
 '@T6G_MB_LIB.T6G(SCH_1):PAGE58_I15@PURE_QUANTA.GENOA_SP5(CHIPS)':
 'VSS_P30': CDS_PINID='VSS_P30';
NODE_NAME     U26 P31
 '@T6G_MB_LIB.T6G(SCH_1):PAGE58_I15@PURE_QUANTA.GENOA_SP5(CHIPS)':
 'VSS_P31': CDS_PINID='VSS_P31';
NODE_NAME     U26 P32
 '@T6G_MB_LIB.T6G(SCH_1):PAGE58_I15@PURE_QUANTA.GENOA_SP5(CHIPS)':
 'VSS_P32': CDS_PINID='VSS_P32';
NODE_NAME     U26 P33
 '@T6G_MB_LIB.T6G(SCH_1):PAGE58_I15@PURE_QUANTA.GENOA_SP5(CHIPS)':
 'VSS_P33': CDS_PINID='VSS_P33';
NODE_NAME     U26 P34
 '@T6G_MB_LIB.T6G(SCH_1):PAGE58_I15@PURE_QUANTA.GENOA_SP5(CHIPS)':
 'VSS_P34': CDS_PINID='VSS_P34';
NODE_NAME     U26 P37
 '@T6G_MB_LIB.T6G(SCH_1):PAGE58_I15@PURE_QUANTA.GENOA_SP5(CHIPS)':
 'VSS_P37': CDS_PINID='VSS_P37';
NODE_NAME     U26 P39
 '@T6G_MB_LIB.T6G(SCH_1):PAGE58_I15@PURE_QUANTA.GENOA_SP5(CHIPS)':
 'VSS_P39': CDS_PINID='VSS_P39';
NODE_NAME     U26 P42
 '@T6G_MB_LIB.T6G(SCH_1):PAGE58_I15@PURE_QUANTA.GENOA_SP5(CHIPS)':
 'VSS_P42': CDS_PINID='VSS_P42';
NODE_NAME     U26 P43
 '@T6G_MB_LIB.T6G(SCH_1):PAGE58_I15@PURE_QUANTA.GENOA_SP5(CHIPS)':
 'VSS_P43': CDS_PINID='VSS_P43';
NODE_NAME     U26 P44
 '@T6G_MB_LIB.T6G(SCH_1):PAGE58_I15@PURE_QUANTA.GENOA_SP5(CHIPS)':
 'VSS_P44': CDS_PINID='VSS_P44';
NODE_NAME     U26 P45
 '@T6G_MB_LIB.T6G(SCH_1):PAGE58_I15@PURE_QUANTA.GENOA_SP5(CHIPS)':
 'VSS_P45': CDS_PINID='VSS_P45';
NODE_NAME     U26 P46
 '@T6G_MB_LIB.T6G(SCH_1):PAGE58_I15@PURE_QUANTA.GENOA_SP5(CHIPS)':
 'VSS_P46': CDS_PINID='VSS_P46';
NODE_NAME     U26 P47
 '@T6G_MB_LIB.T6G(SCH_1):PAGE58_I15@PURE_QUANTA.GENOA_SP5(CHIPS)':
 'VSS_P47': CDS_PINID='VSS_P47';
NODE_NAME     U26 P48
 '@T6G_MB_LIB.T6G(SCH_1):PAGE58_I15@PURE_QUANTA.GENOA_SP5(CHIPS)':
 'VSS_P48': CDS_PINID='VSS_P48';
NODE_NAME     U26 P49
 '@T6G_MB_LIB.T6G(SCH_1):PAGE58_I15@PURE_QUANTA.GENOA_SP5(CHIPS)':
 'VSS_P49': CDS_PINID='VSS_P49';
NODE_NAME     U26 P50
 '@T6G_MB_LIB.T6G(SCH_1):PAGE58_I15@PURE_QUANTA.GENOA_SP5(CHIPS)':
 'VSS_P50': CDS_PINID='VSS_P50';
NODE_NAME     U26 P51
 '@T6G_MB_LIB.T6G(SCH_1):PAGE58_I15@PURE_QUANTA.GENOA_SP5(CHIPS)':
 'VSS_P51': CDS_PINID='VSS_P51';
NODE_NAME     U26 P52
 '@T6G_MB_LIB.T6G(SCH_1):PAGE58_I15@PURE_QUANTA.GENOA_SP5(CHIPS)':
 'VSS_P52': CDS_PINID='VSS_P52';
NODE_NAME     U26 P53
 '@T6G_MB_LIB.T6G(SCH_1):PAGE58_I15@PURE_QUANTA.GENOA_SP5(CHIPS)':
 'VSS_P53': CDS_PINID='VSS_P53';
NODE_NAME     U26 P59
 '@T6G_MB_LIB.T6G(SCH_1):PAGE58_I15@PURE_QUANTA.GENOA_SP5(CHIPS)':
 'VSS_P59': CDS_PINID='VSS_P59';
NODE_NAME     U26 P61
 '@T6G_MB_LIB.T6G(SCH_1):PAGE58_I15@PURE_QUANTA.GENOA_SP5(CHIPS)':
 'VSS_P61': CDS_PINID='VSS_P61';
NODE_NAME     U26 P66
 '@T6G_MB_LIB.T6G(SCH_1):PAGE58_I15@PURE_QUANTA.GENOA_SP5(CHIPS)':
 'VSS_P66': CDS_PINID='VSS_P66';
NODE_NAME     U26 P73
 '@T6G_MB_LIB.T6G(SCH_1):PAGE58_I15@PURE_QUANTA.GENOA_SP5(CHIPS)':
 'VSS_P73': CDS_PINID='VSS_P73';
NODE_NAME     U26 R1
 '@T6G_MB_LIB.T6G(SCH_1):PAGE58_I15@PURE_QUANTA.GENOA_SP5(CHIPS)':
 'VSS_R1': CDS_PINID='VSS_R1';
NODE_NAME     U26 R4
 '@T6G_MB_LIB.T6G(SCH_1):PAGE58_I15@PURE_QUANTA.GENOA_SP5(CHIPS)':
 'VSS_R4': CDS_PINID='VSS_R4';
NODE_NAME     U26 R6
 '@T6G_MB_LIB.T6G(SCH_1):PAGE58_I15@PURE_QUANTA.GENOA_SP5(CHIPS)':
 'VSS_R6': CDS_PINID='VSS_R6';
NODE_NAME     U26 R8
 '@T6G_MB_LIB.T6G(SCH_1):PAGE58_I15@PURE_QUANTA.GENOA_SP5(CHIPS)':
 'VSS_R8': CDS_PINID='VSS_R8';
NODE_NAME     U26 R11
 '@T6G_MB_LIB.T6G(SCH_1):PAGE58_I15@PURE_QUANTA.GENOA_SP5(CHIPS)':
 'VSS_R11': CDS_PINID='VSS_R11';
NODE_NAME     U26 R13
 '@T6G_MB_LIB.T6G(SCH_1):PAGE58_I15@PURE_QUANTA.GENOA_SP5(CHIPS)':
 'VSS_R13': CDS_PINID='VSS_R13';
NODE_NAME     U26 R15
 '@T6G_MB_LIB.T6G(SCH_1):PAGE58_I15@PURE_QUANTA.GENOA_SP5(CHIPS)':
 'VSS_R15': CDS_PINID='VSS_R15';
NODE_NAME     U26 R18
 '@T6G_MB_LIB.T6G(SCH_1):PAGE58_I15@PURE_QUANTA.GENOA_SP5(CHIPS)':
 'VSS_R18': CDS_PINID='VSS_R18';
NODE_NAME     U26 R20
 '@T6G_MB_LIB.T6G(SCH_1):PAGE58_I15@PURE_QUANTA.GENOA_SP5(CHIPS)':
 'VSS_R20': CDS_PINID='VSS_R20';
NODE_NAME     U26 R22
 '@T6G_MB_LIB.T6G(SCH_1):PAGE58_I15@PURE_QUANTA.GENOA_SP5(CHIPS)':
 'VSS_R22': CDS_PINID='VSS_R22';
NODE_NAME     U26 R25
 '@T6G_MB_LIB.T6G(SCH_1):PAGE58_I15@PURE_QUANTA.GENOA_SP5(CHIPS)':
 'VSS_R25': CDS_PINID='VSS_R25';
NODE_NAME     U26 R28
 '@T6G_MB_LIB.T6G(SCH_1):PAGE58_I15@PURE_QUANTA.GENOA_SP5(CHIPS)':
 'VSS_R28': CDS_PINID='VSS_R28';
NODE_NAME     U26 R31
 '@T6G_MB_LIB.T6G(SCH_1):PAGE58_I15@PURE_QUANTA.GENOA_SP5(CHIPS)':
 'VSS_R31': CDS_PINID='VSS_R31';
NODE_NAME     U26 R34
 '@T6G_MB_LIB.T6G(SCH_1):PAGE58_I15@PURE_QUANTA.GENOA_SP5(CHIPS)':
 'VSS_R34': CDS_PINID='VSS_R34';
NODE_NAME     U26 R35
 '@T6G_MB_LIB.T6G(SCH_1):PAGE58_I15@PURE_QUANTA.GENOA_SP5(CHIPS)':
 'VSS_R35': CDS_PINID='VSS_R35';
NODE_NAME     U26 R36
 '@T6G_MB_LIB.T6G(SCH_1):PAGE58_I15@PURE_QUANTA.GENOA_SP5(CHIPS)':
 'VSS_R36': CDS_PINID='VSS_R36';
NODE_NAME     U26 R40
 '@T6G_MB_LIB.T6G(SCH_1):PAGE58_I15@PURE_QUANTA.GENOA_SP5(CHIPS)':
 'VSS_R40': CDS_PINID='VSS_R40';
NODE_NAME     U26 R41
 '@T6G_MB_LIB.T6G(SCH_1):PAGE58_I15@PURE_QUANTA.GENOA_SP5(CHIPS)':
 'VSS_R41': CDS_PINID='VSS_R41';
NODE_NAME     U26 R42
 '@T6G_MB_LIB.T6G(SCH_1):PAGE58_I15@PURE_QUANTA.GENOA_SP5(CHIPS)':
 'VSS_R42': CDS_PINID='VSS_R42';
NODE_NAME     U26 R45
 '@T6G_MB_LIB.T6G(SCH_1):PAGE58_I15@PURE_QUANTA.GENOA_SP5(CHIPS)':
 'VSS_R45': CDS_PINID='VSS_R45';
NODE_NAME     U26 R48
 '@T6G_MB_LIB.T6G(SCH_1):PAGE58_I15@PURE_QUANTA.GENOA_SP5(CHIPS)':
 'VSS_R48': CDS_PINID='VSS_R48';
NODE_NAME     U26 R51
 '@T6G_MB_LIB.T6G(SCH_1):PAGE58_I15@PURE_QUANTA.GENOA_SP5(CHIPS)':
 'VSS_R51': CDS_PINID='VSS_R51';
NODE_NAME     U26 R54
 '@T6G_MB_LIB.T6G(SCH_1):PAGE58_I15@PURE_QUANTA.GENOA_SP5(CHIPS)':
 'VSS_R54': CDS_PINID='VSS_R54';
NODE_NAME     U26 R56
 '@T6G_MB_LIB.T6G(SCH_1):PAGE58_I15@PURE_QUANTA.GENOA_SP5(CHIPS)':
 'VSS_R56': CDS_PINID='VSS_R56';
NODE_NAME     U26 R58
 '@T6G_MB_LIB.T6G(SCH_1):PAGE58_I15@PURE_QUANTA.GENOA_SP5(CHIPS)':
 'VSS_R58': CDS_PINID='VSS_R58';
NODE_NAME     U26 R61
 '@T6G_MB_LIB.T6G(SCH_1):PAGE58_I15@PURE_QUANTA.GENOA_SP5(CHIPS)':
 'VSS_R61': CDS_PINID='VSS_R61';
NODE_NAME     U26 R63
 '@T6G_MB_LIB.T6G(SCH_1):PAGE58_I15@PURE_QUANTA.GENOA_SP5(CHIPS)':
 'VSS_R63': CDS_PINID='VSS_R63';
NODE_NAME     U26 R65
 '@T6G_MB_LIB.T6G(SCH_1):PAGE58_I15@PURE_QUANTA.GENOA_SP5(CHIPS)':
 'VSS_R65': CDS_PINID='VSS_R65';
NODE_NAME     U26 R68
 '@T6G_MB_LIB.T6G(SCH_1):PAGE58_I15@PURE_QUANTA.GENOA_SP5(CHIPS)':
 'VSS_R68': CDS_PINID='VSS_R68';
NODE_NAME     U26 R70
 '@T6G_MB_LIB.T6G(SCH_1):PAGE58_I15@PURE_QUANTA.GENOA_SP5(CHIPS)':
 'VSS_R70': CDS_PINID='VSS_R70';
NODE_NAME     U26 R72
 '@T6G_MB_LIB.T6G(SCH_1):PAGE58_I15@PURE_QUANTA.GENOA_SP5(CHIPS)':
 'VSS_R72': CDS_PINID='VSS_R72';
NODE_NAME     U26 R75
 '@T6G_MB_LIB.T6G(SCH_1):PAGE58_I15@PURE_QUANTA.GENOA_SP5(CHIPS)':
 'VSS_R75': CDS_PINID='VSS_R75';
NODE_NAME     U26 T3
 '@T6G_MB_LIB.T6G(SCH_1):PAGE58_I15@PURE_QUANTA.GENOA_SP5(CHIPS)':
 'VSS_T3': CDS_PINID='VSS_T3';
NODE_NAME     U26 T5
 '@T6G_MB_LIB.T6G(SCH_1):PAGE58_I15@PURE_QUANTA.GENOA_SP5(CHIPS)':
 'VSS_T5': CDS_PINID='VSS_T5';
NODE_NAME     U26 T8
 '@T6G_MB_LIB.T6G(SCH_1):PAGE58_I15@PURE_QUANTA.GENOA_SP5(CHIPS)':
 'VSS_T8': CDS_PINID='VSS_T8';
NODE_NAME     U26 T10
 '@T6G_MB_LIB.T6G(SCH_1):PAGE58_I15@PURE_QUANTA.GENOA_SP5(CHIPS)':
 'VSS_T10': CDS_PINID='VSS_T10';
NODE_NAME     U26 T12
 '@T6G_MB_LIB.T6G(SCH_1):PAGE58_I15@PURE_QUANTA.GENOA_SP5(CHIPS)':
 'VSS_T12': CDS_PINID='VSS_T12';
NODE_NAME     U26 T15
 '@T6G_MB_LIB.T6G(SCH_1):PAGE58_I15@PURE_QUANTA.GENOA_SP5(CHIPS)':
 'VSS_T15': CDS_PINID='VSS_T15';
NODE_NAME     U26 T17
 '@T6G_MB_LIB.T6G(SCH_1):PAGE58_I15@PURE_QUANTA.GENOA_SP5(CHIPS)':
 'VSS_T17': CDS_PINID='VSS_T17';
NODE_NAME     U26 T19
 '@T6G_MB_LIB.T6G(SCH_1):PAGE58_I15@PURE_QUANTA.GENOA_SP5(CHIPS)':
 'VSS_T19': CDS_PINID='VSS_T19';
NODE_NAME     U26 T22
 '@T6G_MB_LIB.T6G(SCH_1):PAGE58_I15@PURE_QUANTA.GENOA_SP5(CHIPS)':
 'VSS_T22': CDS_PINID='VSS_T22';
NODE_NAME     U26 T25
 '@T6G_MB_LIB.T6G(SCH_1):PAGE58_I15@PURE_QUANTA.GENOA_SP5(CHIPS)':
 'VSS_T25': CDS_PINID='VSS_T25';
NODE_NAME     U26 T28
 '@T6G_MB_LIB.T6G(SCH_1):PAGE58_I15@PURE_QUANTA.GENOA_SP5(CHIPS)':
 'VSS_T28': CDS_PINID='VSS_T28';
NODE_NAME     U26 T31
 '@T6G_MB_LIB.T6G(SCH_1):PAGE58_I15@PURE_QUANTA.GENOA_SP5(CHIPS)':
 'VSS_T31': CDS_PINID='VSS_T31';
NODE_NAME     U26 T34
 '@T6G_MB_LIB.T6G(SCH_1):PAGE58_I15@PURE_QUANTA.GENOA_SP5(CHIPS)':
 'VSS_T34': CDS_PINID='VSS_T34';
NODE_NAME     U26 T37
 '@T6G_MB_LIB.T6G(SCH_1):PAGE58_I15@PURE_QUANTA.GENOA_SP5(CHIPS)':
 'VSS_T37': CDS_PINID='VSS_T37';
NODE_NAME     U26 T39
 '@T6G_MB_LIB.T6G(SCH_1):PAGE58_I15@PURE_QUANTA.GENOA_SP5(CHIPS)':
 'VSS_T39': CDS_PINID='VSS_T39';
NODE_NAME     U26 T42
 '@T6G_MB_LIB.T6G(SCH_1):PAGE58_I15@PURE_QUANTA.GENOA_SP5(CHIPS)':
 'VSS_T42': CDS_PINID='VSS_T42';
NODE_NAME     U26 T45
 '@T6G_MB_LIB.T6G(SCH_1):PAGE58_I15@PURE_QUANTA.GENOA_SP5(CHIPS)':
 'VSS_T45': CDS_PINID='VSS_T45';
NODE_NAME     U26 T48
 '@T6G_MB_LIB.T6G(SCH_1):PAGE58_I15@PURE_QUANTA.GENOA_SP5(CHIPS)':
 'VSS_T48': CDS_PINID='VSS_T48';
NODE_NAME     U26 T51
 '@T6G_MB_LIB.T6G(SCH_1):PAGE58_I15@PURE_QUANTA.GENOA_SP5(CHIPS)':
 'VSS_T51': CDS_PINID='VSS_T51';
NODE_NAME     U26 T54
 '@T6G_MB_LIB.T6G(SCH_1):PAGE58_I15@PURE_QUANTA.GENOA_SP5(CHIPS)':
 'VSS_T54': CDS_PINID='VSS_T54';
NODE_NAME     U26 T57
 '@T6G_MB_LIB.T6G(SCH_1):PAGE58_I15@PURE_QUANTA.GENOA_SP5(CHIPS)':
 'VSS_T57': CDS_PINID='VSS_T57';
NODE_NAME     U26 T59
 '@T6G_MB_LIB.T6G(SCH_1):PAGE58_I15@PURE_QUANTA.GENOA_SP5(CHIPS)':
 'VSS_T59': CDS_PINID='VSS_T59';
NODE_NAME     U26 T61
 '@T6G_MB_LIB.T6G(SCH_1):PAGE58_I15@PURE_QUANTA.GENOA_SP5(CHIPS)':
 'VSS_T61': CDS_PINID='VSS_T61';
NODE_NAME     U26 T64
 '@T6G_MB_LIB.T6G(SCH_1):PAGE58_I15@PURE_QUANTA.GENOA_SP5(CHIPS)':
 'VSS_T64': CDS_PINID='VSS_T64';
NODE_NAME     U26 BL26
 '@T6G_MB_LIB.T6G(SCH_1):PAGE59_I1@PURE_QUANTA.GENOA_SP5(CHIPS)':
 'VSS_BL26': CDS_PINID='VSS_BL26';
NODE_NAME     U26 BL28
 '@T6G_MB_LIB.T6G(SCH_1):PAGE59_I1@PURE_QUANTA.GENOA_SP5(CHIPS)':
 'VSS_BL28': CDS_PINID='VSS_BL28';
NODE_NAME     U26 BL49
 '@T6G_MB_LIB.T6G(SCH_1):PAGE59_I1@PURE_QUANTA.GENOA_SP5(CHIPS)':
 'VSS_BL49': CDS_PINID='VSS_BL49';
NODE_NAME     U26 BL51
 '@T6G_MB_LIB.T6G(SCH_1):PAGE59_I1@PURE_QUANTA.GENOA_SP5(CHIPS)':
 'VSS_BL51': CDS_PINID='VSS_BL51';
NODE_NAME     U26 BL53
 '@T6G_MB_LIB.T6G(SCH_1):PAGE59_I1@PURE_QUANTA.GENOA_SP5(CHIPS)':
 'VSS_BL53': CDS_PINID='VSS_BL53';
NODE_NAME     U26 BL56
 '@T6G_MB_LIB.T6G(SCH_1):PAGE59_I1@PURE_QUANTA.GENOA_SP5(CHIPS)':
 'VSS_BL56': CDS_PINID='VSS_BL56';
NODE_NAME     U26 BL58
 '@T6G_MB_LIB.T6G(SCH_1):PAGE59_I1@PURE_QUANTA.GENOA_SP5(CHIPS)':
 'VSS_BL58': CDS_PINID='VSS_BL58';
NODE_NAME     U26 BL61
 '@T6G_MB_LIB.T6G(SCH_1):PAGE59_I1@PURE_QUANTA.GENOA_SP5(CHIPS)':
 'VSS_BL61': CDS_PINID='VSS_BL61';
NODE_NAME     U26 BL63
 '@T6G_MB_LIB.T6G(SCH_1):PAGE59_I1@PURE_QUANTA.GENOA_SP5(CHIPS)':
 'VSS_BL63': CDS_PINID='VSS_BL63';
NODE_NAME     U26 BL65
 '@T6G_MB_LIB.T6G(SCH_1):PAGE59_I1@PURE_QUANTA.GENOA_SP5(CHIPS)':
 'VSS_BL65': CDS_PINID='VSS_BL65';
NODE_NAME     U26 BL68
 '@T6G_MB_LIB.T6G(SCH_1):PAGE59_I1@PURE_QUANTA.GENOA_SP5(CHIPS)':
 'VSS_BL68': CDS_PINID='VSS_BL68';
NODE_NAME     U26 BL70
 '@T6G_MB_LIB.T6G(SCH_1):PAGE59_I1@PURE_QUANTA.GENOA_SP5(CHIPS)':
 'VSS_BL70': CDS_PINID='VSS_BL70';
NODE_NAME     U26 BL72
 '@T6G_MB_LIB.T6G(SCH_1):PAGE59_I1@PURE_QUANTA.GENOA_SP5(CHIPS)':
 'VSS_BL72': CDS_PINID='VSS_BL72';
NODE_NAME     U26 BL75
 '@T6G_MB_LIB.T6G(SCH_1):PAGE59_I1@PURE_QUANTA.GENOA_SP5(CHIPS)':
 'VSS_BL75': CDS_PINID='VSS_BL75';
NODE_NAME     U26 BM3
 '@T6G_MB_LIB.T6G(SCH_1):PAGE59_I1@PURE_QUANTA.GENOA_SP5(CHIPS)':
 'VSS_BM3': CDS_PINID='VSS_BM3';
NODE_NAME     U26 BM8
 '@T6G_MB_LIB.T6G(SCH_1):PAGE59_I1@PURE_QUANTA.GENOA_SP5(CHIPS)':
 'VSS_BM8': CDS_PINID='VSS_BM8';
NODE_NAME     U26 BM10
 '@T6G_MB_LIB.T6G(SCH_1):PAGE59_I1@PURE_QUANTA.GENOA_SP5(CHIPS)':
 'VSS_BM10': CDS_PINID='VSS_BM10';
NODE_NAME     U26 BM15
 '@T6G_MB_LIB.T6G(SCH_1):PAGE59_I1@PURE_QUANTA.GENOA_SP5(CHIPS)':
 'VSS_BM15': CDS_PINID='VSS_BM15';
NODE_NAME     U26 BM17
 '@T6G_MB_LIB.T6G(SCH_1):PAGE59_I1@PURE_QUANTA.GENOA_SP5(CHIPS)':
 'VSS_BM17': CDS_PINID='VSS_BM17';
NODE_NAME     U26 BM23
 '@T6G_MB_LIB.T6G(SCH_1):PAGE59_I1@PURE_QUANTA.GENOA_SP5(CHIPS)':
 'VSS_BM23': CDS_PINID='VSS_BM23';
NODE_NAME     U26 BM25
 '@T6G_MB_LIB.T6G(SCH_1):PAGE59_I1@PURE_QUANTA.GENOA_SP5(CHIPS)':
 'VSS_BM25': CDS_PINID='VSS_BM25';
NODE_NAME     U26 BM27
 '@T6G_MB_LIB.T6G(SCH_1):PAGE59_I1@PURE_QUANTA.GENOA_SP5(CHIPS)':
 'VSS_BM27': CDS_PINID='VSS_BM27';
NODE_NAME     U26 BM29
 '@T6G_MB_LIB.T6G(SCH_1):PAGE59_I1@PURE_QUANTA.GENOA_SP5(CHIPS)':
 'VSS_BM29': CDS_PINID='VSS_BM29';
NODE_NAME     U26 BM31
 '@T6G_MB_LIB.T6G(SCH_1):PAGE59_I1@PURE_QUANTA.GENOA_SP5(CHIPS)':
 'VSS_BM31': CDS_PINID='VSS_BM31';
NODE_NAME     U26 BM33
 '@T6G_MB_LIB.T6G(SCH_1):PAGE59_I1@PURE_QUANTA.GENOA_SP5(CHIPS)':
 'VSS_BM33': CDS_PINID='VSS_BM33';
NODE_NAME     U26 BM35
 '@T6G_MB_LIB.T6G(SCH_1):PAGE59_I1@PURE_QUANTA.GENOA_SP5(CHIPS)':
 'VSS_BM35': CDS_PINID='VSS_BM35';
NODE_NAME     U26 BM37
 '@T6G_MB_LIB.T6G(SCH_1):PAGE59_I1@PURE_QUANTA.GENOA_SP5(CHIPS)':
 'VSS_BM37': CDS_PINID='VSS_BM37';
NODE_NAME     U26 BM40
 '@T6G_MB_LIB.T6G(SCH_1):PAGE59_I1@PURE_QUANTA.GENOA_SP5(CHIPS)':
 'VSS_BM40': CDS_PINID='VSS_BM40';
NODE_NAME     U26 BM42
 '@T6G_MB_LIB.T6G(SCH_1):PAGE59_I1@PURE_QUANTA.GENOA_SP5(CHIPS)':
 'VSS_BM42': CDS_PINID='VSS_BM42';
NODE_NAME     U26 BM44
 '@T6G_MB_LIB.T6G(SCH_1):PAGE59_I1@PURE_QUANTA.GENOA_SP5(CHIPS)':
 'VSS_BM44': CDS_PINID='VSS_BM44';
NODE_NAME     U26 BM46
 '@T6G_MB_LIB.T6G(SCH_1):PAGE59_I1@PURE_QUANTA.GENOA_SP5(CHIPS)':
 'VSS_BM46': CDS_PINID='VSS_BM46';
NODE_NAME     U26 BM48
 '@T6G_MB_LIB.T6G(SCH_1):PAGE59_I1@PURE_QUANTA.GENOA_SP5(CHIPS)':
 'VSS_BM48': CDS_PINID='VSS_BM48';
NODE_NAME     U26 BM50
 '@T6G_MB_LIB.T6G(SCH_1):PAGE59_I1@PURE_QUANTA.GENOA_SP5(CHIPS)':
 'VSS_BM50': CDS_PINID='VSS_BM50';
NODE_NAME     U26 BM52
 '@T6G_MB_LIB.T6G(SCH_1):PAGE59_I1@PURE_QUANTA.GENOA_SP5(CHIPS)':
 'VSS_BM52': CDS_PINID='VSS_BM52';
NODE_NAME     U26 BM54
 '@T6G_MB_LIB.T6G(SCH_1):PAGE59_I1@PURE_QUANTA.GENOA_SP5(CHIPS)':
 'VSS_BM54': CDS_PINID='VSS_BM54';
NODE_NAME     U26 BM59
 '@T6G_MB_LIB.T6G(SCH_1):PAGE59_I1@PURE_QUANTA.GENOA_SP5(CHIPS)':
 'VSS_BM59': CDS_PINID='VSS_BM59';
NODE_NAME     U26 BM61
 '@T6G_MB_LIB.T6G(SCH_1):PAGE59_I1@PURE_QUANTA.GENOA_SP5(CHIPS)':
 'VSS_BM61': CDS_PINID='VSS_BM61';
NODE_NAME     U26 BM66
 '@T6G_MB_LIB.T6G(SCH_1):PAGE59_I1@PURE_QUANTA.GENOA_SP5(CHIPS)':
 'VSS_BM66': CDS_PINID='VSS_BM66';
NODE_NAME     U26 BM68
 '@T6G_MB_LIB.T6G(SCH_1):PAGE59_I1@PURE_QUANTA.GENOA_SP5(CHIPS)':
 'VSS_BM68': CDS_PINID='VSS_BM68';
NODE_NAME     U26 BM73
 '@T6G_MB_LIB.T6G(SCH_1):PAGE59_I1@PURE_QUANTA.GENOA_SP5(CHIPS)':
 'VSS_BM73': CDS_PINID='VSS_BM73';
NODE_NAME     U26 BN1
 '@T6G_MB_LIB.T6G(SCH_1):PAGE59_I1@PURE_QUANTA.GENOA_SP5(CHIPS)':
 'VSS_BN1': CDS_PINID='VSS_BN1';
NODE_NAME     U26 BN4
 '@T6G_MB_LIB.T6G(SCH_1):PAGE59_I1@PURE_QUANTA.GENOA_SP5(CHIPS)':
 'VSS_BN4': CDS_PINID='VSS_BN4';
NODE_NAME     U26 BN6
 '@T6G_MB_LIB.T6G(SCH_1):PAGE59_I1@PURE_QUANTA.GENOA_SP5(CHIPS)':
 'VSS_BN6': CDS_PINID='VSS_BN6';
NODE_NAME     U26 BN8
 '@T6G_MB_LIB.T6G(SCH_1):PAGE59_I1@PURE_QUANTA.GENOA_SP5(CHIPS)':
 'VSS_BN8': CDS_PINID='VSS_BN8';
NODE_NAME     U26 BN11
 '@T6G_MB_LIB.T6G(SCH_1):PAGE59_I1@PURE_QUANTA.GENOA_SP5(CHIPS)':
 'VSS_BN11': CDS_PINID='VSS_BN11';
NODE_NAME     U26 BN13
 '@T6G_MB_LIB.T6G(SCH_1):PAGE59_I1@PURE_QUANTA.GENOA_SP5(CHIPS)':
 'VSS_BN13': CDS_PINID='VSS_BN13';
NODE_NAME     U26 BN15
 '@T6G_MB_LIB.T6G(SCH_1):PAGE59_I1@PURE_QUANTA.GENOA_SP5(CHIPS)':
 'VSS_BN15': CDS_PINID='VSS_BN15';
NODE_NAME     U26 BN18
 '@T6G_MB_LIB.T6G(SCH_1):PAGE59_I1@PURE_QUANTA.GENOA_SP5(CHIPS)':
 'VSS_BN18': CDS_PINID='VSS_BN18';
NODE_NAME     U26 BN20
 '@T6G_MB_LIB.T6G(SCH_1):PAGE59_I1@PURE_QUANTA.GENOA_SP5(CHIPS)':
 'VSS_BN20': CDS_PINID='VSS_BN20';
NODE_NAME     U26 BN22
 '@T6G_MB_LIB.T6G(SCH_1):PAGE59_I1@PURE_QUANTA.GENOA_SP5(CHIPS)':
 'VSS_BN22': CDS_PINID='VSS_BN22';
NODE_NAME     U26 BN24
 '@T6G_MB_LIB.T6G(SCH_1):PAGE59_I1@PURE_QUANTA.GENOA_SP5(CHIPS)':
 'VSS_BN24': CDS_PINID='VSS_BN24';
NODE_NAME     U26 BN26
 '@T6G_MB_LIB.T6G(SCH_1):PAGE59_I1@PURE_QUANTA.GENOA_SP5(CHIPS)':
 'VSS_BN26': CDS_PINID='VSS_BN26';
NODE_NAME     U26 BN28
 '@T6G_MB_LIB.T6G(SCH_1):PAGE59_I1@PURE_QUANTA.GENOA_SP5(CHIPS)':
 'VSS_BN28': CDS_PINID='VSS_BN28';
NODE_NAME     U26 BN30
 '@T6G_MB_LIB.T6G(SCH_1):PAGE59_I1@PURE_QUANTA.GENOA_SP5(CHIPS)':
 'VSS_BN30': CDS_PINID='VSS_BN30';
NODE_NAME     U26 BN32
 '@T6G_MB_LIB.T6G(SCH_1):PAGE59_I1@PURE_QUANTA.GENOA_SP5(CHIPS)':
 'VSS_BN32': CDS_PINID='VSS_BN32';
NODE_NAME     U26 BN34
 '@T6G_MB_LIB.T6G(SCH_1):PAGE59_I1@PURE_QUANTA.GENOA_SP5(CHIPS)':
 'VSS_BN34': CDS_PINID='VSS_BN34';
NODE_NAME     U26 BN36
 '@T6G_MB_LIB.T6G(SCH_1):PAGE59_I1@PURE_QUANTA.GENOA_SP5(CHIPS)':
 'VSS_BN36': CDS_PINID='VSS_BN36';
NODE_NAME     U26 BN41
 '@T6G_MB_LIB.T6G(SCH_1):PAGE59_I1@PURE_QUANTA.GENOA_SP5(CHIPS)':
 'VSS_BN41': CDS_PINID='VSS_BN41';
NODE_NAME     U26 BN43
 '@T6G_MB_LIB.T6G(SCH_1):PAGE59_I1@PURE_QUANTA.GENOA_SP5(CHIPS)':
 'VSS_BN43': CDS_PINID='VSS_BN43';
NODE_NAME     U26 BN45
 '@T6G_MB_LIB.T6G(SCH_1):PAGE59_I1@PURE_QUANTA.GENOA_SP5(CHIPS)':
 'VSS_BN45': CDS_PINID='VSS_BN45';
NODE_NAME     U26 BN47
 '@T6G_MB_LIB.T6G(SCH_1):PAGE59_I1@PURE_QUANTA.GENOA_SP5(CHIPS)':
 'VSS_BN47': CDS_PINID='VSS_BN47';
NODE_NAME     U26 BN49
 '@T6G_MB_LIB.T6G(SCH_1):PAGE59_I1@PURE_QUANTA.GENOA_SP5(CHIPS)':
 'VSS_BN49': CDS_PINID='VSS_BN49';
NODE_NAME     U26 BN51
 '@T6G_MB_LIB.T6G(SCH_1):PAGE59_I1@PURE_QUANTA.GENOA_SP5(CHIPS)':
 'VSS_BN51': CDS_PINID='VSS_BN51';
NODE_NAME     U26 BN53
 '@T6G_MB_LIB.T6G(SCH_1):PAGE59_I1@PURE_QUANTA.GENOA_SP5(CHIPS)':
 'VSS_BN53': CDS_PINID='VSS_BN53';
NODE_NAME     U26 BN56
 '@T6G_MB_LIB.T6G(SCH_1):PAGE59_I1@PURE_QUANTA.GENOA_SP5(CHIPS)':
 'VSS_BN56': CDS_PINID='VSS_BN56';
NODE_NAME     U26 BN58
 '@T6G_MB_LIB.T6G(SCH_1):PAGE59_I1@PURE_QUANTA.GENOA_SP5(CHIPS)':
 'VSS_BN58': CDS_PINID='VSS_BN58';
NODE_NAME     U26 BN61
 '@T6G_MB_LIB.T6G(SCH_1):PAGE59_I1@PURE_QUANTA.GENOA_SP5(CHIPS)':
 'VSS_BN61': CDS_PINID='VSS_BN61';
NODE_NAME     U26 BN63
 '@T6G_MB_LIB.T6G(SCH_1):PAGE59_I1@PURE_QUANTA.GENOA_SP5(CHIPS)':
 'VSS_BN63': CDS_PINID='VSS_BN63';
NODE_NAME     U26 BN65
 '@T6G_MB_LIB.T6G(SCH_1):PAGE59_I1@PURE_QUANTA.GENOA_SP5(CHIPS)':
 'VSS_BN65': CDS_PINID='VSS_BN65';
NODE_NAME     U26 BN68
 '@T6G_MB_LIB.T6G(SCH_1):PAGE59_I1@PURE_QUANTA.GENOA_SP5(CHIPS)':
 'VSS_BN68': CDS_PINID='VSS_BN68';
NODE_NAME     U26 BN70
 '@T6G_MB_LIB.T6G(SCH_1):PAGE59_I1@PURE_QUANTA.GENOA_SP5(CHIPS)':
 'VSS_BN70': CDS_PINID='VSS_BN70';
NODE_NAME     U26 BN72
 '@T6G_MB_LIB.T6G(SCH_1):PAGE59_I1@PURE_QUANTA.GENOA_SP5(CHIPS)':
 'VSS_BN72': CDS_PINID='VSS_BN72';
NODE_NAME     U26 BN75
 '@T6G_MB_LIB.T6G(SCH_1):PAGE59_I1@PURE_QUANTA.GENOA_SP5(CHIPS)':
 'VSS_BN75': CDS_PINID='VSS_BN75';
NODE_NAME     U26 BP3
 '@T6G_MB_LIB.T6G(SCH_1):PAGE59_I1@PURE_QUANTA.GENOA_SP5(CHIPS)':
 'VSS_BP3': CDS_PINID='VSS_BP3';
NODE_NAME     U26 BP5
 '@T6G_MB_LIB.T6G(SCH_1):PAGE59_I1@PURE_QUANTA.GENOA_SP5(CHIPS)':
 'VSS_BP5': CDS_PINID='VSS_BP5';
NODE_NAME     U26 BP8
 '@T6G_MB_LIB.T6G(SCH_1):PAGE59_I1@PURE_QUANTA.GENOA_SP5(CHIPS)':
 'VSS_BP8': CDS_PINID='VSS_BP8';
NODE_NAME     U26 BP10
 '@T6G_MB_LIB.T6G(SCH_1):PAGE59_I1@PURE_QUANTA.GENOA_SP5(CHIPS)':
 'VSS_BP10': CDS_PINID='VSS_BP10';
NODE_NAME     U26 BP12
 '@T6G_MB_LIB.T6G(SCH_1):PAGE59_I1@PURE_QUANTA.GENOA_SP5(CHIPS)':
 'VSS_BP12': CDS_PINID='VSS_BP12';
NODE_NAME     U26 BP15
 '@T6G_MB_LIB.T6G(SCH_1):PAGE59_I1@PURE_QUANTA.GENOA_SP5(CHIPS)':
 'VSS_BP15': CDS_PINID='VSS_BP15';
NODE_NAME     U26 BP17
 '@T6G_MB_LIB.T6G(SCH_1):PAGE59_I1@PURE_QUANTA.GENOA_SP5(CHIPS)':
 'VSS_BP17': CDS_PINID='VSS_BP17';
NODE_NAME     U26 BP19
 '@T6G_MB_LIB.T6G(SCH_1):PAGE59_I1@PURE_QUANTA.GENOA_SP5(CHIPS)':
 'VSS_BP19': CDS_PINID='VSS_BP19';
NODE_NAME     U26 BP23
 '@T6G_MB_LIB.T6G(SCH_1):PAGE59_I1@PURE_QUANTA.GENOA_SP5(CHIPS)':
 'VSS_BP23': CDS_PINID='VSS_BP23';
NODE_NAME     U26 BP25
 '@T6G_MB_LIB.T6G(SCH_1):PAGE59_I1@PURE_QUANTA.GENOA_SP5(CHIPS)':
 'VSS_BP25': CDS_PINID='VSS_BP25';
NODE_NAME     U26 BP27
 '@T6G_MB_LIB.T6G(SCH_1):PAGE59_I1@PURE_QUANTA.GENOA_SP5(CHIPS)':
 'VSS_BP27': CDS_PINID='VSS_BP27';
NODE_NAME     U26 BP29
 '@T6G_MB_LIB.T6G(SCH_1):PAGE59_I1@PURE_QUANTA.GENOA_SP5(CHIPS)':
 'VSS_BP29': CDS_PINID='VSS_BP29';
NODE_NAME     U26 BP31
 '@T6G_MB_LIB.T6G(SCH_1):PAGE59_I1@PURE_QUANTA.GENOA_SP5(CHIPS)':
 'VSS_BP31': CDS_PINID='VSS_BP31';
NODE_NAME     U26 BP33
 '@T6G_MB_LIB.T6G(SCH_1):PAGE59_I1@PURE_QUANTA.GENOA_SP5(CHIPS)':
 'VSS_BP33': CDS_PINID='VSS_BP33';
NODE_NAME     U26 BP35
 '@T6G_MB_LIB.T6G(SCH_1):PAGE59_I1@PURE_QUANTA.GENOA_SP5(CHIPS)':
 'VSS_BP35': CDS_PINID='VSS_BP35';
NODE_NAME     U26 BP37
 '@T6G_MB_LIB.T6G(SCH_1):PAGE59_I1@PURE_QUANTA.GENOA_SP5(CHIPS)':
 'VSS_BP37': CDS_PINID='VSS_BP37';
NODE_NAME     U26 BP40
 '@T6G_MB_LIB.T6G(SCH_1):PAGE59_I1@PURE_QUANTA.GENOA_SP5(CHIPS)':
 'VSS_BP40': CDS_PINID='VSS_BP40';
NODE_NAME     U26 BP42
 '@T6G_MB_LIB.T6G(SCH_1):PAGE59_I1@PURE_QUANTA.GENOA_SP5(CHIPS)':
 'VSS_BP42': CDS_PINID='VSS_BP42';
NODE_NAME     U26 BP44
 '@T6G_MB_LIB.T6G(SCH_1):PAGE59_I1@PURE_QUANTA.GENOA_SP5(CHIPS)':
 'VSS_BP44': CDS_PINID='VSS_BP44';
NODE_NAME     U26 BP46
 '@T6G_MB_LIB.T6G(SCH_1):PAGE59_I1@PURE_QUANTA.GENOA_SP5(CHIPS)':
 'VSS_BP46': CDS_PINID='VSS_BP46';
NODE_NAME     U26 BP48
 '@T6G_MB_LIB.T6G(SCH_1):PAGE59_I1@PURE_QUANTA.GENOA_SP5(CHIPS)':
 'VSS_BP48': CDS_PINID='VSS_BP48';
NODE_NAME     U26 BP50
 '@T6G_MB_LIB.T6G(SCH_1):PAGE59_I1@PURE_QUANTA.GENOA_SP5(CHIPS)':
 'VSS_BP50': CDS_PINID='VSS_BP50';
NODE_NAME     U26 BP52
 '@T6G_MB_LIB.T6G(SCH_1):PAGE59_I1@PURE_QUANTA.GENOA_SP5(CHIPS)':
 'VSS_BP52': CDS_PINID='VSS_BP52';
NODE_NAME     U26 BP54
 '@T6G_MB_LIB.T6G(SCH_1):PAGE59_I1@PURE_QUANTA.GENOA_SP5(CHIPS)':
 'VSS_BP54': CDS_PINID='VSS_BP54';
NODE_NAME     U26 BP57
 '@T6G_MB_LIB.T6G(SCH_1):PAGE59_I1@PURE_QUANTA.GENOA_SP5(CHIPS)':
 'VSS_BP57': CDS_PINID='VSS_BP57';
NODE_NAME     U26 BP59
 '@T6G_MB_LIB.T6G(SCH_1):PAGE59_I1@PURE_QUANTA.GENOA_SP5(CHIPS)':
 'VSS_BP59': CDS_PINID='VSS_BP59';
NODE_NAME     U26 BP61
 '@T6G_MB_LIB.T6G(SCH_1):PAGE59_I1@PURE_QUANTA.GENOA_SP5(CHIPS)':
 'VSS_BP61': CDS_PINID='VSS_BP61';
NODE_NAME     U26 BP64
 '@T6G_MB_LIB.T6G(SCH_1):PAGE59_I1@PURE_QUANTA.GENOA_SP5(CHIPS)':
 'VSS_BP64': CDS_PINID='VSS_BP64';
NODE_NAME     U26 BP66
 '@T6G_MB_LIB.T6G(SCH_1):PAGE59_I1@PURE_QUANTA.GENOA_SP5(CHIPS)':
 'VSS_BP66': CDS_PINID='VSS_BP66';
NODE_NAME     U26 BP68
 '@T6G_MB_LIB.T6G(SCH_1):PAGE59_I1@PURE_QUANTA.GENOA_SP5(CHIPS)':
 'VSS_BP68': CDS_PINID='VSS_BP68';
NODE_NAME     U26 BP71
 '@T6G_MB_LIB.T6G(SCH_1):PAGE59_I1@PURE_QUANTA.GENOA_SP5(CHIPS)':
 'VSS_BP71': CDS_PINID='VSS_BP71';
NODE_NAME     U26 BP73
 '@T6G_MB_LIB.T6G(SCH_1):PAGE59_I1@PURE_QUANTA.GENOA_SP5(CHIPS)':
 'VSS_BP73': CDS_PINID='VSS_BP73';
NODE_NAME     U26 BR1
 '@T6G_MB_LIB.T6G(SCH_1):PAGE59_I1@PURE_QUANTA.GENOA_SP5(CHIPS)':
 'VSS_BR1': CDS_PINID='VSS_BR1';
NODE_NAME     U26 BR3
 '@T6G_MB_LIB.T6G(SCH_1):PAGE59_I1@PURE_QUANTA.GENOA_SP5(CHIPS)':
 'VSS_BR3': CDS_PINID='VSS_BR3';
NODE_NAME     U26 BR6
 '@T6G_MB_LIB.T6G(SCH_1):PAGE59_I1@PURE_QUANTA.GENOA_SP5(CHIPS)':
 'VSS_BR6': CDS_PINID='VSS_BR6';
NODE_NAME     U26 BR7
 '@T6G_MB_LIB.T6G(SCH_1):PAGE59_I1@PURE_QUANTA.GENOA_SP5(CHIPS)':
 'VSS_BR7': CDS_PINID='VSS_BR7';
NODE_NAME     U26 BR8
 '@T6G_MB_LIB.T6G(SCH_1):PAGE59_I1@PURE_QUANTA.GENOA_SP5(CHIPS)':
 'VSS_BR8': CDS_PINID='VSS_BR8';
NODE_NAME     U26 BR10
 '@T6G_MB_LIB.T6G(SCH_1):PAGE59_I1@PURE_QUANTA.GENOA_SP5(CHIPS)':
 'VSS_BR10': CDS_PINID='VSS_BR10';
NODE_NAME     U26 BR13
 '@T6G_MB_LIB.T6G(SCH_1):PAGE59_I1@PURE_QUANTA.GENOA_SP5(CHIPS)':
 'VSS_BR13': CDS_PINID='VSS_BR13';
NODE_NAME     U26 BR14
 '@T6G_MB_LIB.T6G(SCH_1):PAGE59_I1@PURE_QUANTA.GENOA_SP5(CHIPS)':
 'VSS_BR14': CDS_PINID='VSS_BR14';
NODE_NAME     U26 BR15
 '@T6G_MB_LIB.T6G(SCH_1):PAGE59_I1@PURE_QUANTA.GENOA_SP5(CHIPS)':
 'VSS_BR15': CDS_PINID='VSS_BR15';
NODE_NAME     U26 BR17
 '@T6G_MB_LIB.T6G(SCH_1):PAGE59_I1@PURE_QUANTA.GENOA_SP5(CHIPS)':
 'VSS_BR17': CDS_PINID='VSS_BR17';
NODE_NAME     U26 BR20
 '@T6G_MB_LIB.T6G(SCH_1):PAGE59_I1@PURE_QUANTA.GENOA_SP5(CHIPS)':
 'VSS_BR20': CDS_PINID='VSS_BR20';
NODE_NAME     U26 BR21
 '@T6G_MB_LIB.T6G(SCH_1):PAGE59_I1@PURE_QUANTA.GENOA_SP5(CHIPS)':
 'VSS_BR21': CDS_PINID='VSS_BR21';
NODE_NAME     U26 BR22
 '@T6G_MB_LIB.T6G(SCH_1):PAGE59_I1@PURE_QUANTA.GENOA_SP5(CHIPS)':
 'VSS_BR22': CDS_PINID='VSS_BR22';
NODE_NAME     U26 BR24
 '@T6G_MB_LIB.T6G(SCH_1):PAGE59_I1@PURE_QUANTA.GENOA_SP5(CHIPS)':
 'VSS_BR24': CDS_PINID='VSS_BR24';
NODE_NAME     U26 BR26
 '@T6G_MB_LIB.T6G(SCH_1):PAGE59_I1@PURE_QUANTA.GENOA_SP5(CHIPS)':
 'VSS_BR26': CDS_PINID='VSS_BR26';
NODE_NAME     U26 BR28
 '@T6G_MB_LIB.T6G(SCH_1):PAGE59_I1@PURE_QUANTA.GENOA_SP5(CHIPS)':
 'VSS_BR28': CDS_PINID='VSS_BR28';
NODE_NAME     U26 BR30
 '@T6G_MB_LIB.T6G(SCH_1):PAGE59_I1@PURE_QUANTA.GENOA_SP5(CHIPS)':
 'VSS_BR30': CDS_PINID='VSS_BR30';
NODE_NAME     U26 BR32
 '@T6G_MB_LIB.T6G(SCH_1):PAGE59_I1@PURE_QUANTA.GENOA_SP5(CHIPS)':
 'VSS_BR32': CDS_PINID='VSS_BR32';
NODE_NAME     U26 BR34
 '@T6G_MB_LIB.T6G(SCH_1):PAGE59_I1@PURE_QUANTA.GENOA_SP5(CHIPS)':
 'VSS_BR34': CDS_PINID='VSS_BR34';
NODE_NAME     U26 BR36
 '@T6G_MB_LIB.T6G(SCH_1):PAGE59_I1@PURE_QUANTA.GENOA_SP5(CHIPS)':
 'VSS_BR36': CDS_PINID='VSS_BR36';
NODE_NAME     U26 BR41
 '@T6G_MB_LIB.T6G(SCH_1):PAGE59_I1@PURE_QUANTA.GENOA_SP5(CHIPS)':
 'VSS_BR41': CDS_PINID='VSS_BR41';
NODE_NAME     U26 BR43
 '@T6G_MB_LIB.T6G(SCH_1):PAGE59_I1@PURE_QUANTA.GENOA_SP5(CHIPS)':
 'VSS_BR43': CDS_PINID='VSS_BR43';
NODE_NAME     U26 BR45
 '@T6G_MB_LIB.T6G(SCH_1):PAGE59_I1@PURE_QUANTA.GENOA_SP5(CHIPS)':
 'VSS_BR45': CDS_PINID='VSS_BR45';
NODE_NAME     U26 BR47
 '@T6G_MB_LIB.T6G(SCH_1):PAGE59_I1@PURE_QUANTA.GENOA_SP5(CHIPS)':
 'VSS_BR47': CDS_PINID='VSS_BR47';
NODE_NAME     U26 BR49
 '@T6G_MB_LIB.T6G(SCH_1):PAGE59_I1@PURE_QUANTA.GENOA_SP5(CHIPS)':
 'VSS_BR49': CDS_PINID='VSS_BR49';
NODE_NAME     U26 BR51
 '@T6G_MB_LIB.T6G(SCH_1):PAGE59_I1@PURE_QUANTA.GENOA_SP5(CHIPS)':
 'VSS_BR51': CDS_PINID='VSS_BR51';
NODE_NAME     U26 BR55
 '@T6G_MB_LIB.T6G(SCH_1):PAGE59_I1@PURE_QUANTA.GENOA_SP5(CHIPS)':
 'VSS_BR55': CDS_PINID='VSS_BR55';
NODE_NAME     U26 BR56
 '@T6G_MB_LIB.T6G(SCH_1):PAGE59_I1@PURE_QUANTA.GENOA_SP5(CHIPS)':
 'VSS_BR56': CDS_PINID='VSS_BR56';
NODE_NAME     U26 BR59
 '@T6G_MB_LIB.T6G(SCH_1):PAGE59_I1@PURE_QUANTA.GENOA_SP5(CHIPS)':
 'VSS_BR59': CDS_PINID='VSS_BR59';
NODE_NAME     U26 BR61
 '@T6G_MB_LIB.T6G(SCH_1):PAGE59_I1@PURE_QUANTA.GENOA_SP5(CHIPS)':
 'VSS_BR61': CDS_PINID='VSS_BR61';
NODE_NAME     U26 BR62
 '@T6G_MB_LIB.T6G(SCH_1):PAGE59_I1@PURE_QUANTA.GENOA_SP5(CHIPS)':
 'VSS_BR62': CDS_PINID='VSS_BR62';
NODE_NAME     U26 BR63
 '@T6G_MB_LIB.T6G(SCH_1):PAGE59_I1@PURE_QUANTA.GENOA_SP5(CHIPS)':
 'VSS_BR63': CDS_PINID='VSS_BR63';
NODE_NAME     U26 BR66
 '@T6G_MB_LIB.T6G(SCH_1):PAGE59_I1@PURE_QUANTA.GENOA_SP5(CHIPS)':
 'VSS_BR66': CDS_PINID='VSS_BR66';
NODE_NAME     U26 BR68
 '@T6G_MB_LIB.T6G(SCH_1):PAGE59_I1@PURE_QUANTA.GENOA_SP5(CHIPS)':
 'VSS_BR68': CDS_PINID='VSS_BR68';
NODE_NAME     U26 BR69
 '@T6G_MB_LIB.T6G(SCH_1):PAGE59_I1@PURE_QUANTA.GENOA_SP5(CHIPS)':
 'VSS_BR69': CDS_PINID='VSS_BR69';
NODE_NAME     U26 BR70
 '@T6G_MB_LIB.T6G(SCH_1):PAGE59_I1@PURE_QUANTA.GENOA_SP5(CHIPS)':
 'VSS_BR70': CDS_PINID='VSS_BR70';
NODE_NAME     U26 BR73
 '@T6G_MB_LIB.T6G(SCH_1):PAGE59_I1@PURE_QUANTA.GENOA_SP5(CHIPS)':
 'VSS_BR73': CDS_PINID='VSS_BR73';
NODE_NAME     U26 BR75
 '@T6G_MB_LIB.T6G(SCH_1):PAGE59_I1@PURE_QUANTA.GENOA_SP5(CHIPS)':
 'VSS_BR75': CDS_PINID='VSS_BR75';
NODE_NAME     U26 BT3
 '@T6G_MB_LIB.T6G(SCH_1):PAGE59_I1@PURE_QUANTA.GENOA_SP5(CHIPS)':
 'VSS_BT3': CDS_PINID='VSS_BT3';
NODE_NAME     U26 BT4
 '@T6G_MB_LIB.T6G(SCH_1):PAGE59_I1@PURE_QUANTA.GENOA_SP5(CHIPS)':
 'VSS_BT4': CDS_PINID='VSS_BT4';
NODE_NAME     U26 BT5
 '@T6G_MB_LIB.T6G(SCH_1):PAGE59_I1@PURE_QUANTA.GENOA_SP5(CHIPS)':
 'VSS_BT5': CDS_PINID='VSS_BT5';
NODE_NAME     U26 BT7
 '@T6G_MB_LIB.T6G(SCH_1):PAGE59_I1@PURE_QUANTA.GENOA_SP5(CHIPS)':
 'VSS_BT7': CDS_PINID='VSS_BT7';
NODE_NAME     U26 BT8
 '@T6G_MB_LIB.T6G(SCH_1):PAGE59_I1@PURE_QUANTA.GENOA_SP5(CHIPS)':
 'VSS_BT8': CDS_PINID='VSS_BT8';
NODE_NAME     U26 BT10
 '@T6G_MB_LIB.T6G(SCH_1):PAGE59_I1@PURE_QUANTA.GENOA_SP5(CHIPS)':
 'VSS_BT10': CDS_PINID='VSS_BT10';
NODE_NAME     U26 BT11
 '@T6G_MB_LIB.T6G(SCH_1):PAGE59_I1@PURE_QUANTA.GENOA_SP5(CHIPS)':
 'VSS_BT11': CDS_PINID='VSS_BT11';
NODE_NAME     U26 BT12
 '@T6G_MB_LIB.T6G(SCH_1):PAGE59_I1@PURE_QUANTA.GENOA_SP5(CHIPS)':
 'VSS_BT12': CDS_PINID='VSS_BT12';
NODE_NAME     U26 BT14
 '@T6G_MB_LIB.T6G(SCH_1):PAGE59_I1@PURE_QUANTA.GENOA_SP5(CHIPS)':
 'VSS_BT14': CDS_PINID='VSS_BT14';
NODE_NAME     U26 BT15
 '@T6G_MB_LIB.T6G(SCH_1):PAGE59_I1@PURE_QUANTA.GENOA_SP5(CHIPS)':
 'VSS_BT15': CDS_PINID='VSS_BT15';
NODE_NAME     U26 BT17
 '@T6G_MB_LIB.T6G(SCH_1):PAGE59_I1@PURE_QUANTA.GENOA_SP5(CHIPS)':
 'VSS_BT17': CDS_PINID='VSS_BT17';
NODE_NAME     U26 BT18
 '@T6G_MB_LIB.T6G(SCH_1):PAGE59_I1@PURE_QUANTA.GENOA_SP5(CHIPS)':
 'VSS_BT18': CDS_PINID='VSS_BT18';
NODE_NAME     U26 BT19
 '@T6G_MB_LIB.T6G(SCH_1):PAGE59_I1@PURE_QUANTA.GENOA_SP5(CHIPS)':
 'VSS_BT19': CDS_PINID='VSS_BT19';
NODE_NAME     U26 BT21
 '@T6G_MB_LIB.T6G(SCH_1):PAGE59_I1@PURE_QUANTA.GENOA_SP5(CHIPS)':
 'VSS_BT21': CDS_PINID='VSS_BT21';
NODE_NAME     U26 BT22
 '@T6G_MB_LIB.T6G(SCH_1):PAGE59_I1@PURE_QUANTA.GENOA_SP5(CHIPS)':
 'VSS_BT22': CDS_PINID='VSS_BT22';
NODE_NAME     U26 BT25
 '@T6G_MB_LIB.T6G(SCH_1):PAGE59_I1@PURE_QUANTA.GENOA_SP5(CHIPS)':
 'VSS_BT25': CDS_PINID='VSS_BT25';
NODE_NAME     U26 BT28
 '@T6G_MB_LIB.T6G(SCH_1):PAGE59_I1@PURE_QUANTA.GENOA_SP5(CHIPS)':
 'VSS_BT28': CDS_PINID='VSS_BT28';
NODE_NAME     U26 BT31
 '@T6G_MB_LIB.T6G(SCH_1):PAGE59_I1@PURE_QUANTA.GENOA_SP5(CHIPS)':
 'VSS_BT31': CDS_PINID='VSS_BT31';
NODE_NAME     U26 BT34
 '@T6G_MB_LIB.T6G(SCH_1):PAGE59_I1@PURE_QUANTA.GENOA_SP5(CHIPS)':
 'VSS_BT34': CDS_PINID='VSS_BT34';
NODE_NAME     U26 BT37
 '@T6G_MB_LIB.T6G(SCH_1):PAGE59_I1@PURE_QUANTA.GENOA_SP5(CHIPS)':
 'VSS_BT37': CDS_PINID='VSS_BT37';
NODE_NAME     U26 BT39
 '@T6G_MB_LIB.T6G(SCH_1):PAGE59_I1@PURE_QUANTA.GENOA_SP5(CHIPS)':
 'VSS_BT39': CDS_PINID='VSS_BT39';
NODE_NAME     U26 BT42
 '@T6G_MB_LIB.T6G(SCH_1):PAGE59_I1@PURE_QUANTA.GENOA_SP5(CHIPS)':
 'VSS_BT42': CDS_PINID='VSS_BT42';
NODE_NAME     U26 BT45
 '@T6G_MB_LIB.T6G(SCH_1):PAGE59_I1@PURE_QUANTA.GENOA_SP5(CHIPS)':
 'VSS_BT45': CDS_PINID='VSS_BT45';
NODE_NAME     U26 BT48
 '@T6G_MB_LIB.T6G(SCH_1):PAGE59_I1@PURE_QUANTA.GENOA_SP5(CHIPS)':
 'VSS_BT48': CDS_PINID='VSS_BT48';
NODE_NAME     U26 BT51
 '@T6G_MB_LIB.T6G(SCH_1):PAGE59_I1@PURE_QUANTA.GENOA_SP5(CHIPS)':
 'VSS_BT51': CDS_PINID='VSS_BT51';
NODE_NAME     U26 BT54
 '@T6G_MB_LIB.T6G(SCH_1):PAGE59_I1@PURE_QUANTA.GENOA_SP5(CHIPS)':
 'VSS_BT54': CDS_PINID='VSS_BT54';
NODE_NAME     U26 BT55
 '@T6G_MB_LIB.T6G(SCH_1):PAGE59_I1@PURE_QUANTA.GENOA_SP5(CHIPS)':
 'VSS_BT55': CDS_PINID='VSS_BT55';
NODE_NAME     U26 BT57
 '@T6G_MB_LIB.T6G(SCH_1):PAGE59_I1@PURE_QUANTA.GENOA_SP5(CHIPS)':
 'VSS_BT57': CDS_PINID='VSS_BT57';
NODE_NAME     U26 BT58
 '@T6G_MB_LIB.T6G(SCH_1):PAGE59_I1@PURE_QUANTA.GENOA_SP5(CHIPS)':
 'VSS_BT58': CDS_PINID='VSS_BT58';
NODE_NAME     U26 BT59
 '@T6G_MB_LIB.T6G(SCH_1):PAGE59_I1@PURE_QUANTA.GENOA_SP5(CHIPS)':
 'VSS_BT59': CDS_PINID='VSS_BT59';
NODE_NAME     U26 BT61
 '@T6G_MB_LIB.T6G(SCH_1):PAGE59_I1@PURE_QUANTA.GENOA_SP5(CHIPS)':
 'VSS_BT61': CDS_PINID='VSS_BT61';
NODE_NAME     U26 BT62
 '@T6G_MB_LIB.T6G(SCH_1):PAGE59_I1@PURE_QUANTA.GENOA_SP5(CHIPS)':
 'VSS_BT62': CDS_PINID='VSS_BT62';
NODE_NAME     U26 BT64
 '@T6G_MB_LIB.T6G(SCH_1):PAGE59_I1@PURE_QUANTA.GENOA_SP5(CHIPS)':
 'VSS_BT64': CDS_PINID='VSS_BT64';
NODE_NAME     U26 BT65
 '@T6G_MB_LIB.T6G(SCH_1):PAGE59_I1@PURE_QUANTA.GENOA_SP5(CHIPS)':
 'VSS_BT65': CDS_PINID='VSS_BT65';
NODE_NAME     U26 BT66
 '@T6G_MB_LIB.T6G(SCH_1):PAGE59_I1@PURE_QUANTA.GENOA_SP5(CHIPS)':
 'VSS_BT66': CDS_PINID='VSS_BT66';
NODE_NAME     U26 BT68
 '@T6G_MB_LIB.T6G(SCH_1):PAGE59_I1@PURE_QUANTA.GENOA_SP5(CHIPS)':
 'VSS_BT68': CDS_PINID='VSS_BT68';
NODE_NAME     U26 BT69
 '@T6G_MB_LIB.T6G(SCH_1):PAGE59_I1@PURE_QUANTA.GENOA_SP5(CHIPS)':
 'VSS_BT69': CDS_PINID='VSS_BT69';
NODE_NAME     U26 BT71
 '@T6G_MB_LIB.T6G(SCH_1):PAGE59_I1@PURE_QUANTA.GENOA_SP5(CHIPS)':
 'VSS_BT71': CDS_PINID='VSS_BT71';
NODE_NAME     U26 BT72
 '@T6G_MB_LIB.T6G(SCH_1):PAGE59_I1@PURE_QUANTA.GENOA_SP5(CHIPS)':
 'VSS_BT72': CDS_PINID='VSS_BT72';
NODE_NAME     U26 BT73
 '@T6G_MB_LIB.T6G(SCH_1):PAGE59_I1@PURE_QUANTA.GENOA_SP5(CHIPS)':
 'VSS_BT73': CDS_PINID='VSS_BT73';
NODE_NAME     U26 BU1
 '@T6G_MB_LIB.T6G(SCH_1):PAGE59_I1@PURE_QUANTA.GENOA_SP5(CHIPS)':
 'VSS_BU1': CDS_PINID='VSS_BU1';
NODE_NAME     U26 BU4
 '@T6G_MB_LIB.T6G(SCH_1):PAGE59_I1@PURE_QUANTA.GENOA_SP5(CHIPS)':
 'VSS_BU4': CDS_PINID='VSS_BU4';
NODE_NAME     U26 BU6
 '@T6G_MB_LIB.T6G(SCH_1):PAGE59_I1@PURE_QUANTA.GENOA_SP5(CHIPS)':
 'VSS_BU6': CDS_PINID='VSS_BU6';
NODE_NAME     U26 BU8
 '@T6G_MB_LIB.T6G(SCH_1):PAGE59_I1@PURE_QUANTA.GENOA_SP5(CHIPS)':
 'VSS_BU8': CDS_PINID='VSS_BU8';
NODE_NAME     U26 BU11
 '@T6G_MB_LIB.T6G(SCH_1):PAGE59_I1@PURE_QUANTA.GENOA_SP5(CHIPS)':
 'VSS_BU11': CDS_PINID='VSS_BU11';
NODE_NAME     U26 BU13
 '@T6G_MB_LIB.T6G(SCH_1):PAGE59_I1@PURE_QUANTA.GENOA_SP5(CHIPS)':
 'VSS_BU13': CDS_PINID='VSS_BU13';
NODE_NAME     U26 BU15
 '@T6G_MB_LIB.T6G(SCH_1):PAGE59_I1@PURE_QUANTA.GENOA_SP5(CHIPS)':
 'VSS_BU15': CDS_PINID='VSS_BU15';
NODE_NAME     U26 BU18
 '@T6G_MB_LIB.T6G(SCH_1):PAGE59_I1@PURE_QUANTA.GENOA_SP5(CHIPS)':
 'VSS_BU18': CDS_PINID='VSS_BU18';
NODE_NAME     U26 BU20
 '@T6G_MB_LIB.T6G(SCH_1):PAGE59_I1@PURE_QUANTA.GENOA_SP5(CHIPS)':
 'VSS_BU20': CDS_PINID='VSS_BU20';
NODE_NAME     U26 BU22
 '@T6G_MB_LIB.T6G(SCH_1):PAGE59_I1@PURE_QUANTA.GENOA_SP5(CHIPS)':
 'VSS_BU22': CDS_PINID='VSS_BU22';
NODE_NAME     U26 BU25
 '@T6G_MB_LIB.T6G(SCH_1):PAGE59_I1@PURE_QUANTA.GENOA_SP5(CHIPS)':
 'VSS_BU25': CDS_PINID='VSS_BU25';
NODE_NAME     U26 BU28
 '@T6G_MB_LIB.T6G(SCH_1):PAGE59_I1@PURE_QUANTA.GENOA_SP5(CHIPS)':
 'VSS_BU28': CDS_PINID='VSS_BU28';
NODE_NAME     U26 BU31
 '@T6G_MB_LIB.T6G(SCH_1):PAGE59_I1@PURE_QUANTA.GENOA_SP5(CHIPS)':
 'VSS_BU31': CDS_PINID='VSS_BU31';
NODE_NAME     U26 BU34
 '@T6G_MB_LIB.T6G(SCH_1):PAGE59_I1@PURE_QUANTA.GENOA_SP5(CHIPS)':
 'VSS_BU34': CDS_PINID='VSS_BU34';
NODE_NAME     U26 BU35
 '@T6G_MB_LIB.T6G(SCH_1):PAGE59_I1@PURE_QUANTA.GENOA_SP5(CHIPS)':
 'VSS_BU35': CDS_PINID='VSS_BU35';
NODE_NAME     U26 BU36
 '@T6G_MB_LIB.T6G(SCH_1):PAGE59_I1@PURE_QUANTA.GENOA_SP5(CHIPS)':
 'VSS_BU36': CDS_PINID='VSS_BU36';
NODE_NAME     U26 BU40
 '@T6G_MB_LIB.T6G(SCH_1):PAGE59_I1@PURE_QUANTA.GENOA_SP5(CHIPS)':
 'VSS_BU40': CDS_PINID='VSS_BU40';
NODE_NAME     U26 BU41
 '@T6G_MB_LIB.T6G(SCH_1):PAGE59_I1@PURE_QUANTA.GENOA_SP5(CHIPS)':
 'VSS_BU41': CDS_PINID='VSS_BU41';
NODE_NAME     U26 BU42
 '@T6G_MB_LIB.T6G(SCH_1):PAGE59_I1@PURE_QUANTA.GENOA_SP5(CHIPS)':
 'VSS_BU42': CDS_PINID='VSS_BU42';
NODE_NAME     U26 BU45
 '@T6G_MB_LIB.T6G(SCH_1):PAGE59_I1@PURE_QUANTA.GENOA_SP5(CHIPS)':
 'VSS_BU45': CDS_PINID='VSS_BU45';
NODE_NAME     U26 BU48
 '@T6G_MB_LIB.T6G(SCH_1):PAGE59_I1@PURE_QUANTA.GENOA_SP5(CHIPS)':
 'VSS_BU48': CDS_PINID='VSS_BU48';
NODE_NAME     U26 BU51
 '@T6G_MB_LIB.T6G(SCH_1):PAGE59_I1@PURE_QUANTA.GENOA_SP5(CHIPS)':
 'VSS_BU51': CDS_PINID='VSS_BU51';
NODE_NAME     U26 BU54
 '@T6G_MB_LIB.T6G(SCH_1):PAGE59_I1@PURE_QUANTA.GENOA_SP5(CHIPS)':
 'VSS_BU54': CDS_PINID='VSS_BU54';
NODE_NAME     U26 BU56
 '@T6G_MB_LIB.T6G(SCH_1):PAGE59_I1@PURE_QUANTA.GENOA_SP5(CHIPS)':
 'VSS_BU56': CDS_PINID='VSS_BU56';
NODE_NAME     U26 BU58
 '@T6G_MB_LIB.T6G(SCH_1):PAGE59_I1@PURE_QUANTA.GENOA_SP5(CHIPS)':
 'VSS_BU58': CDS_PINID='VSS_BU58';
NODE_NAME     U26 BU61
 '@T6G_MB_LIB.T6G(SCH_1):PAGE59_I1@PURE_QUANTA.GENOA_SP5(CHIPS)':
 'VSS_BU61': CDS_PINID='VSS_BU61';
NODE_NAME     U26 BU63
 '@T6G_MB_LIB.T6G(SCH_1):PAGE59_I1@PURE_QUANTA.GENOA_SP5(CHIPS)':
 'VSS_BU63': CDS_PINID='VSS_BU63';
NODE_NAME     U26 BU65
 '@T6G_MB_LIB.T6G(SCH_1):PAGE59_I1@PURE_QUANTA.GENOA_SP5(CHIPS)':
 'VSS_BU65': CDS_PINID='VSS_BU65';
NODE_NAME     U26 BU68
 '@T6G_MB_LIB.T6G(SCH_1):PAGE59_I1@PURE_QUANTA.GENOA_SP5(CHIPS)':
 'VSS_BU68': CDS_PINID='VSS_BU68';
NODE_NAME     U26 BU70
 '@T6G_MB_LIB.T6G(SCH_1):PAGE59_I1@PURE_QUANTA.GENOA_SP5(CHIPS)':
 'VSS_BU70': CDS_PINID='VSS_BU70';
NODE_NAME     U26 BU72
 '@T6G_MB_LIB.T6G(SCH_1):PAGE59_I1@PURE_QUANTA.GENOA_SP5(CHIPS)':
 'VSS_BU72': CDS_PINID='VSS_BU72';
NODE_NAME     U26 BU75
 '@T6G_MB_LIB.T6G(SCH_1):PAGE59_I1@PURE_QUANTA.GENOA_SP5(CHIPS)':
 'VSS_BU75': CDS_PINID='VSS_BU75';
NODE_NAME     U26 BV3
 '@T6G_MB_LIB.T6G(SCH_1):PAGE59_I1@PURE_QUANTA.GENOA_SP5(CHIPS)':
 'VSS_BV3': CDS_PINID='VSS_BV3';
NODE_NAME     U26 BV8
 '@T6G_MB_LIB.T6G(SCH_1):PAGE59_I1@PURE_QUANTA.GENOA_SP5(CHIPS)':
 'VSS_BV8': CDS_PINID='VSS_BV8';
NODE_NAME     U26 BV10
 '@T6G_MB_LIB.T6G(SCH_1):PAGE59_I1@PURE_QUANTA.GENOA_SP5(CHIPS)':
 'VSS_BV10': CDS_PINID='VSS_BV10';
NODE_NAME     U26 BV15
 '@T6G_MB_LIB.T6G(SCH_1):PAGE59_I1@PURE_QUANTA.GENOA_SP5(CHIPS)':
 'VSS_BV15': CDS_PINID='VSS_BV15';
NODE_NAME     U26 BV17
 '@T6G_MB_LIB.T6G(SCH_1):PAGE59_I1@PURE_QUANTA.GENOA_SP5(CHIPS)':
 'VSS_BV17': CDS_PINID='VSS_BV17';
NODE_NAME     U26 BV23
 '@T6G_MB_LIB.T6G(SCH_1):PAGE59_I1@PURE_QUANTA.GENOA_SP5(CHIPS)':
 'VSS_BV23': CDS_PINID='VSS_BV23';
NODE_NAME     U26 BV24
 '@T6G_MB_LIB.T6G(SCH_1):PAGE59_I1@PURE_QUANTA.GENOA_SP5(CHIPS)':
 'VSS_BV24': CDS_PINID='VSS_BV24';
NODE_NAME     U26 BV25
 '@T6G_MB_LIB.T6G(SCH_1):PAGE59_I1@PURE_QUANTA.GENOA_SP5(CHIPS)':
 'VSS_BV25': CDS_PINID='VSS_BV25';
NODE_NAME     U26 BV26
 '@T6G_MB_LIB.T6G(SCH_1):PAGE59_I1@PURE_QUANTA.GENOA_SP5(CHIPS)':
 'VSS_BV26': CDS_PINID='VSS_BV26';
NODE_NAME     U26 BV27
 '@T6G_MB_LIB.T6G(SCH_1):PAGE59_I1@PURE_QUANTA.GENOA_SP5(CHIPS)':
 'VSS_BV27': CDS_PINID='VSS_BV27';
NODE_NAME     U26 BV28
 '@T6G_MB_LIB.T6G(SCH_1):PAGE59_I1@PURE_QUANTA.GENOA_SP5(CHIPS)':
 'VSS_BV28': CDS_PINID='VSS_BV28';
NODE_NAME     U26 BV29
 '@T6G_MB_LIB.T6G(SCH_1):PAGE59_I1@PURE_QUANTA.GENOA_SP5(CHIPS)':
 'VSS_BV29': CDS_PINID='VSS_BV29';
NODE_NAME     U26 BV30
 '@T6G_MB_LIB.T6G(SCH_1):PAGE59_I1@PURE_QUANTA.GENOA_SP5(CHIPS)':
 'VSS_BV30': CDS_PINID='VSS_BV30';
NODE_NAME     U26 BV31
 '@T6G_MB_LIB.T6G(SCH_1):PAGE59_I1@PURE_QUANTA.GENOA_SP5(CHIPS)':
 'VSS_BV31': CDS_PINID='VSS_BV31';
NODE_NAME     U26 BV32
 '@T6G_MB_LIB.T6G(SCH_1):PAGE59_I1@PURE_QUANTA.GENOA_SP5(CHIPS)':
 'VSS_BV32': CDS_PINID='VSS_BV32';
NODE_NAME     U26 BV33
 '@T6G_MB_LIB.T6G(SCH_1):PAGE59_I1@PURE_QUANTA.GENOA_SP5(CHIPS)':
 'VSS_BV33': CDS_PINID='VSS_BV33';
NODE_NAME     U26 BV34
 '@T6G_MB_LIB.T6G(SCH_1):PAGE59_I1@PURE_QUANTA.GENOA_SP5(CHIPS)':
 'VSS_BV34': CDS_PINID='VSS_BV34';
NODE_NAME     U26 BV37
 '@T6G_MB_LIB.T6G(SCH_1):PAGE59_I1@PURE_QUANTA.GENOA_SP5(CHIPS)':
 'VSS_BV37': CDS_PINID='VSS_BV37';
NODE_NAME     U26 BV39
 '@T6G_MB_LIB.T6G(SCH_1):PAGE59_I1@PURE_QUANTA.GENOA_SP5(CHIPS)':
 'VSS_BV39': CDS_PINID='VSS_BV39';
NODE_NAME     U26 BV43
 '@T6G_MB_LIB.T6G(SCH_1):PAGE59_I1@PURE_QUANTA.GENOA_SP5(CHIPS)':
 'VSS_BV43': CDS_PINID='VSS_BV43';
NODE_NAME     U26 BV44
 '@T6G_MB_LIB.T6G(SCH_1):PAGE59_I1@PURE_QUANTA.GENOA_SP5(CHIPS)':
 'VSS_BV44': CDS_PINID='VSS_BV44';
NODE_NAME     U26 BV45
 '@T6G_MB_LIB.T6G(SCH_1):PAGE59_I1@PURE_QUANTA.GENOA_SP5(CHIPS)':
 'VSS_BV45': CDS_PINID='VSS_BV45';
NODE_NAME     U26 BV46
 '@T6G_MB_LIB.T6G(SCH_1):PAGE59_I2@PURE_QUANTA.GENOA_SP5(CHIPS)':
 'VSS_BV46': CDS_PINID='VSS_BV46';
NODE_NAME     U26 BV47
 '@T6G_MB_LIB.T6G(SCH_1):PAGE59_I2@PURE_QUANTA.GENOA_SP5(CHIPS)':
 'VSS_BV47': CDS_PINID='VSS_BV47';
NODE_NAME     U26 BV48
 '@T6G_MB_LIB.T6G(SCH_1):PAGE59_I2@PURE_QUANTA.GENOA_SP5(CHIPS)':
 'VSS_BV48': CDS_PINID='VSS_BV48';
NODE_NAME     U26 BV49
 '@T6G_MB_LIB.T6G(SCH_1):PAGE59_I2@PURE_QUANTA.GENOA_SP5(CHIPS)':
 'VSS_BV49': CDS_PINID='VSS_BV49';
NODE_NAME     U26 BV50
 '@T6G_MB_LIB.T6G(SCH_1):PAGE59_I2@PURE_QUANTA.GENOA_SP5(CHIPS)':
 'VSS_BV50': CDS_PINID='VSS_BV50';
NODE_NAME     U26 BV51
 '@T6G_MB_LIB.T6G(SCH_1):PAGE59_I2@PURE_QUANTA.GENOA_SP5(CHIPS)':
 'VSS_BV51': CDS_PINID='VSS_BV51';
NODE_NAME     U26 BV52
 '@T6G_MB_LIB.T6G(SCH_1):PAGE59_I2@PURE_QUANTA.GENOA_SP5(CHIPS)':
 'VSS_BV52': CDS_PINID='VSS_BV52';
NODE_NAME     U26 BV53
 '@T6G_MB_LIB.T6G(SCH_1):PAGE59_I2@PURE_QUANTA.GENOA_SP5(CHIPS)':
 'VSS_BV53': CDS_PINID='VSS_BV53';
NODE_NAME     U26 BV59
 '@T6G_MB_LIB.T6G(SCH_1):PAGE59_I2@PURE_QUANTA.GENOA_SP5(CHIPS)':
 'VSS_BV59': CDS_PINID='VSS_BV59';
NODE_NAME     U26 BV61
 '@T6G_MB_LIB.T6G(SCH_1):PAGE59_I2@PURE_QUANTA.GENOA_SP5(CHIPS)':
 'VSS_BV61': CDS_PINID='VSS_BV61';
NODE_NAME     U26 BV66
 '@T6G_MB_LIB.T6G(SCH_1):PAGE59_I2@PURE_QUANTA.GENOA_SP5(CHIPS)':
 'VSS_BV66': CDS_PINID='VSS_BV66';
NODE_NAME     U26 BV68
 '@T6G_MB_LIB.T6G(SCH_1):PAGE59_I2@PURE_QUANTA.GENOA_SP5(CHIPS)':
 'VSS_BV68': CDS_PINID='VSS_BV68';
NODE_NAME     U26 BV73
 '@T6G_MB_LIB.T6G(SCH_1):PAGE59_I2@PURE_QUANTA.GENOA_SP5(CHIPS)':
 'VSS_BV73': CDS_PINID='VSS_BV73';
NODE_NAME     U26 BW1
 '@T6G_MB_LIB.T6G(SCH_1):PAGE59_I2@PURE_QUANTA.GENOA_SP5(CHIPS)':
 'VSS_BW1': CDS_PINID='VSS_BW1';
NODE_NAME     U26 BW4
 '@T6G_MB_LIB.T6G(SCH_1):PAGE59_I2@PURE_QUANTA.GENOA_SP5(CHIPS)':
 'VSS_BW4': CDS_PINID='VSS_BW4';
NODE_NAME     U26 BW6
 '@T6G_MB_LIB.T6G(SCH_1):PAGE59_I2@PURE_QUANTA.GENOA_SP5(CHIPS)':
 'VSS_BW6': CDS_PINID='VSS_BW6';
NODE_NAME     U26 BW8
 '@T6G_MB_LIB.T6G(SCH_1):PAGE59_I2@PURE_QUANTA.GENOA_SP5(CHIPS)':
 'VSS_BW8': CDS_PINID='VSS_BW8';
NODE_NAME     U26 BW11
 '@T6G_MB_LIB.T6G(SCH_1):PAGE59_I2@PURE_QUANTA.GENOA_SP5(CHIPS)':
 'VSS_BW11': CDS_PINID='VSS_BW11';
NODE_NAME     U26 BW13
 '@T6G_MB_LIB.T6G(SCH_1):PAGE59_I2@PURE_QUANTA.GENOA_SP5(CHIPS)':
 'VSS_BW13': CDS_PINID='VSS_BW13';
NODE_NAME     U26 BW15
 '@T6G_MB_LIB.T6G(SCH_1):PAGE59_I2@PURE_QUANTA.GENOA_SP5(CHIPS)':
 'VSS_BW15': CDS_PINID='VSS_BW15';
NODE_NAME     U26 BW18
 '@T6G_MB_LIB.T6G(SCH_1):PAGE59_I2@PURE_QUANTA.GENOA_SP5(CHIPS)':
 'VSS_BW18': CDS_PINID='VSS_BW18';
NODE_NAME     U26 BW20
 '@T6G_MB_LIB.T6G(SCH_1):PAGE59_I2@PURE_QUANTA.GENOA_SP5(CHIPS)':
 'VSS_BW20': CDS_PINID='VSS_BW20';
NODE_NAME     U26 BW22
 '@T6G_MB_LIB.T6G(SCH_1):PAGE59_I2@PURE_QUANTA.GENOA_SP5(CHIPS)':
 'VSS_BW22': CDS_PINID='VSS_BW22';
NODE_NAME     U26 BW28
 '@T6G_MB_LIB.T6G(SCH_1):PAGE59_I2@PURE_QUANTA.GENOA_SP5(CHIPS)':
 'VSS_BW28': CDS_PINID='VSS_BW28';
NODE_NAME     U26 BW31
 '@T6G_MB_LIB.T6G(SCH_1):PAGE59_I2@PURE_QUANTA.GENOA_SP5(CHIPS)':
 'VSS_BW31': CDS_PINID='VSS_BW31';
NODE_NAME     U26 BW34
 '@T6G_MB_LIB.T6G(SCH_1):PAGE59_I2@PURE_QUANTA.GENOA_SP5(CHIPS)':
 'VSS_BW34': CDS_PINID='VSS_BW34';
NODE_NAME     U26 BW42
 '@T6G_MB_LIB.T6G(SCH_1):PAGE59_I2@PURE_QUANTA.GENOA_SP5(CHIPS)':
 'VSS_BW42': CDS_PINID='VSS_BW42';
NODE_NAME     U26 BW45
 '@T6G_MB_LIB.T6G(SCH_1):PAGE59_I2@PURE_QUANTA.GENOA_SP5(CHIPS)':
 'VSS_BW45': CDS_PINID='VSS_BW45';
NODE_NAME     U26 BW48
 '@T6G_MB_LIB.T6G(SCH_1):PAGE59_I2@PURE_QUANTA.GENOA_SP5(CHIPS)':
 'VSS_BW48': CDS_PINID='VSS_BW48';
NODE_NAME     U26 BW51
 '@T6G_MB_LIB.T6G(SCH_1):PAGE59_I2@PURE_QUANTA.GENOA_SP5(CHIPS)':
 'VSS_BW51': CDS_PINID='VSS_BW51';
NODE_NAME     U26 BW54
 '@T6G_MB_LIB.T6G(SCH_1):PAGE59_I2@PURE_QUANTA.GENOA_SP5(CHIPS)':
 'VSS_BW54': CDS_PINID='VSS_BW54';
NODE_NAME     U26 BW56
 '@T6G_MB_LIB.T6G(SCH_1):PAGE59_I2@PURE_QUANTA.GENOA_SP5(CHIPS)':
 'VSS_BW56': CDS_PINID='VSS_BW56';
NODE_NAME     U26 BW58
 '@T6G_MB_LIB.T6G(SCH_1):PAGE59_I2@PURE_QUANTA.GENOA_SP5(CHIPS)':
 'VSS_BW58': CDS_PINID='VSS_BW58';
NODE_NAME     U26 BW61
 '@T6G_MB_LIB.T6G(SCH_1):PAGE59_I2@PURE_QUANTA.GENOA_SP5(CHIPS)':
 'VSS_BW61': CDS_PINID='VSS_BW61';
NODE_NAME     U26 BW63
 '@T6G_MB_LIB.T6G(SCH_1):PAGE59_I2@PURE_QUANTA.GENOA_SP5(CHIPS)':
 'VSS_BW63': CDS_PINID='VSS_BW63';
NODE_NAME     U26 BW65
 '@T6G_MB_LIB.T6G(SCH_1):PAGE59_I2@PURE_QUANTA.GENOA_SP5(CHIPS)':
 'VSS_BW65': CDS_PINID='VSS_BW65';
NODE_NAME     U26 BW68
 '@T6G_MB_LIB.T6G(SCH_1):PAGE59_I2@PURE_QUANTA.GENOA_SP5(CHIPS)':
 'VSS_BW68': CDS_PINID='VSS_BW68';
NODE_NAME     U26 BW70
 '@T6G_MB_LIB.T6G(SCH_1):PAGE59_I2@PURE_QUANTA.GENOA_SP5(CHIPS)':
 'VSS_BW70': CDS_PINID='VSS_BW70';
NODE_NAME     U26 BW72
 '@T6G_MB_LIB.T6G(SCH_1):PAGE59_I2@PURE_QUANTA.GENOA_SP5(CHIPS)':
 'VSS_BW72': CDS_PINID='VSS_BW72';
NODE_NAME     U26 BW75
 '@T6G_MB_LIB.T6G(SCH_1):PAGE59_I2@PURE_QUANTA.GENOA_SP5(CHIPS)':
 'VSS_BW75': CDS_PINID='VSS_BW75';
NODE_NAME     U26 BY3
 '@T6G_MB_LIB.T6G(SCH_1):PAGE59_I2@PURE_QUANTA.GENOA_SP5(CHIPS)':
 'VSS_BY3': CDS_PINID='VSS_BY3';
NODE_NAME     U26 BY5
 '@T6G_MB_LIB.T6G(SCH_1):PAGE59_I2@PURE_QUANTA.GENOA_SP5(CHIPS)':
 'VSS_BY5': CDS_PINID='VSS_BY5';
NODE_NAME     U26 BY8
 '@T6G_MB_LIB.T6G(SCH_1):PAGE59_I2@PURE_QUANTA.GENOA_SP5(CHIPS)':
 'VSS_BY8': CDS_PINID='VSS_BY8';
NODE_NAME     U26 BY10
 '@T6G_MB_LIB.T6G(SCH_1):PAGE59_I2@PURE_QUANTA.GENOA_SP5(CHIPS)':
 'VSS_BY10': CDS_PINID='VSS_BY10';
NODE_NAME     U26 BY12
 '@T6G_MB_LIB.T6G(SCH_1):PAGE59_I2@PURE_QUANTA.GENOA_SP5(CHIPS)':
 'VSS_BY12': CDS_PINID='VSS_BY12';
NODE_NAME     U26 BY15
 '@T6G_MB_LIB.T6G(SCH_1):PAGE59_I2@PURE_QUANTA.GENOA_SP5(CHIPS)':
 'VSS_BY15': CDS_PINID='VSS_BY15';
NODE_NAME     U26 BY17
 '@T6G_MB_LIB.T6G(SCH_1):PAGE59_I2@PURE_QUANTA.GENOA_SP5(CHIPS)':
 'VSS_BY17': CDS_PINID='VSS_BY17';
NODE_NAME     U26 BY19
 '@T6G_MB_LIB.T6G(SCH_1):PAGE59_I2@PURE_QUANTA.GENOA_SP5(CHIPS)':
 'VSS_BY19': CDS_PINID='VSS_BY19';
NODE_NAME     U26 BY22
 '@T6G_MB_LIB.T6G(SCH_1):PAGE59_I2@PURE_QUANTA.GENOA_SP5(CHIPS)':
 'VSS_BY22': CDS_PINID='VSS_BY22';
NODE_NAME     U26 BY25
 '@T6G_MB_LIB.T6G(SCH_1):PAGE59_I2@PURE_QUANTA.GENOA_SP5(CHIPS)':
 'VSS_BY25': CDS_PINID='VSS_BY25';
NODE_NAME     U26 BY28
 '@T6G_MB_LIB.T6G(SCH_1):PAGE59_I2@PURE_QUANTA.GENOA_SP5(CHIPS)':
 'VSS_BY28': CDS_PINID='VSS_BY28';
NODE_NAME     U26 BY31
 '@T6G_MB_LIB.T6G(SCH_1):PAGE59_I2@PURE_QUANTA.GENOA_SP5(CHIPS)':
 'VSS_BY31': CDS_PINID='VSS_BY31';
NODE_NAME     U26 BY34
 '@T6G_MB_LIB.T6G(SCH_1):PAGE59_I2@PURE_QUANTA.GENOA_SP5(CHIPS)':
 'VSS_BY34': CDS_PINID='VSS_BY34';
NODE_NAME     U26 BY37
 '@T6G_MB_LIB.T6G(SCH_1):PAGE59_I2@PURE_QUANTA.GENOA_SP5(CHIPS)':
 'VSS_BY37': CDS_PINID='VSS_BY37';
NODE_NAME     U26 BY39
 '@T6G_MB_LIB.T6G(SCH_1):PAGE59_I2@PURE_QUANTA.GENOA_SP5(CHIPS)':
 'VSS_BY39': CDS_PINID='VSS_BY39';
NODE_NAME     U26 BY42
 '@T6G_MB_LIB.T6G(SCH_1):PAGE59_I2@PURE_QUANTA.GENOA_SP5(CHIPS)':
 'VSS_BY42': CDS_PINID='VSS_BY42';
NODE_NAME     U26 BY45
 '@T6G_MB_LIB.T6G(SCH_1):PAGE59_I2@PURE_QUANTA.GENOA_SP5(CHIPS)':
 'VSS_BY45': CDS_PINID='VSS_BY45';
NODE_NAME     U26 BY48
 '@T6G_MB_LIB.T6G(SCH_1):PAGE59_I2@PURE_QUANTA.GENOA_SP5(CHIPS)':
 'VSS_BY48': CDS_PINID='VSS_BY48';
NODE_NAME     U26 BY51
 '@T6G_MB_LIB.T6G(SCH_1):PAGE59_I2@PURE_QUANTA.GENOA_SP5(CHIPS)':
 'VSS_BY51': CDS_PINID='VSS_BY51';
NODE_NAME     U26 BY54
 '@T6G_MB_LIB.T6G(SCH_1):PAGE59_I2@PURE_QUANTA.GENOA_SP5(CHIPS)':
 'VSS_BY54': CDS_PINID='VSS_BY54';
NODE_NAME     U26 BY57
 '@T6G_MB_LIB.T6G(SCH_1):PAGE59_I2@PURE_QUANTA.GENOA_SP5(CHIPS)':
 'VSS_BY57': CDS_PINID='VSS_BY57';
NODE_NAME     U26 BY59
 '@T6G_MB_LIB.T6G(SCH_1):PAGE59_I2@PURE_QUANTA.GENOA_SP5(CHIPS)':
 'VSS_BY59': CDS_PINID='VSS_BY59';
NODE_NAME     U26 BY61
 '@T6G_MB_LIB.T6G(SCH_1):PAGE59_I2@PURE_QUANTA.GENOA_SP5(CHIPS)':
 'VSS_BY61': CDS_PINID='VSS_BY61';
NODE_NAME     U26 BY64
 '@T6G_MB_LIB.T6G(SCH_1):PAGE59_I2@PURE_QUANTA.GENOA_SP5(CHIPS)':
 'VSS_BY64': CDS_PINID='VSS_BY64';
NODE_NAME     U26 BY66
 '@T6G_MB_LIB.T6G(SCH_1):PAGE59_I2@PURE_QUANTA.GENOA_SP5(CHIPS)':
 'VSS_BY66': CDS_PINID='VSS_BY66';
NODE_NAME     U26 BY68
 '@T6G_MB_LIB.T6G(SCH_1):PAGE59_I2@PURE_QUANTA.GENOA_SP5(CHIPS)':
 'VSS_BY68': CDS_PINID='VSS_BY68';
NODE_NAME     U26 BY71
 '@T6G_MB_LIB.T6G(SCH_1):PAGE59_I2@PURE_QUANTA.GENOA_SP5(CHIPS)':
 'VSS_BY71': CDS_PINID='VSS_BY71';
NODE_NAME     U26 BY73
 '@T6G_MB_LIB.T6G(SCH_1):PAGE59_I2@PURE_QUANTA.GENOA_SP5(CHIPS)':
 'VSS_BY73': CDS_PINID='VSS_BY73';
NODE_NAME     U26 CA1
 '@T6G_MB_LIB.T6G(SCH_1):PAGE59_I2@PURE_QUANTA.GENOA_SP5(CHIPS)':
 'VSS_CA1': CDS_PINID='VSS_CA1';
NODE_NAME     U26 CA6
 '@T6G_MB_LIB.T6G(SCH_1):PAGE59_I2@PURE_QUANTA.GENOA_SP5(CHIPS)':
 'VSS_CA6': CDS_PINID='VSS_CA6';
NODE_NAME     U26 CA8
 '@T6G_MB_LIB.T6G(SCH_1):PAGE59_I2@PURE_QUANTA.GENOA_SP5(CHIPS)':
 'VSS_CA8': CDS_PINID='VSS_CA8';
NODE_NAME     U26 CA13
 '@T6G_MB_LIB.T6G(SCH_1):PAGE59_I2@PURE_QUANTA.GENOA_SP5(CHIPS)':
 'VSS_CA13': CDS_PINID='VSS_CA13';
NODE_NAME     U26 CA15
 '@T6G_MB_LIB.T6G(SCH_1):PAGE59_I2@PURE_QUANTA.GENOA_SP5(CHIPS)':
 'VSS_CA15': CDS_PINID='VSS_CA15';
NODE_NAME     U26 CA20
 '@T6G_MB_LIB.T6G(SCH_1):PAGE59_I2@PURE_QUANTA.GENOA_SP5(CHIPS)':
 'VSS_CA20': CDS_PINID='VSS_CA20';
NODE_NAME     U26 CA22
 '@T6G_MB_LIB.T6G(SCH_1):PAGE59_I2@PURE_QUANTA.GENOA_SP5(CHIPS)':
 'VSS_CA22': CDS_PINID='VSS_CA22';
NODE_NAME     U26 CA25
 '@T6G_MB_LIB.T6G(SCH_1):PAGE59_I2@PURE_QUANTA.GENOA_SP5(CHIPS)':
 'VSS_CA25': CDS_PINID='VSS_CA25';
NODE_NAME     U26 CA28
 '@T6G_MB_LIB.T6G(SCH_1):PAGE59_I2@PURE_QUANTA.GENOA_SP5(CHIPS)':
 'VSS_CA28': CDS_PINID='VSS_CA28';
NODE_NAME     U26 CA31
 '@T6G_MB_LIB.T6G(SCH_1):PAGE59_I2@PURE_QUANTA.GENOA_SP5(CHIPS)':
 'VSS_CA31': CDS_PINID='VSS_CA31';
NODE_NAME     U26 CA34
 '@T6G_MB_LIB.T6G(SCH_1):PAGE59_I2@PURE_QUANTA.GENOA_SP5(CHIPS)':
 'VSS_CA34': CDS_PINID='VSS_CA34';
NODE_NAME     U26 CA35
 '@T6G_MB_LIB.T6G(SCH_1):PAGE59_I2@PURE_QUANTA.GENOA_SP5(CHIPS)':
 'VSS_CA35': CDS_PINID='VSS_CA35';
NODE_NAME     U26 CA36
 '@T6G_MB_LIB.T6G(SCH_1):PAGE59_I2@PURE_QUANTA.GENOA_SP5(CHIPS)':
 'VSS_CA36': CDS_PINID='VSS_CA36';
NODE_NAME     U26 CA40
 '@T6G_MB_LIB.T6G(SCH_1):PAGE59_I2@PURE_QUANTA.GENOA_SP5(CHIPS)':
 'VSS_CA40': CDS_PINID='VSS_CA40';
NODE_NAME     U26 CA41
 '@T6G_MB_LIB.T6G(SCH_1):PAGE59_I2@PURE_QUANTA.GENOA_SP5(CHIPS)':
 'VSS_CA41': CDS_PINID='VSS_CA41';
NODE_NAME     U26 CA42
 '@T6G_MB_LIB.T6G(SCH_1):PAGE59_I2@PURE_QUANTA.GENOA_SP5(CHIPS)':
 'VSS_CA42': CDS_PINID='VSS_CA42';
NODE_NAME     U26 CA45
 '@T6G_MB_LIB.T6G(SCH_1):PAGE59_I2@PURE_QUANTA.GENOA_SP5(CHIPS)':
 'VSS_CA45': CDS_PINID='VSS_CA45';
NODE_NAME     U26 CA48
 '@T6G_MB_LIB.T6G(SCH_1):PAGE59_I2@PURE_QUANTA.GENOA_SP5(CHIPS)':
 'VSS_CA48': CDS_PINID='VSS_CA48';
NODE_NAME     U26 CA51
 '@T6G_MB_LIB.T6G(SCH_1):PAGE59_I2@PURE_QUANTA.GENOA_SP5(CHIPS)':
 'VSS_CA51': CDS_PINID='VSS_CA51';
NODE_NAME     U26 CA54
 '@T6G_MB_LIB.T6G(SCH_1):PAGE59_I2@PURE_QUANTA.GENOA_SP5(CHIPS)':
 'VSS_CA54': CDS_PINID='VSS_CA54';
NODE_NAME     U26 CA56
 '@T6G_MB_LIB.T6G(SCH_1):PAGE59_I2@PURE_QUANTA.GENOA_SP5(CHIPS)':
 'VSS_CA56': CDS_PINID='VSS_CA56';
NODE_NAME     U26 CA61
 '@T6G_MB_LIB.T6G(SCH_1):PAGE59_I2@PURE_QUANTA.GENOA_SP5(CHIPS)':
 'VSS_CA61': CDS_PINID='VSS_CA61';
NODE_NAME     U26 CA63
 '@T6G_MB_LIB.T6G(SCH_1):PAGE59_I2@PURE_QUANTA.GENOA_SP5(CHIPS)':
 'VSS_CA63': CDS_PINID='VSS_CA63';
NODE_NAME     U26 CA68
 '@T6G_MB_LIB.T6G(SCH_1):PAGE59_I2@PURE_QUANTA.GENOA_SP5(CHIPS)':
 'VSS_CA68': CDS_PINID='VSS_CA68';
NODE_NAME     U26 CA70
 '@T6G_MB_LIB.T6G(SCH_1):PAGE59_I2@PURE_QUANTA.GENOA_SP5(CHIPS)':
 'VSS_CA70': CDS_PINID='VSS_CA70';
NODE_NAME     U26 CA75
 '@T6G_MB_LIB.T6G(SCH_1):PAGE59_I2@PURE_QUANTA.GENOA_SP5(CHIPS)':
 'VSS_CA75': CDS_PINID='VSS_CA75';
NODE_NAME     U26 CB3
 '@T6G_MB_LIB.T6G(SCH_1):PAGE59_I2@PURE_QUANTA.GENOA_SP5(CHIPS)':
 'VSS_CB3': CDS_PINID='VSS_CB3';
NODE_NAME     U26 CB5
 '@T6G_MB_LIB.T6G(SCH_1):PAGE59_I2@PURE_QUANTA.GENOA_SP5(CHIPS)':
 'VSS_CB5': CDS_PINID='VSS_CB5';
NODE_NAME     U26 CB8
 '@T6G_MB_LIB.T6G(SCH_1):PAGE59_I2@PURE_QUANTA.GENOA_SP5(CHIPS)':
 'VSS_CB8': CDS_PINID='VSS_CB8';
NODE_NAME     U26 CB10
 '@T6G_MB_LIB.T6G(SCH_1):PAGE59_I2@PURE_QUANTA.GENOA_SP5(CHIPS)':
 'VSS_CB10': CDS_PINID='VSS_CB10';
NODE_NAME     U26 CB12
 '@T6G_MB_LIB.T6G(SCH_1):PAGE59_I2@PURE_QUANTA.GENOA_SP5(CHIPS)':
 'VSS_CB12': CDS_PINID='VSS_CB12';
NODE_NAME     U26 CB15
 '@T6G_MB_LIB.T6G(SCH_1):PAGE59_I2@PURE_QUANTA.GENOA_SP5(CHIPS)':
 'VSS_CB15': CDS_PINID='VSS_CB15';
NODE_NAME     U26 CB17
 '@T6G_MB_LIB.T6G(SCH_1):PAGE59_I2@PURE_QUANTA.GENOA_SP5(CHIPS)':
 'VSS_CB17': CDS_PINID='VSS_CB17';
NODE_NAME     U26 CB19
 '@T6G_MB_LIB.T6G(SCH_1):PAGE59_I2@PURE_QUANTA.GENOA_SP5(CHIPS)':
 'VSS_CB19': CDS_PINID='VSS_CB19';
NODE_NAME     U26 CB23
 '@T6G_MB_LIB.T6G(SCH_1):PAGE59_I2@PURE_QUANTA.GENOA_SP5(CHIPS)':
 'VSS_CB23': CDS_PINID='VSS_CB23';
NODE_NAME     U26 CB24
 '@T6G_MB_LIB.T6G(SCH_1):PAGE59_I2@PURE_QUANTA.GENOA_SP5(CHIPS)':
 'VSS_CB24': CDS_PINID='VSS_CB24';
NODE_NAME     U26 CB25
 '@T6G_MB_LIB.T6G(SCH_1):PAGE59_I2@PURE_QUANTA.GENOA_SP5(CHIPS)':
 'VSS_CB25': CDS_PINID='VSS_CB25';
NODE_NAME     U26 CB26
 '@T6G_MB_LIB.T6G(SCH_1):PAGE59_I2@PURE_QUANTA.GENOA_SP5(CHIPS)':
 'VSS_CB26': CDS_PINID='VSS_CB26';
NODE_NAME     U26 CB27
 '@T6G_MB_LIB.T6G(SCH_1):PAGE59_I2@PURE_QUANTA.GENOA_SP5(CHIPS)':
 'VSS_CB27': CDS_PINID='VSS_CB27';
NODE_NAME     U26 CB28
 '@T6G_MB_LIB.T6G(SCH_1):PAGE59_I2@PURE_QUANTA.GENOA_SP5(CHIPS)':
 'VSS_CB28': CDS_PINID='VSS_CB28';
NODE_NAME     U26 CB29
 '@T6G_MB_LIB.T6G(SCH_1):PAGE59_I2@PURE_QUANTA.GENOA_SP5(CHIPS)':
 'VSS_CB29': CDS_PINID='VSS_CB29';
NODE_NAME     U26 CB30
 '@T6G_MB_LIB.T6G(SCH_1):PAGE59_I2@PURE_QUANTA.GENOA_SP5(CHIPS)':
 'VSS_CB30': CDS_PINID='VSS_CB30';
NODE_NAME     U26 CB31
 '@T6G_MB_LIB.T6G(SCH_1):PAGE59_I2@PURE_QUANTA.GENOA_SP5(CHIPS)':
 'VSS_CB31': CDS_PINID='VSS_CB31';
NODE_NAME     U26 CB32
 '@T6G_MB_LIB.T6G(SCH_1):PAGE59_I2@PURE_QUANTA.GENOA_SP5(CHIPS)':
 'VSS_CB32': CDS_PINID='VSS_CB32';
NODE_NAME     U26 CB33
 '@T6G_MB_LIB.T6G(SCH_1):PAGE59_I2@PURE_QUANTA.GENOA_SP5(CHIPS)':
 'VSS_CB33': CDS_PINID='VSS_CB33';
NODE_NAME     U26 CB34
 '@T6G_MB_LIB.T6G(SCH_1):PAGE59_I2@PURE_QUANTA.GENOA_SP5(CHIPS)':
 'VSS_CB34': CDS_PINID='VSS_CB34';
NODE_NAME     U26 CB37
 '@T6G_MB_LIB.T6G(SCH_1):PAGE59_I2@PURE_QUANTA.GENOA_SP5(CHIPS)':
 'VSS_CB37': CDS_PINID='VSS_CB37';
NODE_NAME     U26 CB39
 '@T6G_MB_LIB.T6G(SCH_1):PAGE59_I2@PURE_QUANTA.GENOA_SP5(CHIPS)':
 'VSS_CB39': CDS_PINID='VSS_CB39';
NODE_NAME     U26 CB42
 '@T6G_MB_LIB.T6G(SCH_1):PAGE59_I2@PURE_QUANTA.GENOA_SP5(CHIPS)':
 'VSS_CB42': CDS_PINID='VSS_CB42';
NODE_NAME     U26 CB43
 '@T6G_MB_LIB.T6G(SCH_1):PAGE59_I2@PURE_QUANTA.GENOA_SP5(CHIPS)':
 'VSS_CB43': CDS_PINID='VSS_CB43';
NODE_NAME     U26 CB45
 '@T6G_MB_LIB.T6G(SCH_1):PAGE59_I2@PURE_QUANTA.GENOA_SP5(CHIPS)':
 'VSS_CB45': CDS_PINID='VSS_CB45';
NODE_NAME     U26 CB46
 '@T6G_MB_LIB.T6G(SCH_1):PAGE59_I2@PURE_QUANTA.GENOA_SP5(CHIPS)':
 'VSS_CB46': CDS_PINID='VSS_CB46';
NODE_NAME     U26 CB47
 '@T6G_MB_LIB.T6G(SCH_1):PAGE59_I2@PURE_QUANTA.GENOA_SP5(CHIPS)':
 'VSS_CB47': CDS_PINID='VSS_CB47';
NODE_NAME     U26 CB48
 '@T6G_MB_LIB.T6G(SCH_1):PAGE59_I2@PURE_QUANTA.GENOA_SP5(CHIPS)':
 'VSS_CB48': CDS_PINID='VSS_CB48';
NODE_NAME     U26 CB49
 '@T6G_MB_LIB.T6G(SCH_1):PAGE59_I2@PURE_QUANTA.GENOA_SP5(CHIPS)':
 'VSS_CB49': CDS_PINID='VSS_CB49';
NODE_NAME     U26 CB50
 '@T6G_MB_LIB.T6G(SCH_1):PAGE59_I2@PURE_QUANTA.GENOA_SP5(CHIPS)':
 'VSS_CB50': CDS_PINID='VSS_CB50';
NODE_NAME     U26 CB51
 '@T6G_MB_LIB.T6G(SCH_1):PAGE59_I2@PURE_QUANTA.GENOA_SP5(CHIPS)':
 'VSS_CB51': CDS_PINID='VSS_CB51';
NODE_NAME     U26 CB52
 '@T6G_MB_LIB.T6G(SCH_1):PAGE59_I2@PURE_QUANTA.GENOA_SP5(CHIPS)':
 'VSS_CB52': CDS_PINID='VSS_CB52';
NODE_NAME     U26 CB53
 '@T6G_MB_LIB.T6G(SCH_1):PAGE59_I2@PURE_QUANTA.GENOA_SP5(CHIPS)':
 'VSS_CB53': CDS_PINID='VSS_CB53';
NODE_NAME     U26 CB57
 '@T6G_MB_LIB.T6G(SCH_1):PAGE59_I2@PURE_QUANTA.GENOA_SP5(CHIPS)':
 'VSS_CB57': CDS_PINID='VSS_CB57';
NODE_NAME     U26 CB59
 '@T6G_MB_LIB.T6G(SCH_1):PAGE59_I2@PURE_QUANTA.GENOA_SP5(CHIPS)':
 'VSS_CB59': CDS_PINID='VSS_CB59';
NODE_NAME     U26 CB61
 '@T6G_MB_LIB.T6G(SCH_1):PAGE59_I2@PURE_QUANTA.GENOA_SP5(CHIPS)':
 'VSS_CB61': CDS_PINID='VSS_CB61';
NODE_NAME     U26 CB64
 '@T6G_MB_LIB.T6G(SCH_1):PAGE59_I2@PURE_QUANTA.GENOA_SP5(CHIPS)':
 'VSS_CB64': CDS_PINID='VSS_CB64';
NODE_NAME     U26 CB66
 '@T6G_MB_LIB.T6G(SCH_1):PAGE59_I2@PURE_QUANTA.GENOA_SP5(CHIPS)':
 'VSS_CB66': CDS_PINID='VSS_CB66';
NODE_NAME     U26 CB68
 '@T6G_MB_LIB.T6G(SCH_1):PAGE59_I2@PURE_QUANTA.GENOA_SP5(CHIPS)':
 'VSS_CB68': CDS_PINID='VSS_CB68';
NODE_NAME     U26 CB71
 '@T6G_MB_LIB.T6G(SCH_1):PAGE59_I2@PURE_QUANTA.GENOA_SP5(CHIPS)':
 'VSS_CB71': CDS_PINID='VSS_CB71';
NODE_NAME     U26 CB73
 '@T6G_MB_LIB.T6G(SCH_1):PAGE59_I2@PURE_QUANTA.GENOA_SP5(CHIPS)':
 'VSS_CB73': CDS_PINID='VSS_CB73';
NODE_NAME     U26 CC1
 '@T6G_MB_LIB.T6G(SCH_1):PAGE59_I2@PURE_QUANTA.GENOA_SP5(CHIPS)':
 'VSS_CC1': CDS_PINID='VSS_CC1';
NODE_NAME     U26 CC4
 '@T6G_MB_LIB.T6G(SCH_1):PAGE59_I2@PURE_QUANTA.GENOA_SP5(CHIPS)':
 'VSS_CC4': CDS_PINID='VSS_CC4';
NODE_NAME     U26 CC6
 '@T6G_MB_LIB.T6G(SCH_1):PAGE59_I2@PURE_QUANTA.GENOA_SP5(CHIPS)':
 'VSS_CC6': CDS_PINID='VSS_CC6';
NODE_NAME     U26 CC8
 '@T6G_MB_LIB.T6G(SCH_1):PAGE59_I2@PURE_QUANTA.GENOA_SP5(CHIPS)':
 'VSS_CC8': CDS_PINID='VSS_CC8';
NODE_NAME     U26 CC11
 '@T6G_MB_LIB.T6G(SCH_1):PAGE59_I2@PURE_QUANTA.GENOA_SP5(CHIPS)':
 'VSS_CC11': CDS_PINID='VSS_CC11';
NODE_NAME     U26 CC13
 '@T6G_MB_LIB.T6G(SCH_1):PAGE59_I2@PURE_QUANTA.GENOA_SP5(CHIPS)':
 'VSS_CC13': CDS_PINID='VSS_CC13';
NODE_NAME     U26 CC15
 '@T6G_MB_LIB.T6G(SCH_1):PAGE59_I2@PURE_QUANTA.GENOA_SP5(CHIPS)':
 'VSS_CC15': CDS_PINID='VSS_CC15';
NODE_NAME     U26 CC18
 '@T6G_MB_LIB.T6G(SCH_1):PAGE59_I2@PURE_QUANTA.GENOA_SP5(CHIPS)':
 'VSS_CC18': CDS_PINID='VSS_CC18';
NODE_NAME     U26 CC20
 '@T6G_MB_LIB.T6G(SCH_1):PAGE59_I2@PURE_QUANTA.GENOA_SP5(CHIPS)':
 'VSS_CC20': CDS_PINID='VSS_CC20';
NODE_NAME     U26 CC25
 '@T6G_MB_LIB.T6G(SCH_1):PAGE59_I2@PURE_QUANTA.GENOA_SP5(CHIPS)':
 'VSS_CC25': CDS_PINID='VSS_CC25';
NODE_NAME     U26 CC28
 '@T6G_MB_LIB.T6G(SCH_1):PAGE59_I2@PURE_QUANTA.GENOA_SP5(CHIPS)':
 'VSS_CC28': CDS_PINID='VSS_CC28';
NODE_NAME     U26 CC31
 '@T6G_MB_LIB.T6G(SCH_1):PAGE59_I2@PURE_QUANTA.GENOA_SP5(CHIPS)':
 'VSS_CC31': CDS_PINID='VSS_CC31';
NODE_NAME     U26 CC34
 '@T6G_MB_LIB.T6G(SCH_1):PAGE59_I2@PURE_QUANTA.GENOA_SP5(CHIPS)':
 'VSS_CC34': CDS_PINID='VSS_CC34';
NODE_NAME     U26 CC42
 '@T6G_MB_LIB.T6G(SCH_1):PAGE59_I2@PURE_QUANTA.GENOA_SP5(CHIPS)':
 'VSS_CC42': CDS_PINID='VSS_CC42';
NODE_NAME     U26 CC45
 '@T6G_MB_LIB.T6G(SCH_1):PAGE59_I2@PURE_QUANTA.GENOA_SP5(CHIPS)':
 'VSS_CC45': CDS_PINID='VSS_CC45';
NODE_NAME     U26 CC48
 '@T6G_MB_LIB.T6G(SCH_1):PAGE59_I2@PURE_QUANTA.GENOA_SP5(CHIPS)':
 'VSS_CC48': CDS_PINID='VSS_CC48';
NODE_NAME     U26 CC51
 '@T6G_MB_LIB.T6G(SCH_1):PAGE59_I2@PURE_QUANTA.GENOA_SP5(CHIPS)':
 'VSS_CC51': CDS_PINID='VSS_CC51';
NODE_NAME     U26 CC54
 '@T6G_MB_LIB.T6G(SCH_1):PAGE59_I2@PURE_QUANTA.GENOA_SP5(CHIPS)':
 'VSS_CC54': CDS_PINID='VSS_CC54';
NODE_NAME     U26 CC56
 '@T6G_MB_LIB.T6G(SCH_1):PAGE59_I2@PURE_QUANTA.GENOA_SP5(CHIPS)':
 'VSS_CC56': CDS_PINID='VSS_CC56';
NODE_NAME     U26 CC58
 '@T6G_MB_LIB.T6G(SCH_1):PAGE59_I2@PURE_QUANTA.GENOA_SP5(CHIPS)':
 'VSS_CC58': CDS_PINID='VSS_CC58';
NODE_NAME     U26 CC61
 '@T6G_MB_LIB.T6G(SCH_1):PAGE59_I2@PURE_QUANTA.GENOA_SP5(CHIPS)':
 'VSS_CC61': CDS_PINID='VSS_CC61';
NODE_NAME     U26 CC63
 '@T6G_MB_LIB.T6G(SCH_1):PAGE59_I2@PURE_QUANTA.GENOA_SP5(CHIPS)':
 'VSS_CC63': CDS_PINID='VSS_CC63';
NODE_NAME     U26 CC65
 '@T6G_MB_LIB.T6G(SCH_1):PAGE59_I2@PURE_QUANTA.GENOA_SP5(CHIPS)':
 'VSS_CC65': CDS_PINID='VSS_CC65';
NODE_NAME     U26 CC68
 '@T6G_MB_LIB.T6G(SCH_1):PAGE59_I2@PURE_QUANTA.GENOA_SP5(CHIPS)':
 'VSS_CC68': CDS_PINID='VSS_CC68';
NODE_NAME     U26 CC70
 '@T6G_MB_LIB.T6G(SCH_1):PAGE59_I2@PURE_QUANTA.GENOA_SP5(CHIPS)':
 'VSS_CC70': CDS_PINID='VSS_CC70';
NODE_NAME     U26 CC72
 '@T6G_MB_LIB.T6G(SCH_1):PAGE59_I2@PURE_QUANTA.GENOA_SP5(CHIPS)':
 'VSS_CC72': CDS_PINID='VSS_CC72';
NODE_NAME     U26 CC75
 '@T6G_MB_LIB.T6G(SCH_1):PAGE59_I2@PURE_QUANTA.GENOA_SP5(CHIPS)':
 'VSS_CC75': CDS_PINID='VSS_CC75';
NODE_NAME     U26 CD3
 '@T6G_MB_LIB.T6G(SCH_1):PAGE59_I2@PURE_QUANTA.GENOA_SP5(CHIPS)':
 'VSS_CD3': CDS_PINID='VSS_CD3';
NODE_NAME     U26 CD8
 '@T6G_MB_LIB.T6G(SCH_1):PAGE59_I2@PURE_QUANTA.GENOA_SP5(CHIPS)':
 'VSS_CD8': CDS_PINID='VSS_CD8';
NODE_NAME     U26 CD10
 '@T6G_MB_LIB.T6G(SCH_1):PAGE59_I2@PURE_QUANTA.GENOA_SP5(CHIPS)':
 'VSS_CD10': CDS_PINID='VSS_CD10';
NODE_NAME     U26 CD15
 '@T6G_MB_LIB.T6G(SCH_1):PAGE59_I2@PURE_QUANTA.GENOA_SP5(CHIPS)':
 'VSS_CD15': CDS_PINID='VSS_CD15';
NODE_NAME     U26 CD17
 '@T6G_MB_LIB.T6G(SCH_1):PAGE59_I2@PURE_QUANTA.GENOA_SP5(CHIPS)':
 'VSS_CD17': CDS_PINID='VSS_CD17';
NODE_NAME     U26 CD22
 '@T6G_MB_LIB.T6G(SCH_1):PAGE59_I2@PURE_QUANTA.GENOA_SP5(CHIPS)':
 'VSS_CD22': CDS_PINID='VSS_CD22';
NODE_NAME     U26 CD25
 '@T6G_MB_LIB.T6G(SCH_1):PAGE59_I2@PURE_QUANTA.GENOA_SP5(CHIPS)':
 'VSS_CD25': CDS_PINID='VSS_CD25';
NODE_NAME     U26 CD28
 '@T6G_MB_LIB.T6G(SCH_1):PAGE59_I2@PURE_QUANTA.GENOA_SP5(CHIPS)':
 'VSS_CD28': CDS_PINID='VSS_CD28';
NODE_NAME     U26 CD31
 '@T6G_MB_LIB.T6G(SCH_1):PAGE59_I2@PURE_QUANTA.GENOA_SP5(CHIPS)':
 'VSS_CD31': CDS_PINID='VSS_CD31';
NODE_NAME     U26 CD34
 '@T6G_MB_LIB.T6G(SCH_1):PAGE59_I2@PURE_QUANTA.GENOA_SP5(CHIPS)':
 'VSS_CD34': CDS_PINID='VSS_CD34';
NODE_NAME     U26 CD37
 '@T6G_MB_LIB.T6G(SCH_1):PAGE59_I2@PURE_QUANTA.GENOA_SP5(CHIPS)':
 'VSS_CD37': CDS_PINID='VSS_CD37';
NODE_NAME     U26 CD39
 '@T6G_MB_LIB.T6G(SCH_1):PAGE59_I2@PURE_QUANTA.GENOA_SP5(CHIPS)':
 'VSS_CD39': CDS_PINID='VSS_CD39';
NODE_NAME     U26 CD42
 '@T6G_MB_LIB.T6G(SCH_1):PAGE59_I2@PURE_QUANTA.GENOA_SP5(CHIPS)':
 'VSS_CD42': CDS_PINID='VSS_CD42';
NODE_NAME     U26 CD45
 '@T6G_MB_LIB.T6G(SCH_1):PAGE59_I2@PURE_QUANTA.GENOA_SP5(CHIPS)':
 'VSS_CD45': CDS_PINID='VSS_CD45';
NODE_NAME     U26 CD48
 '@T6G_MB_LIB.T6G(SCH_1):PAGE59_I2@PURE_QUANTA.GENOA_SP5(CHIPS)':
 'VSS_CD48': CDS_PINID='VSS_CD48';
NODE_NAME     U26 CD51
 '@T6G_MB_LIB.T6G(SCH_1):PAGE59_I2@PURE_QUANTA.GENOA_SP5(CHIPS)':
 'VSS_CD51': CDS_PINID='VSS_CD51';
NODE_NAME     U26 CD54
 '@T6G_MB_LIB.T6G(SCH_1):PAGE59_I2@PURE_QUANTA.GENOA_SP5(CHIPS)':
 'VSS_CD54': CDS_PINID='VSS_CD54';
NODE_NAME     U26 CD59
 '@T6G_MB_LIB.T6G(SCH_1):PAGE59_I2@PURE_QUANTA.GENOA_SP5(CHIPS)':
 'VSS_CD59': CDS_PINID='VSS_CD59';
NODE_NAME     U26 CD61
 '@T6G_MB_LIB.T6G(SCH_1):PAGE59_I2@PURE_QUANTA.GENOA_SP5(CHIPS)':
 'VSS_CD61': CDS_PINID='VSS_CD61';
NODE_NAME     U26 CD66
 '@T6G_MB_LIB.T6G(SCH_1):PAGE59_I2@PURE_QUANTA.GENOA_SP5(CHIPS)':
 'VSS_CD66': CDS_PINID='VSS_CD66';
NODE_NAME     U26 CD68
 '@T6G_MB_LIB.T6G(SCH_1):PAGE59_I2@PURE_QUANTA.GENOA_SP5(CHIPS)':
 'VSS_CD68': CDS_PINID='VSS_CD68';
NODE_NAME     U26 CD73
 '@T6G_MB_LIB.T6G(SCH_1):PAGE59_I2@PURE_QUANTA.GENOA_SP5(CHIPS)':
 'VSS_CD73': CDS_PINID='VSS_CD73';
NODE_NAME     U26 CE1
 '@T6G_MB_LIB.T6G(SCH_1):PAGE59_I2@PURE_QUANTA.GENOA_SP5(CHIPS)':
 'VSS_CE1': CDS_PINID='VSS_CE1';
NODE_NAME     U26 CE4
 '@T6G_MB_LIB.T6G(SCH_1):PAGE59_I2@PURE_QUANTA.GENOA_SP5(CHIPS)':
 'VSS_CE4': CDS_PINID='VSS_CE4';
NODE_NAME     U26 CE6
 '@T6G_MB_LIB.T6G(SCH_1):PAGE59_I2@PURE_QUANTA.GENOA_SP5(CHIPS)':
 'VSS_CE6': CDS_PINID='VSS_CE6';
NODE_NAME     U26 CE8
 '@T6G_MB_LIB.T6G(SCH_1):PAGE59_I2@PURE_QUANTA.GENOA_SP5(CHIPS)':
 'VSS_CE8': CDS_PINID='VSS_CE8';
NODE_NAME     U26 CE11
 '@T6G_MB_LIB.T6G(SCH_1):PAGE59_I2@PURE_QUANTA.GENOA_SP5(CHIPS)':
 'VSS_CE11': CDS_PINID='VSS_CE11';
NODE_NAME     U26 CE13
 '@T6G_MB_LIB.T6G(SCH_1):PAGE59_I2@PURE_QUANTA.GENOA_SP5(CHIPS)':
 'VSS_CE13': CDS_PINID='VSS_CE13';
NODE_NAME     U26 CE15
 '@T6G_MB_LIB.T6G(SCH_1):PAGE59_I2@PURE_QUANTA.GENOA_SP5(CHIPS)':
 'VSS_CE15': CDS_PINID='VSS_CE15';
NODE_NAME     U26 CE18
 '@T6G_MB_LIB.T6G(SCH_1):PAGE59_I2@PURE_QUANTA.GENOA_SP5(CHIPS)':
 'VSS_CE18': CDS_PINID='VSS_CE18';
NODE_NAME     U26 CE20
 '@T6G_MB_LIB.T6G(SCH_1):PAGE59_I2@PURE_QUANTA.GENOA_SP5(CHIPS)':
 'VSS_CE20': CDS_PINID='VSS_CE20';
NODE_NAME     U26 CE22
 '@T6G_MB_LIB.T6G(SCH_1):PAGE59_I2@PURE_QUANTA.GENOA_SP5(CHIPS)':
 'VSS_CE22': CDS_PINID='VSS_CE22';
NODE_NAME     U26 CE25
 '@T6G_MB_LIB.T6G(SCH_1):PAGE59_I2@PURE_QUANTA.GENOA_SP5(CHIPS)':
 'VSS_CE25': CDS_PINID='VSS_CE25';
NODE_NAME     U26 CE28
 '@T6G_MB_LIB.T6G(SCH_1):PAGE59_I2@PURE_QUANTA.GENOA_SP5(CHIPS)':
 'VSS_CE28': CDS_PINID='VSS_CE28';
NODE_NAME     U26 CE31
 '@T6G_MB_LIB.T6G(SCH_1):PAGE59_I2@PURE_QUANTA.GENOA_SP5(CHIPS)':
 'VSS_CE31': CDS_PINID='VSS_CE31';
NODE_NAME     U26 CE34
 '@T6G_MB_LIB.T6G(SCH_1):PAGE59_I2@PURE_QUANTA.GENOA_SP5(CHIPS)':
 'VSS_CE34': CDS_PINID='VSS_CE34';
NODE_NAME     U26 CE35
 '@T6G_MB_LIB.T6G(SCH_1):PAGE59_I2@PURE_QUANTA.GENOA_SP5(CHIPS)':
 'VSS_CE35': CDS_PINID='VSS_CE35';
NODE_NAME     U26 CE36
 '@T6G_MB_LIB.T6G(SCH_1):PAGE59_I2@PURE_QUANTA.GENOA_SP5(CHIPS)':
 'VSS_CE36': CDS_PINID='VSS_CE36';
NODE_NAME     U26 CE40
 '@T6G_MB_LIB.T6G(SCH_1):PAGE59_I2@PURE_QUANTA.GENOA_SP5(CHIPS)':
 'VSS_CE40': CDS_PINID='VSS_CE40';
NODE_NAME     U26 CE41
 '@T6G_MB_LIB.T6G(SCH_1):PAGE59_I2@PURE_QUANTA.GENOA_SP5(CHIPS)':
 'VSS_CE41': CDS_PINID='VSS_CE41';
NODE_NAME     U26 CE42
 '@T6G_MB_LIB.T6G(SCH_1):PAGE59_I2@PURE_QUANTA.GENOA_SP5(CHIPS)':
 'VSS_CE42': CDS_PINID='VSS_CE42';
NODE_NAME     U26 CE45
 '@T6G_MB_LIB.T6G(SCH_1):PAGE59_I2@PURE_QUANTA.GENOA_SP5(CHIPS)':
 'VSS_CE45': CDS_PINID='VSS_CE45';
NODE_NAME     U26 CE48
 '@T6G_MB_LIB.T6G(SCH_1):PAGE59_I2@PURE_QUANTA.GENOA_SP5(CHIPS)':
 'VSS_CE48': CDS_PINID='VSS_CE48';
NODE_NAME     U26 CE51
 '@T6G_MB_LIB.T6G(SCH_1):PAGE59_I2@PURE_QUANTA.GENOA_SP5(CHIPS)':
 'VSS_CE51': CDS_PINID='VSS_CE51';
NODE_NAME     U26 CE54
 '@T6G_MB_LIB.T6G(SCH_1):PAGE59_I2@PURE_QUANTA.GENOA_SP5(CHIPS)':
 'VSS_CE54': CDS_PINID='VSS_CE54';
NODE_NAME     U26 CE56
 '@T6G_MB_LIB.T6G(SCH_1):PAGE59_I2@PURE_QUANTA.GENOA_SP5(CHIPS)':
 'VSS_CE56': CDS_PINID='VSS_CE56';
NODE_NAME     U26 CE58
 '@T6G_MB_LIB.T6G(SCH_1):PAGE59_I2@PURE_QUANTA.GENOA_SP5(CHIPS)':
 'VSS_CE58': CDS_PINID='VSS_CE58';
NODE_NAME     U26 CE61
 '@T6G_MB_LIB.T6G(SCH_1):PAGE59_I2@PURE_QUANTA.GENOA_SP5(CHIPS)':
 'VSS_CE61': CDS_PINID='VSS_CE61';
NODE_NAME     U26 CE63
 '@T6G_MB_LIB.T6G(SCH_1):PAGE59_I2@PURE_QUANTA.GENOA_SP5(CHIPS)':
 'VSS_CE63': CDS_PINID='VSS_CE63';
NODE_NAME     U26 CE65
 '@T6G_MB_LIB.T6G(SCH_1):PAGE59_I2@PURE_QUANTA.GENOA_SP5(CHIPS)':
 'VSS_CE65': CDS_PINID='VSS_CE65';
NODE_NAME     U26 CE68
 '@T6G_MB_LIB.T6G(SCH_1):PAGE59_I2@PURE_QUANTA.GENOA_SP5(CHIPS)':
 'VSS_CE68': CDS_PINID='VSS_CE68';
NODE_NAME     U26 CE70
 '@T6G_MB_LIB.T6G(SCH_1):PAGE59_I2@PURE_QUANTA.GENOA_SP5(CHIPS)':
 'VSS_CE70': CDS_PINID='VSS_CE70';
NODE_NAME     U26 CE72
 '@T6G_MB_LIB.T6G(SCH_1):PAGE59_I2@PURE_QUANTA.GENOA_SP5(CHIPS)':
 'VSS_CE72': CDS_PINID='VSS_CE72';
NODE_NAME     U26 CE75
 '@T6G_MB_LIB.T6G(SCH_1):PAGE59_I2@PURE_QUANTA.GENOA_SP5(CHIPS)':
 'VSS_CE75': CDS_PINID='VSS_CE75';
NODE_NAME     U26 CF3
 '@T6G_MB_LIB.T6G(SCH_1):PAGE59_I2@PURE_QUANTA.GENOA_SP5(CHIPS)':
 'VSS_CF3': CDS_PINID='VSS_CF3';
NODE_NAME     U26 CF5
 '@T6G_MB_LIB.T6G(SCH_1):PAGE59_I2@PURE_QUANTA.GENOA_SP5(CHIPS)':
 'VSS_CF5': CDS_PINID='VSS_CF5';
NODE_NAME     U26 CF8
 '@T6G_MB_LIB.T6G(SCH_1):PAGE59_I2@PURE_QUANTA.GENOA_SP5(CHIPS)':
 'VSS_CF8': CDS_PINID='VSS_CF8';
NODE_NAME     U26 CF10
 '@T6G_MB_LIB.T6G(SCH_1):PAGE59_I2@PURE_QUANTA.GENOA_SP5(CHIPS)':
 'VSS_CF10': CDS_PINID='VSS_CF10';
NODE_NAME     U26 CF12
 '@T6G_MB_LIB.T6G(SCH_1):PAGE59_I2@PURE_QUANTA.GENOA_SP5(CHIPS)':
 'VSS_CF12': CDS_PINID='VSS_CF12';
NODE_NAME     U26 CF15
 '@T6G_MB_LIB.T6G(SCH_1):PAGE59_I2@PURE_QUANTA.GENOA_SP5(CHIPS)':
 'VSS_CF15': CDS_PINID='VSS_CF15';
NODE_NAME     U26 CF17
 '@T6G_MB_LIB.T6G(SCH_1):PAGE59_I2@PURE_QUANTA.GENOA_SP5(CHIPS)':
 'VSS_CF17': CDS_PINID='VSS_CF17';
NODE_NAME     U26 CF19
 '@T6G_MB_LIB.T6G(SCH_1):PAGE59_I2@PURE_QUANTA.GENOA_SP5(CHIPS)':
 'VSS_CF19': CDS_PINID='VSS_CF19';
NODE_NAME     U26 CF23
 '@T6G_MB_LIB.T6G(SCH_1):PAGE59_I2@PURE_QUANTA.GENOA_SP5(CHIPS)':
 'VSS_CF23': CDS_PINID='VSS_CF23';
NODE_NAME     U26 CF24
 '@T6G_MB_LIB.T6G(SCH_1):PAGE59_I2@PURE_QUANTA.GENOA_SP5(CHIPS)':
 'VSS_CF24': CDS_PINID='VSS_CF24';
NODE_NAME     U26 CF25
 '@T6G_MB_LIB.T6G(SCH_1):PAGE59_I2@PURE_QUANTA.GENOA_SP5(CHIPS)':
 'VSS_CF25': CDS_PINID='VSS_CF25';
NODE_NAME     U26 CF26
 '@T6G_MB_LIB.T6G(SCH_1):PAGE59_I2@PURE_QUANTA.GENOA_SP5(CHIPS)':
 'VSS_CF26': CDS_PINID='VSS_CF26';
NODE_NAME     U26 CF27
 '@T6G_MB_LIB.T6G(SCH_1):PAGE59_I2@PURE_QUANTA.GENOA_SP5(CHIPS)':
 'VSS_CF27': CDS_PINID='VSS_CF27';
NODE_NAME     U26 CF28
 '@T6G_MB_LIB.T6G(SCH_1):PAGE59_I2@PURE_QUANTA.GENOA_SP5(CHIPS)':
 'VSS_CF28': CDS_PINID='VSS_CF28';
NODE_NAME     U26 CF29
 '@T6G_MB_LIB.T6G(SCH_1):PAGE59_I2@PURE_QUANTA.GENOA_SP5(CHIPS)':
 'VSS_CF29': CDS_PINID='VSS_CF29';
NODE_NAME     U26 CF30
 '@T6G_MB_LIB.T6G(SCH_1):PAGE59_I2@PURE_QUANTA.GENOA_SP5(CHIPS)':
 'VSS_CF30': CDS_PINID='VSS_CF30';
NODE_NAME     U26 CF31
 '@T6G_MB_LIB.T6G(SCH_1):PAGE59_I2@PURE_QUANTA.GENOA_SP5(CHIPS)':
 'VSS_CF31': CDS_PINID='VSS_CF31';
NODE_NAME     U26 CF32
 '@T6G_MB_LIB.T6G(SCH_1):PAGE59_I2@PURE_QUANTA.GENOA_SP5(CHIPS)':
 'VSS_CF32': CDS_PINID='VSS_CF32';
NODE_NAME     U26 CF33
 '@T6G_MB_LIB.T6G(SCH_1):PAGE59_I2@PURE_QUANTA.GENOA_SP5(CHIPS)':
 'VSS_CF33': CDS_PINID='VSS_CF33';
NODE_NAME     U26 CF34
 '@T6G_MB_LIB.T6G(SCH_1):PAGE59_I3@PURE_QUANTA.GENOA_SP5(CHIPS)':
 'VSS_CF34': CDS_PINID='VSS_CF34';
NODE_NAME     U26 CF37
 '@T6G_MB_LIB.T6G(SCH_1):PAGE59_I3@PURE_QUANTA.GENOA_SP5(CHIPS)':
 'VSS_CF37': CDS_PINID='VSS_CF37';
NODE_NAME     U26 CF39
 '@T6G_MB_LIB.T6G(SCH_1):PAGE59_I3@PURE_QUANTA.GENOA_SP5(CHIPS)':
 'VSS_CF39': CDS_PINID='VSS_CF39';
NODE_NAME     U26 CF42
 '@T6G_MB_LIB.T6G(SCH_1):PAGE59_I3@PURE_QUANTA.GENOA_SP5(CHIPS)':
 'VSS_CF42': CDS_PINID='VSS_CF42';
NODE_NAME     U26 CF43
 '@T6G_MB_LIB.T6G(SCH_1):PAGE59_I3@PURE_QUANTA.GENOA_SP5(CHIPS)':
 'VSS_CF43': CDS_PINID='VSS_CF43';
NODE_NAME     U26 CF44
 '@T6G_MB_LIB.T6G(SCH_1):PAGE59_I3@PURE_QUANTA.GENOA_SP5(CHIPS)':
 'VSS_CF44': CDS_PINID='VSS_CF44';
NODE_NAME     U26 CF45
 '@T6G_MB_LIB.T6G(SCH_1):PAGE59_I3@PURE_QUANTA.GENOA_SP5(CHIPS)':
 'VSS_CF45': CDS_PINID='VSS_CF45';
NODE_NAME     U26 CF47
 '@T6G_MB_LIB.T6G(SCH_1):PAGE59_I3@PURE_QUANTA.GENOA_SP5(CHIPS)':
 'VSS_CF47': CDS_PINID='VSS_CF47';
NODE_NAME     U26 CF48
 '@T6G_MB_LIB.T6G(SCH_1):PAGE59_I3@PURE_QUANTA.GENOA_SP5(CHIPS)':
 'VSS_CF48': CDS_PINID='VSS_CF48';
NODE_NAME     U26 CF49
 '@T6G_MB_LIB.T6G(SCH_1):PAGE59_I3@PURE_QUANTA.GENOA_SP5(CHIPS)':
 'VSS_CF49': CDS_PINID='VSS_CF49';
NODE_NAME     U26 CF50
 '@T6G_MB_LIB.T6G(SCH_1):PAGE59_I3@PURE_QUANTA.GENOA_SP5(CHIPS)':
 'VSS_CF50': CDS_PINID='VSS_CF50';
NODE_NAME     U26 CF51
 '@T6G_MB_LIB.T6G(SCH_1):PAGE59_I3@PURE_QUANTA.GENOA_SP5(CHIPS)':
 'VSS_CF51': CDS_PINID='VSS_CF51';
NODE_NAME     U26 CF52
 '@T6G_MB_LIB.T6G(SCH_1):PAGE59_I3@PURE_QUANTA.GENOA_SP5(CHIPS)':
 'VSS_CF52': CDS_PINID='VSS_CF52';
NODE_NAME     U26 CF53
 '@T6G_MB_LIB.T6G(SCH_1):PAGE59_I3@PURE_QUANTA.GENOA_SP5(CHIPS)':
 'VSS_CF53': CDS_PINID='VSS_CF53';
NODE_NAME     U26 CF57
 '@T6G_MB_LIB.T6G(SCH_1):PAGE59_I3@PURE_QUANTA.GENOA_SP5(CHIPS)':
 'VSS_CF57': CDS_PINID='VSS_CF57';
NODE_NAME     U26 CF59
 '@T6G_MB_LIB.T6G(SCH_1):PAGE59_I3@PURE_QUANTA.GENOA_SP5(CHIPS)':
 'VSS_CF59': CDS_PINID='VSS_CF59';
NODE_NAME     U26 CF61
 '@T6G_MB_LIB.T6G(SCH_1):PAGE59_I3@PURE_QUANTA.GENOA_SP5(CHIPS)':
 'VSS_CF61': CDS_PINID='VSS_CF61';
NODE_NAME     U26 CF64
 '@T6G_MB_LIB.T6G(SCH_1):PAGE59_I3@PURE_QUANTA.GENOA_SP5(CHIPS)':
 'VSS_CF64': CDS_PINID='VSS_CF64';
NODE_NAME     U26 CF66
 '@T6G_MB_LIB.T6G(SCH_1):PAGE59_I3@PURE_QUANTA.GENOA_SP5(CHIPS)':
 'VSS_CF66': CDS_PINID='VSS_CF66';
NODE_NAME     U26 CF68
 '@T6G_MB_LIB.T6G(SCH_1):PAGE59_I3@PURE_QUANTA.GENOA_SP5(CHIPS)':
 'VSS_CF68': CDS_PINID='VSS_CF68';
NODE_NAME     U26 CF71
 '@T6G_MB_LIB.T6G(SCH_1):PAGE59_I3@PURE_QUANTA.GENOA_SP5(CHIPS)':
 'VSS_CF71': CDS_PINID='VSS_CF71';
NODE_NAME     U26 CF73
 '@T6G_MB_LIB.T6G(SCH_1):PAGE59_I3@PURE_QUANTA.GENOA_SP5(CHIPS)':
 'VSS_CF73': CDS_PINID='VSS_CF73';
NODE_NAME     U26 CG1
 '@T6G_MB_LIB.T6G(SCH_1):PAGE59_I3@PURE_QUANTA.GENOA_SP5(CHIPS)':
 'VSS_CG1': CDS_PINID='VSS_CG1';
NODE_NAME     U26 CG6
 '@T6G_MB_LIB.T6G(SCH_1):PAGE59_I3@PURE_QUANTA.GENOA_SP5(CHIPS)':
 'VSS_CG6': CDS_PINID='VSS_CG6';
NODE_NAME     U26 CG8
 '@T6G_MB_LIB.T6G(SCH_1):PAGE59_I3@PURE_QUANTA.GENOA_SP5(CHIPS)':
 'VSS_CG8': CDS_PINID='VSS_CG8';
NODE_NAME     U26 CG13
 '@T6G_MB_LIB.T6G(SCH_1):PAGE59_I3@PURE_QUANTA.GENOA_SP5(CHIPS)':
 'VSS_CG13': CDS_PINID='VSS_CG13';
NODE_NAME     U26 CG15
 '@T6G_MB_LIB.T6G(SCH_1):PAGE59_I3@PURE_QUANTA.GENOA_SP5(CHIPS)':
 'VSS_CG15': CDS_PINID='VSS_CG15';
NODE_NAME     U26 CG20
 '@T6G_MB_LIB.T6G(SCH_1):PAGE59_I3@PURE_QUANTA.GENOA_SP5(CHIPS)':
 'VSS_CG20': CDS_PINID='VSS_CG20';
NODE_NAME     U26 CG22
 '@T6G_MB_LIB.T6G(SCH_1):PAGE59_I3@PURE_QUANTA.GENOA_SP5(CHIPS)':
 'VSS_CG22': CDS_PINID='VSS_CG22';
NODE_NAME     U26 CG25
 '@T6G_MB_LIB.T6G(SCH_1):PAGE59_I3@PURE_QUANTA.GENOA_SP5(CHIPS)':
 'VSS_CG25': CDS_PINID='VSS_CG25';
NODE_NAME     U26 CG28
 '@T6G_MB_LIB.T6G(SCH_1):PAGE59_I3@PURE_QUANTA.GENOA_SP5(CHIPS)':
 'VSS_CG28': CDS_PINID='VSS_CG28';
NODE_NAME     U26 CG31
 '@T6G_MB_LIB.T6G(SCH_1):PAGE59_I3@PURE_QUANTA.GENOA_SP5(CHIPS)':
 'VSS_CG31': CDS_PINID='VSS_CG31';
NODE_NAME     U26 CG34
 '@T6G_MB_LIB.T6G(SCH_1):PAGE59_I3@PURE_QUANTA.GENOA_SP5(CHIPS)':
 'VSS_CG34': CDS_PINID='VSS_CG34';
NODE_NAME     U26 CG45
 '@T6G_MB_LIB.T6G(SCH_1):PAGE59_I3@PURE_QUANTA.GENOA_SP5(CHIPS)':
 'VSS_CG45': CDS_PINID='VSS_CG45';
NODE_NAME     U26 CG48
 '@T6G_MB_LIB.T6G(SCH_1):PAGE59_I3@PURE_QUANTA.GENOA_SP5(CHIPS)':
 'VSS_CG48': CDS_PINID='VSS_CG48';
NODE_NAME     U26 CG51
 '@T6G_MB_LIB.T6G(SCH_1):PAGE59_I3@PURE_QUANTA.GENOA_SP5(CHIPS)':
 'VSS_CG51': CDS_PINID='VSS_CG51';
NODE_NAME     U26 CG54
 '@T6G_MB_LIB.T6G(SCH_1):PAGE59_I3@PURE_QUANTA.GENOA_SP5(CHIPS)':
 'VSS_CG54': CDS_PINID='VSS_CG54';
NODE_NAME     U26 CG56
 '@T6G_MB_LIB.T6G(SCH_1):PAGE59_I3@PURE_QUANTA.GENOA_SP5(CHIPS)':
 'VSS_CG56': CDS_PINID='VSS_CG56';
NODE_NAME     U26 CG61
 '@T6G_MB_LIB.T6G(SCH_1):PAGE59_I3@PURE_QUANTA.GENOA_SP5(CHIPS)':
 'VSS_CG61': CDS_PINID='VSS_CG61';
NODE_NAME     U26 CG63
 '@T6G_MB_LIB.T6G(SCH_1):PAGE59_I3@PURE_QUANTA.GENOA_SP5(CHIPS)':
 'VSS_CG63': CDS_PINID='VSS_CG63';
NODE_NAME     U26 CG68
 '@T6G_MB_LIB.T6G(SCH_1):PAGE59_I3@PURE_QUANTA.GENOA_SP5(CHIPS)':
 'VSS_CG68': CDS_PINID='VSS_CG68';
NODE_NAME     U26 CG70
 '@T6G_MB_LIB.T6G(SCH_1):PAGE59_I3@PURE_QUANTA.GENOA_SP5(CHIPS)':
 'VSS_CG70': CDS_PINID='VSS_CG70';
NODE_NAME     U26 CG75
 '@T6G_MB_LIB.T6G(SCH_1):PAGE59_I3@PURE_QUANTA.GENOA_SP5(CHIPS)':
 'VSS_CG75': CDS_PINID='VSS_CG75';
NODE_NAME     U26 CH3
 '@T6G_MB_LIB.T6G(SCH_1):PAGE59_I3@PURE_QUANTA.GENOA_SP5(CHIPS)':
 'VSS_CH3': CDS_PINID='VSS_CH3';
NODE_NAME     U26 CH5
 '@T6G_MB_LIB.T6G(SCH_1):PAGE59_I3@PURE_QUANTA.GENOA_SP5(CHIPS)':
 'VSS_CH5': CDS_PINID='VSS_CH5';
NODE_NAME     U26 CH8
 '@T6G_MB_LIB.T6G(SCH_1):PAGE59_I3@PURE_QUANTA.GENOA_SP5(CHIPS)':
 'VSS_CH8': CDS_PINID='VSS_CH8';
NODE_NAME     U26 CH10
 '@T6G_MB_LIB.T6G(SCH_1):PAGE59_I3@PURE_QUANTA.GENOA_SP5(CHIPS)':
 'VSS_CH10': CDS_PINID='VSS_CH10';
NODE_NAME     U26 CH12
 '@T6G_MB_LIB.T6G(SCH_1):PAGE59_I3@PURE_QUANTA.GENOA_SP5(CHIPS)':
 'VSS_CH12': CDS_PINID='VSS_CH12';
NODE_NAME     U26 CH15
 '@T6G_MB_LIB.T6G(SCH_1):PAGE59_I3@PURE_QUANTA.GENOA_SP5(CHIPS)':
 'VSS_CH15': CDS_PINID='VSS_CH15';
NODE_NAME     U26 CH17
 '@T6G_MB_LIB.T6G(SCH_1):PAGE59_I3@PURE_QUANTA.GENOA_SP5(CHIPS)':
 'VSS_CH17': CDS_PINID='VSS_CH17';
NODE_NAME     U26 CH19
 '@T6G_MB_LIB.T6G(SCH_1):PAGE59_I3@PURE_QUANTA.GENOA_SP5(CHIPS)':
 'VSS_CH19': CDS_PINID='VSS_CH19';
NODE_NAME     U26 CH22
 '@T6G_MB_LIB.T6G(SCH_1):PAGE59_I3@PURE_QUANTA.GENOA_SP5(CHIPS)':
 'VSS_CH22': CDS_PINID='VSS_CH22';
NODE_NAME     U26 CH25
 '@T6G_MB_LIB.T6G(SCH_1):PAGE59_I3@PURE_QUANTA.GENOA_SP5(CHIPS)':
 'VSS_CH25': CDS_PINID='VSS_CH25';
NODE_NAME     U26 CH28
 '@T6G_MB_LIB.T6G(SCH_1):PAGE59_I3@PURE_QUANTA.GENOA_SP5(CHIPS)':
 'VSS_CH28': CDS_PINID='VSS_CH28';
NODE_NAME     U26 CH31
 '@T6G_MB_LIB.T6G(SCH_1):PAGE59_I3@PURE_QUANTA.GENOA_SP5(CHIPS)':
 'VSS_CH31': CDS_PINID='VSS_CH31';
NODE_NAME     U26 CH34
 '@T6G_MB_LIB.T6G(SCH_1):PAGE59_I3@PURE_QUANTA.GENOA_SP5(CHIPS)':
 'VSS_CH34': CDS_PINID='VSS_CH34';
NODE_NAME     U26 CH37
 '@T6G_MB_LIB.T6G(SCH_1):PAGE59_I3@PURE_QUANTA.GENOA_SP5(CHIPS)':
 'VSS_CH37': CDS_PINID='VSS_CH37';
NODE_NAME     U26 CH39
 '@T6G_MB_LIB.T6G(SCH_1):PAGE59_I3@PURE_QUANTA.GENOA_SP5(CHIPS)':
 'VSS_CH39': CDS_PINID='VSS_CH39';
NODE_NAME     U26 CH42
 '@T6G_MB_LIB.T6G(SCH_1):PAGE59_I3@PURE_QUANTA.GENOA_SP5(CHIPS)':
 'VSS_CH42': CDS_PINID='VSS_CH42';
NODE_NAME     U26 CH45
 '@T6G_MB_LIB.T6G(SCH_1):PAGE59_I3@PURE_QUANTA.GENOA_SP5(CHIPS)':
 'VSS_CH45': CDS_PINID='VSS_CH45';
NODE_NAME     U26 CH48
 '@T6G_MB_LIB.T6G(SCH_1):PAGE59_I3@PURE_QUANTA.GENOA_SP5(CHIPS)':
 'VSS_CH48': CDS_PINID='VSS_CH48';
NODE_NAME     U26 CH51
 '@T6G_MB_LIB.T6G(SCH_1):PAGE59_I3@PURE_QUANTA.GENOA_SP5(CHIPS)':
 'VSS_CH51': CDS_PINID='VSS_CH51';
NODE_NAME     U26 CH54
 '@T6G_MB_LIB.T6G(SCH_1):PAGE59_I3@PURE_QUANTA.GENOA_SP5(CHIPS)':
 'VSS_CH54': CDS_PINID='VSS_CH54';
NODE_NAME     U26 CH57
 '@T6G_MB_LIB.T6G(SCH_1):PAGE59_I3@PURE_QUANTA.GENOA_SP5(CHIPS)':
 'VSS_CH57': CDS_PINID='VSS_CH57';
NODE_NAME     U26 CH59
 '@T6G_MB_LIB.T6G(SCH_1):PAGE59_I3@PURE_QUANTA.GENOA_SP5(CHIPS)':
 'VSS_CH59': CDS_PINID='VSS_CH59';
NODE_NAME     U26 CH61
 '@T6G_MB_LIB.T6G(SCH_1):PAGE59_I3@PURE_QUANTA.GENOA_SP5(CHIPS)':
 'VSS_CH61': CDS_PINID='VSS_CH61';
NODE_NAME     U26 CH64
 '@T6G_MB_LIB.T6G(SCH_1):PAGE59_I3@PURE_QUANTA.GENOA_SP5(CHIPS)':
 'VSS_CH64': CDS_PINID='VSS_CH64';
NODE_NAME     U26 CH66
 '@T6G_MB_LIB.T6G(SCH_1):PAGE59_I3@PURE_QUANTA.GENOA_SP5(CHIPS)':
 'VSS_CH66': CDS_PINID='VSS_CH66';
NODE_NAME     U26 CH68
 '@T6G_MB_LIB.T6G(SCH_1):PAGE59_I3@PURE_QUANTA.GENOA_SP5(CHIPS)':
 'VSS_CH68': CDS_PINID='VSS_CH68';
NODE_NAME     U26 CH71
 '@T6G_MB_LIB.T6G(SCH_1):PAGE59_I3@PURE_QUANTA.GENOA_SP5(CHIPS)':
 'VSS_CH71': CDS_PINID='VSS_CH71';
NODE_NAME     U26 CH73
 '@T6G_MB_LIB.T6G(SCH_1):PAGE59_I3@PURE_QUANTA.GENOA_SP5(CHIPS)':
 'VSS_CH73': CDS_PINID='VSS_CH73';
NODE_NAME     U26 CJ1
 '@T6G_MB_LIB.T6G(SCH_1):PAGE59_I3@PURE_QUANTA.GENOA_SP5(CHIPS)':
 'VSS_CJ1': CDS_PINID='VSS_CJ1';
NODE_NAME     U26 CJ4
 '@T6G_MB_LIB.T6G(SCH_1):PAGE59_I3@PURE_QUANTA.GENOA_SP5(CHIPS)':
 'VSS_CJ4': CDS_PINID='VSS_CJ4';
NODE_NAME     U26 CJ6
 '@T6G_MB_LIB.T6G(SCH_1):PAGE59_I3@PURE_QUANTA.GENOA_SP5(CHIPS)':
 'VSS_CJ6': CDS_PINID='VSS_CJ6';
NODE_NAME     U26 CJ8
 '@T6G_MB_LIB.T6G(SCH_1):PAGE59_I3@PURE_QUANTA.GENOA_SP5(CHIPS)':
 'VSS_CJ8': CDS_PINID='VSS_CJ8';
NODE_NAME     U26 CJ11
 '@T6G_MB_LIB.T6G(SCH_1):PAGE59_I3@PURE_QUANTA.GENOA_SP5(CHIPS)':
 'VSS_CJ11': CDS_PINID='VSS_CJ11';
NODE_NAME     U26 CJ13
 '@T6G_MB_LIB.T6G(SCH_1):PAGE59_I3@PURE_QUANTA.GENOA_SP5(CHIPS)':
 'VSS_CJ13': CDS_PINID='VSS_CJ13';
NODE_NAME     U26 CJ15
 '@T6G_MB_LIB.T6G(SCH_1):PAGE59_I3@PURE_QUANTA.GENOA_SP5(CHIPS)':
 'VSS_CJ15': CDS_PINID='VSS_CJ15';
NODE_NAME     U26 CJ18
 '@T6G_MB_LIB.T6G(SCH_1):PAGE59_I3@PURE_QUANTA.GENOA_SP5(CHIPS)':
 'VSS_CJ18': CDS_PINID='VSS_CJ18';
NODE_NAME     U26 CJ20
 '@T6G_MB_LIB.T6G(SCH_1):PAGE59_I3@PURE_QUANTA.GENOA_SP5(CHIPS)':
 'VSS_CJ20': CDS_PINID='VSS_CJ20';
NODE_NAME     U26 CJ23
 '@T6G_MB_LIB.T6G(SCH_1):PAGE59_I3@PURE_QUANTA.GENOA_SP5(CHIPS)':
 'VSS_CJ23': CDS_PINID='VSS_CJ23';
NODE_NAME     U26 CJ31
 '@T6G_MB_LIB.T6G(SCH_1):PAGE59_I3@PURE_QUANTA.GENOA_SP5(CHIPS)':
 'VSS_CJ31': CDS_PINID='VSS_CJ31';
NODE_NAME     U26 CJ34
 '@T6G_MB_LIB.T6G(SCH_1):PAGE59_I3@PURE_QUANTA.GENOA_SP5(CHIPS)':
 'VSS_CJ34': CDS_PINID='VSS_CJ34';
NODE_NAME     U26 CJ35
 '@T6G_MB_LIB.T6G(SCH_1):PAGE59_I3@PURE_QUANTA.GENOA_SP5(CHIPS)':
 'VSS_CJ35': CDS_PINID='VSS_CJ35';
NODE_NAME     U26 CJ36
 '@T6G_MB_LIB.T6G(SCH_1):PAGE59_I3@PURE_QUANTA.GENOA_SP5(CHIPS)':
 'VSS_CJ36': CDS_PINID='VSS_CJ36';
NODE_NAME     U26 CJ40
 '@T6G_MB_LIB.T6G(SCH_1):PAGE59_I3@PURE_QUANTA.GENOA_SP5(CHIPS)':
 'VSS_CJ40': CDS_PINID='VSS_CJ40';
NODE_NAME     U26 CJ41
 '@T6G_MB_LIB.T6G(SCH_1):PAGE59_I3@PURE_QUANTA.GENOA_SP5(CHIPS)':
 'VSS_CJ41': CDS_PINID='VSS_CJ41';
NODE_NAME     U26 CJ42
 '@T6G_MB_LIB.T6G(SCH_1):PAGE59_I3@PURE_QUANTA.GENOA_SP5(CHIPS)':
 'VSS_CJ42': CDS_PINID='VSS_CJ42';
NODE_NAME     U26 CJ45
 '@T6G_MB_LIB.T6G(SCH_1):PAGE59_I3@PURE_QUANTA.GENOA_SP5(CHIPS)':
 'VSS_CJ45': CDS_PINID='VSS_CJ45';
NODE_NAME     U26 CJ56
 '@T6G_MB_LIB.T6G(SCH_1):PAGE59_I3@PURE_QUANTA.GENOA_SP5(CHIPS)':
 'VSS_CJ56': CDS_PINID='VSS_CJ56';
NODE_NAME     U26 CJ58
 '@T6G_MB_LIB.T6G(SCH_1):PAGE59_I3@PURE_QUANTA.GENOA_SP5(CHIPS)':
 'VSS_CJ58': CDS_PINID='VSS_CJ58';
NODE_NAME     U26 CJ61
 '@T6G_MB_LIB.T6G(SCH_1):PAGE59_I3@PURE_QUANTA.GENOA_SP5(CHIPS)':
 'VSS_CJ61': CDS_PINID='VSS_CJ61';
NODE_NAME     U26 CJ63
 '@T6G_MB_LIB.T6G(SCH_1):PAGE59_I3@PURE_QUANTA.GENOA_SP5(CHIPS)':
 'VSS_CJ63': CDS_PINID='VSS_CJ63';
NODE_NAME     U26 CJ65
 '@T6G_MB_LIB.T6G(SCH_1):PAGE59_I3@PURE_QUANTA.GENOA_SP5(CHIPS)':
 'VSS_CJ65': CDS_PINID='VSS_CJ65';
NODE_NAME     U26 CJ68
 '@T6G_MB_LIB.T6G(SCH_1):PAGE59_I3@PURE_QUANTA.GENOA_SP5(CHIPS)':
 'VSS_CJ68': CDS_PINID='VSS_CJ68';
NODE_NAME     U26 CJ70
 '@T6G_MB_LIB.T6G(SCH_1):PAGE59_I3@PURE_QUANTA.GENOA_SP5(CHIPS)':
 'VSS_CJ70': CDS_PINID='VSS_CJ70';
NODE_NAME     U26 CJ72
 '@T6G_MB_LIB.T6G(SCH_1):PAGE59_I3@PURE_QUANTA.GENOA_SP5(CHIPS)':
 'VSS_CJ72': CDS_PINID='VSS_CJ72';
NODE_NAME     U26 CJ75
 '@T6G_MB_LIB.T6G(SCH_1):PAGE59_I3@PURE_QUANTA.GENOA_SP5(CHIPS)':
 'VSS_CJ75': CDS_PINID='VSS_CJ75';
NODE_NAME     U26 CK3
 '@T6G_MB_LIB.T6G(SCH_1):PAGE59_I3@PURE_QUANTA.GENOA_SP5(CHIPS)':
 'VSS_CK3': CDS_PINID='VSS_CK3';
NODE_NAME     U26 CK8
 '@T6G_MB_LIB.T6G(SCH_1):PAGE59_I3@PURE_QUANTA.GENOA_SP5(CHIPS)':
 'VSS_CK8': CDS_PINID='VSS_CK8';
NODE_NAME     U26 CK15
 '@T6G_MB_LIB.T6G(SCH_1):PAGE59_I3@PURE_QUANTA.GENOA_SP5(CHIPS)':
 'VSS_CK15': CDS_PINID='VSS_CK15';
NODE_NAME     U26 CK17
 '@T6G_MB_LIB.T6G(SCH_1):PAGE59_I3@PURE_QUANTA.GENOA_SP5(CHIPS)':
 'VSS_CK17': CDS_PINID='VSS_CK17';
NODE_NAME     U26 CK22
 '@T6G_MB_LIB.T6G(SCH_1):PAGE59_I3@PURE_QUANTA.GENOA_SP5(CHIPS)':
 'VSS_CK22': CDS_PINID='VSS_CK22';
NODE_NAME     U26 CK23
 '@T6G_MB_LIB.T6G(SCH_1):PAGE59_I3@PURE_QUANTA.GENOA_SP5(CHIPS)':
 'VSS_CK23': CDS_PINID='VSS_CK23';
NODE_NAME     U26 CK24
 '@T6G_MB_LIB.T6G(SCH_1):PAGE59_I3@PURE_QUANTA.GENOA_SP5(CHIPS)':
 'VSS_CK24': CDS_PINID='VSS_CK24';
NODE_NAME     U26 CK25
 '@T6G_MB_LIB.T6G(SCH_1):PAGE59_I3@PURE_QUANTA.GENOA_SP5(CHIPS)':
 'VSS_CK25': CDS_PINID='VSS_CK25';
NODE_NAME     U26 CK26
 '@T6G_MB_LIB.T6G(SCH_1):PAGE59_I3@PURE_QUANTA.GENOA_SP5(CHIPS)':
 'VSS_CK26': CDS_PINID='VSS_CK26';
NODE_NAME     U26 CK27
 '@T6G_MB_LIB.T6G(SCH_1):PAGE59_I3@PURE_QUANTA.GENOA_SP5(CHIPS)':
 'VSS_CK27': CDS_PINID='VSS_CK27';
NODE_NAME     U26 CK28
 '@T6G_MB_LIB.T6G(SCH_1):PAGE59_I3@PURE_QUANTA.GENOA_SP5(CHIPS)':
 'VSS_CK28': CDS_PINID='VSS_CK28';
NODE_NAME     U26 CK32
 '@T6G_MB_LIB.T6G(SCH_1):PAGE59_I3@PURE_QUANTA.GENOA_SP5(CHIPS)':
 'VSS_CK32': CDS_PINID='VSS_CK32';
NODE_NAME     U26 CK33
 '@T6G_MB_LIB.T6G(SCH_1):PAGE59_I3@PURE_QUANTA.GENOA_SP5(CHIPS)':
 'VSS_CK33': CDS_PINID='VSS_CK33';
NODE_NAME     U26 CK34
 '@T6G_MB_LIB.T6G(SCH_1):PAGE59_I3@PURE_QUANTA.GENOA_SP5(CHIPS)':
 'VSS_CK34': CDS_PINID='VSS_CK34';
NODE_NAME     U26 CK37
 '@T6G_MB_LIB.T6G(SCH_1):PAGE59_I3@PURE_QUANTA.GENOA_SP5(CHIPS)':
 'VSS_CK37': CDS_PINID='VSS_CK37';
NODE_NAME     U26 CK39
 '@T6G_MB_LIB.T6G(SCH_1):PAGE59_I3@PURE_QUANTA.GENOA_SP5(CHIPS)':
 'VSS_CK39': CDS_PINID='VSS_CK39';
NODE_NAME     U26 CK42
 '@T6G_MB_LIB.T6G(SCH_1):PAGE59_I3@PURE_QUANTA.GENOA_SP5(CHIPS)':
 'VSS_CK42': CDS_PINID='VSS_CK42';
NODE_NAME     U26 CK43
 '@T6G_MB_LIB.T6G(SCH_1):PAGE59_I3@PURE_QUANTA.GENOA_SP5(CHIPS)':
 'VSS_CK43': CDS_PINID='VSS_CK43';
NODE_NAME     U26 CK44
 '@T6G_MB_LIB.T6G(SCH_1):PAGE59_I3@PURE_QUANTA.GENOA_SP5(CHIPS)':
 'VSS_CK44': CDS_PINID='VSS_CK44';
NODE_NAME     U26 CK45
 '@T6G_MB_LIB.T6G(SCH_1):PAGE59_I3@PURE_QUANTA.GENOA_SP5(CHIPS)':
 'VSS_CK45': CDS_PINID='VSS_CK45';
NODE_NAME     U26 CK48
 '@T6G_MB_LIB.T6G(SCH_1):PAGE59_I3@PURE_QUANTA.GENOA_SP5(CHIPS)':
 'VSS_CK48': CDS_PINID='VSS_CK48';
NODE_NAME     U26 CK49
 '@T6G_MB_LIB.T6G(SCH_1):PAGE59_I3@PURE_QUANTA.GENOA_SP5(CHIPS)':
 'VSS_CK49': CDS_PINID='VSS_CK49';
NODE_NAME     U26 CK50
 '@T6G_MB_LIB.T6G(SCH_1):PAGE59_I3@PURE_QUANTA.GENOA_SP5(CHIPS)':
 'VSS_CK50': CDS_PINID='VSS_CK50';
NODE_NAME     U26 CK51
 '@T6G_MB_LIB.T6G(SCH_1):PAGE59_I3@PURE_QUANTA.GENOA_SP5(CHIPS)':
 'VSS_CK51': CDS_PINID='VSS_CK51';
NODE_NAME     U26 CK52
 '@T6G_MB_LIB.T6G(SCH_1):PAGE59_I3@PURE_QUANTA.GENOA_SP5(CHIPS)':
 'VSS_CK52': CDS_PINID='VSS_CK52';
NODE_NAME     U26 CK53
 '@T6G_MB_LIB.T6G(SCH_1):PAGE59_I3@PURE_QUANTA.GENOA_SP5(CHIPS)':
 'VSS_CK53': CDS_PINID='VSS_CK53';
NODE_NAME     U26 CK54
 '@T6G_MB_LIB.T6G(SCH_1):PAGE59_I3@PURE_QUANTA.GENOA_SP5(CHIPS)':
 'VSS_CK54': CDS_PINID='VSS_CK54';
NODE_NAME     U26 CK59
 '@T6G_MB_LIB.T6G(SCH_1):PAGE59_I3@PURE_QUANTA.GENOA_SP5(CHIPS)':
 'VSS_CK59': CDS_PINID='VSS_CK59';
NODE_NAME     U26 CK61
 '@T6G_MB_LIB.T6G(SCH_1):PAGE59_I3@PURE_QUANTA.GENOA_SP5(CHIPS)':
 'VSS_CK61': CDS_PINID='VSS_CK61';
NODE_NAME     U26 CK66
 '@T6G_MB_LIB.T6G(SCH_1):PAGE59_I3@PURE_QUANTA.GENOA_SP5(CHIPS)':
 'VSS_CK66': CDS_PINID='VSS_CK66';
NODE_NAME     U26 CK68
 '@T6G_MB_LIB.T6G(SCH_1):PAGE59_I3@PURE_QUANTA.GENOA_SP5(CHIPS)':
 'VSS_CK68': CDS_PINID='VSS_CK68';
NODE_NAME     U26 CK73
 '@T6G_MB_LIB.T6G(SCH_1):PAGE59_I3@PURE_QUANTA.GENOA_SP5(CHIPS)':
 'VSS_CK73': CDS_PINID='VSS_CK73';
NODE_NAME     U26 CL1
 '@T6G_MB_LIB.T6G(SCH_1):PAGE59_I3@PURE_QUANTA.GENOA_SP5(CHIPS)':
 'VSS_CL1': CDS_PINID='VSS_CL1';
NODE_NAME     U26 CL4
 '@T6G_MB_LIB.T6G(SCH_1):PAGE59_I3@PURE_QUANTA.GENOA_SP5(CHIPS)':
 'VSS_CL4': CDS_PINID='VSS_CL4';
NODE_NAME     U26 CL6
 '@T6G_MB_LIB.T6G(SCH_1):PAGE59_I3@PURE_QUANTA.GENOA_SP5(CHIPS)':
 'VSS_CL6': CDS_PINID='VSS_CL6';
NODE_NAME     U26 CL8
 '@T6G_MB_LIB.T6G(SCH_1):PAGE59_I3@PURE_QUANTA.GENOA_SP5(CHIPS)':
 'VSS_CL8': CDS_PINID='VSS_CL8';
NODE_NAME     U26 CL11
 '@T6G_MB_LIB.T6G(SCH_1):PAGE59_I3@PURE_QUANTA.GENOA_SP5(CHIPS)':
 'VSS_CL11': CDS_PINID='VSS_CL11';
NODE_NAME     U26 CL13
 '@T6G_MB_LIB.T6G(SCH_1):PAGE59_I3@PURE_QUANTA.GENOA_SP5(CHIPS)':
 'VSS_CL13': CDS_PINID='VSS_CL13';
NODE_NAME     U26 CL15
 '@T6G_MB_LIB.T6G(SCH_1):PAGE59_I3@PURE_QUANTA.GENOA_SP5(CHIPS)':
 'VSS_CL15': CDS_PINID='VSS_CL15';
NODE_NAME     U26 CL18
 '@T6G_MB_LIB.T6G(SCH_1):PAGE59_I3@PURE_QUANTA.GENOA_SP5(CHIPS)':
 'VSS_CL18': CDS_PINID='VSS_CL18';
NODE_NAME     U26 CL20
 '@T6G_MB_LIB.T6G(SCH_1):PAGE59_I3@PURE_QUANTA.GENOA_SP5(CHIPS)':
 'VSS_CL20': CDS_PINID='VSS_CL20';
NODE_NAME     U26 CL22
 '@T6G_MB_LIB.T6G(SCH_1):PAGE59_I3@PURE_QUANTA.GENOA_SP5(CHIPS)':
 'VSS_CL22': CDS_PINID='VSS_CL22';
NODE_NAME     U26 CL25
 '@T6G_MB_LIB.T6G(SCH_1):PAGE59_I3@PURE_QUANTA.GENOA_SP5(CHIPS)':
 'VSS_CL25': CDS_PINID='VSS_CL25';
NODE_NAME     U26 CL28
 '@T6G_MB_LIB.T6G(SCH_1):PAGE59_I3@PURE_QUANTA.GENOA_SP5(CHIPS)':
 'VSS_CL28': CDS_PINID='VSS_CL28';
NODE_NAME     U26 CL31
 '@T6G_MB_LIB.T6G(SCH_1):PAGE59_I3@PURE_QUANTA.GENOA_SP5(CHIPS)':
 'VSS_CL31': CDS_PINID='VSS_CL31';
NODE_NAME     U26 CL34
 '@T6G_MB_LIB.T6G(SCH_1):PAGE59_I3@PURE_QUANTA.GENOA_SP5(CHIPS)':
 'VSS_CL34': CDS_PINID='VSS_CL34';
NODE_NAME     U26 CL35
 '@T6G_MB_LIB.T6G(SCH_1):PAGE59_I3@PURE_QUANTA.GENOA_SP5(CHIPS)':
 'VSS_CL35': CDS_PINID='VSS_CL35';
NODE_NAME     U26 CL36
 '@T6G_MB_LIB.T6G(SCH_1):PAGE59_I3@PURE_QUANTA.GENOA_SP5(CHIPS)':
 'VSS_CL36': CDS_PINID='VSS_CL36';
NODE_NAME     U26 CL40
 '@T6G_MB_LIB.T6G(SCH_1):PAGE59_I3@PURE_QUANTA.GENOA_SP5(CHIPS)':
 'VSS_CL40': CDS_PINID='VSS_CL40';
NODE_NAME     U26 CL41
 '@T6G_MB_LIB.T6G(SCH_1):PAGE59_I3@PURE_QUANTA.GENOA_SP5(CHIPS)':
 'VSS_CL41': CDS_PINID='VSS_CL41';
NODE_NAME     U26 CL42
 '@T6G_MB_LIB.T6G(SCH_1):PAGE59_I3@PURE_QUANTA.GENOA_SP5(CHIPS)':
 'VSS_CL42': CDS_PINID='VSS_CL42';
NODE_NAME     U26 CL45
 '@T6G_MB_LIB.T6G(SCH_1):PAGE59_I3@PURE_QUANTA.GENOA_SP5(CHIPS)':
 'VSS_CL45': CDS_PINID='VSS_CL45';
NODE_NAME     U26 CL48
 '@T6G_MB_LIB.T6G(SCH_1):PAGE59_I3@PURE_QUANTA.GENOA_SP5(CHIPS)':
 'VSS_CL48': CDS_PINID='VSS_CL48';
NODE_NAME     U26 CL51
 '@T6G_MB_LIB.T6G(SCH_1):PAGE59_I3@PURE_QUANTA.GENOA_SP5(CHIPS)':
 'VSS_CL51': CDS_PINID='VSS_CL51';
NODE_NAME     U26 CL54
 '@T6G_MB_LIB.T6G(SCH_1):PAGE59_I3@PURE_QUANTA.GENOA_SP5(CHIPS)':
 'VSS_CL54': CDS_PINID='VSS_CL54';
NODE_NAME     U26 CL56
 '@T6G_MB_LIB.T6G(SCH_1):PAGE59_I3@PURE_QUANTA.GENOA_SP5(CHIPS)':
 'VSS_CL56': CDS_PINID='VSS_CL56';
NODE_NAME     U26 CL58
 '@T6G_MB_LIB.T6G(SCH_1):PAGE59_I3@PURE_QUANTA.GENOA_SP5(CHIPS)':
 'VSS_CL58': CDS_PINID='VSS_CL58';
NODE_NAME     U26 CL61
 '@T6G_MB_LIB.T6G(SCH_1):PAGE59_I3@PURE_QUANTA.GENOA_SP5(CHIPS)':
 'VSS_CL61': CDS_PINID='VSS_CL61';
NODE_NAME     U26 CL63
 '@T6G_MB_LIB.T6G(SCH_1):PAGE59_I3@PURE_QUANTA.GENOA_SP5(CHIPS)':
 'VSS_CL63': CDS_PINID='VSS_CL63';
NODE_NAME     U26 CL65
 '@T6G_MB_LIB.T6G(SCH_1):PAGE59_I3@PURE_QUANTA.GENOA_SP5(CHIPS)':
 'VSS_CL65': CDS_PINID='VSS_CL65';
NODE_NAME     U26 CL68
 '@T6G_MB_LIB.T6G(SCH_1):PAGE59_I3@PURE_QUANTA.GENOA_SP5(CHIPS)':
 'VSS_CL68': CDS_PINID='VSS_CL68';
NODE_NAME     U26 CL70
 '@T6G_MB_LIB.T6G(SCH_1):PAGE59_I3@PURE_QUANTA.GENOA_SP5(CHIPS)':
 'VSS_CL70': CDS_PINID='VSS_CL70';
NODE_NAME     U26 CL72
 '@T6G_MB_LIB.T6G(SCH_1):PAGE59_I3@PURE_QUANTA.GENOA_SP5(CHIPS)':
 'VSS_CL72': CDS_PINID='VSS_CL72';
NODE_NAME     U26 CL75
 '@T6G_MB_LIB.T6G(SCH_1):PAGE59_I3@PURE_QUANTA.GENOA_SP5(CHIPS)':
 'VSS_CL75': CDS_PINID='VSS_CL75';
NODE_NAME     U26 CM3
 '@T6G_MB_LIB.T6G(SCH_1):PAGE59_I3@PURE_QUANTA.GENOA_SP5(CHIPS)':
 'VSS_CM3': CDS_PINID='VSS_CM3';
NODE_NAME     U26 CM5
 '@T6G_MB_LIB.T6G(SCH_1):PAGE59_I3@PURE_QUANTA.GENOA_SP5(CHIPS)':
 'VSS_CM5': CDS_PINID='VSS_CM5';
NODE_NAME     U26 CM8
 '@T6G_MB_LIB.T6G(SCH_1):PAGE59_I3@PURE_QUANTA.GENOA_SP5(CHIPS)':
 'VSS_CM8': CDS_PINID='VSS_CM8';
NODE_NAME     U26 CM10
 '@T6G_MB_LIB.T6G(SCH_1):PAGE59_I3@PURE_QUANTA.GENOA_SP5(CHIPS)':
 'VSS_CM10': CDS_PINID='VSS_CM10';
NODE_NAME     U26 CM12
 '@T6G_MB_LIB.T6G(SCH_1):PAGE59_I3@PURE_QUANTA.GENOA_SP5(CHIPS)':
 'VSS_CM12': CDS_PINID='VSS_CM12';
NODE_NAME     U26 CM15
 '@T6G_MB_LIB.T6G(SCH_1):PAGE59_I3@PURE_QUANTA.GENOA_SP5(CHIPS)':
 'VSS_CM15': CDS_PINID='VSS_CM15';
NODE_NAME     U26 CM17
 '@T6G_MB_LIB.T6G(SCH_1):PAGE59_I3@PURE_QUANTA.GENOA_SP5(CHIPS)':
 'VSS_CM17': CDS_PINID='VSS_CM17';
NODE_NAME     U26 CM19
 '@T6G_MB_LIB.T6G(SCH_1):PAGE59_I3@PURE_QUANTA.GENOA_SP5(CHIPS)':
 'VSS_CM19': CDS_PINID='VSS_CM19';
NODE_NAME     U26 CM23
 '@T6G_MB_LIB.T6G(SCH_1):PAGE59_I3@PURE_QUANTA.GENOA_SP5(CHIPS)':
 'VSS_CM23': CDS_PINID='VSS_CM23';
NODE_NAME     U26 CM24
 '@T6G_MB_LIB.T6G(SCH_1):PAGE59_I3@PURE_QUANTA.GENOA_SP5(CHIPS)':
 'VSS_CM24': CDS_PINID='VSS_CM24';
NODE_NAME     U26 CM25
 '@T6G_MB_LIB.T6G(SCH_1):PAGE59_I3@PURE_QUANTA.GENOA_SP5(CHIPS)':
 'VSS_CM25': CDS_PINID='VSS_CM25';
NODE_NAME     U26 CM26
 '@T6G_MB_LIB.T6G(SCH_1):PAGE59_I3@PURE_QUANTA.GENOA_SP5(CHIPS)':
 'VSS_CM26': CDS_PINID='VSS_CM26';
NODE_NAME     U26 CM27
 '@T6G_MB_LIB.T6G(SCH_1):PAGE59_I3@PURE_QUANTA.GENOA_SP5(CHIPS)':
 'VSS_CM27': CDS_PINID='VSS_CM27';
NODE_NAME     U26 CM28
 '@T6G_MB_LIB.T6G(SCH_1):PAGE59_I3@PURE_QUANTA.GENOA_SP5(CHIPS)':
 'VSS_CM28': CDS_PINID='VSS_CM28';
NODE_NAME     U26 CM29
 '@T6G_MB_LIB.T6G(SCH_1):PAGE59_I3@PURE_QUANTA.GENOA_SP5(CHIPS)':
 'VSS_CM29': CDS_PINID='VSS_CM29';
NODE_NAME     U26 CM30
 '@T6G_MB_LIB.T6G(SCH_1):PAGE59_I3@PURE_QUANTA.GENOA_SP5(CHIPS)':
 'VSS_CM30': CDS_PINID='VSS_CM30';
NODE_NAME     U26 CM31
 '@T6G_MB_LIB.T6G(SCH_1):PAGE59_I3@PURE_QUANTA.GENOA_SP5(CHIPS)':
 'VSS_CM31': CDS_PINID='VSS_CM31';
NODE_NAME     U26 CM32
 '@T6G_MB_LIB.T6G(SCH_1):PAGE59_I3@PURE_QUANTA.GENOA_SP5(CHIPS)':
 'VSS_CM32': CDS_PINID='VSS_CM32';
NODE_NAME     U26 CM33
 '@T6G_MB_LIB.T6G(SCH_1):PAGE59_I3@PURE_QUANTA.GENOA_SP5(CHIPS)':
 'VSS_CM33': CDS_PINID='VSS_CM33';
NODE_NAME     U26 CM34
 '@T6G_MB_LIB.T6G(SCH_1):PAGE59_I3@PURE_QUANTA.GENOA_SP5(CHIPS)':
 'VSS_CM34': CDS_PINID='VSS_CM34';
NODE_NAME     U26 CM37
 '@T6G_MB_LIB.T6G(SCH_1):PAGE59_I3@PURE_QUANTA.GENOA_SP5(CHIPS)':
 'VSS_CM37': CDS_PINID='VSS_CM37';
NODE_NAME     U26 CM39
 '@T6G_MB_LIB.T6G(SCH_1):PAGE59_I3@PURE_QUANTA.GENOA_SP5(CHIPS)':
 'VSS_CM39': CDS_PINID='VSS_CM39';
NODE_NAME     U26 CM42
 '@T6G_MB_LIB.T6G(SCH_1):PAGE59_I3@PURE_QUANTA.GENOA_SP5(CHIPS)':
 'VSS_CM42': CDS_PINID='VSS_CM42';
NODE_NAME     U26 CM43
 '@T6G_MB_LIB.T6G(SCH_1):PAGE59_I3@PURE_QUANTA.GENOA_SP5(CHIPS)':
 'VSS_CM43': CDS_PINID='VSS_CM43';
NODE_NAME     U26 CM44
 '@T6G_MB_LIB.T6G(SCH_1):PAGE59_I3@PURE_QUANTA.GENOA_SP5(CHIPS)':
 'VSS_CM44': CDS_PINID='VSS_CM44';
NODE_NAME     U26 CM45
 '@T6G_MB_LIB.T6G(SCH_1):PAGE59_I3@PURE_QUANTA.GENOA_SP5(CHIPS)':
 'VSS_CM45': CDS_PINID='VSS_CM45';
NODE_NAME     U26 CM46
 '@T6G_MB_LIB.T6G(SCH_1):PAGE59_I3@PURE_QUANTA.GENOA_SP5(CHIPS)':
 'VSS_CM46': CDS_PINID='VSS_CM46';
NODE_NAME     U26 CM47
 '@T6G_MB_LIB.T6G(SCH_1):PAGE59_I3@PURE_QUANTA.GENOA_SP5(CHIPS)':
 'VSS_CM47': CDS_PINID='VSS_CM47';
NODE_NAME     U26 CM48
 '@T6G_MB_LIB.T6G(SCH_1):PAGE59_I3@PURE_QUANTA.GENOA_SP5(CHIPS)':
 'VSS_CM48': CDS_PINID='VSS_CM48';
NODE_NAME     U26 CM49
 '@T6G_MB_LIB.T6G(SCH_1):PAGE59_I3@PURE_QUANTA.GENOA_SP5(CHIPS)':
 'VSS_CM49': CDS_PINID='VSS_CM49';
NODE_NAME     U26 CM51
 '@T6G_MB_LIB.T6G(SCH_1):PAGE59_I3@PURE_QUANTA.GENOA_SP5(CHIPS)':
 'VSS_CM51': CDS_PINID='VSS_CM51';
NODE_NAME     U26 CM52
 '@T6G_MB_LIB.T6G(SCH_1):PAGE59_I3@PURE_QUANTA.GENOA_SP5(CHIPS)':
 'VSS_CM52': CDS_PINID='VSS_CM52';
NODE_NAME     U26 CM53
 '@T6G_MB_LIB.T6G(SCH_1):PAGE59_I3@PURE_QUANTA.GENOA_SP5(CHIPS)':
 'VSS_CM53': CDS_PINID='VSS_CM53';
NODE_NAME     U26 CM57
 '@T6G_MB_LIB.T6G(SCH_1):PAGE59_I3@PURE_QUANTA.GENOA_SP5(CHIPS)':
 'VSS_CM57': CDS_PINID='VSS_CM57';
NODE_NAME     U26 CM59
 '@T6G_MB_LIB.T6G(SCH_1):PAGE59_I3@PURE_QUANTA.GENOA_SP5(CHIPS)':
 'VSS_CM59': CDS_PINID='VSS_CM59';
NODE_NAME     U26 CM61
 '@T6G_MB_LIB.T6G(SCH_1):PAGE59_I3@PURE_QUANTA.GENOA_SP5(CHIPS)':
 'VSS_CM61': CDS_PINID='VSS_CM61';
NODE_NAME     U26 CM64
 '@T6G_MB_LIB.T6G(SCH_1):PAGE59_I3@PURE_QUANTA.GENOA_SP5(CHIPS)':
 'VSS_CM64': CDS_PINID='VSS_CM64';
NODE_NAME     U26 CM66
 '@T6G_MB_LIB.T6G(SCH_1):PAGE59_I3@PURE_QUANTA.GENOA_SP5(CHIPS)':
 'VSS_CM66': CDS_PINID='VSS_CM66';
NODE_NAME     U26 CM68
 '@T6G_MB_LIB.T6G(SCH_1):PAGE59_I3@PURE_QUANTA.GENOA_SP5(CHIPS)':
 'VSS_CM68': CDS_PINID='VSS_CM68';
NODE_NAME     U26 CM71
 '@T6G_MB_LIB.T6G(SCH_1):PAGE59_I3@PURE_QUANTA.GENOA_SP5(CHIPS)':
 'VSS_CM71': CDS_PINID='VSS_CM71';
NODE_NAME     U26 CM73
 '@T6G_MB_LIB.T6G(SCH_1):PAGE59_I3@PURE_QUANTA.GENOA_SP5(CHIPS)':
 'VSS_CM73': CDS_PINID='VSS_CM73';
NODE_NAME     U26 CN1
 '@T6G_MB_LIB.T6G(SCH_1):PAGE59_I3@PURE_QUANTA.GENOA_SP5(CHIPS)':
 'VSS_CN1': CDS_PINID='VSS_CN1';
NODE_NAME     U26 CN6
 '@T6G_MB_LIB.T6G(SCH_1):PAGE59_I3@PURE_QUANTA.GENOA_SP5(CHIPS)':
 'VSS_CN6': CDS_PINID='VSS_CN6';
NODE_NAME     U26 CN8
 '@T6G_MB_LIB.T6G(SCH_1):PAGE59_I3@PURE_QUANTA.GENOA_SP5(CHIPS)':
 'VSS_CN8': CDS_PINID='VSS_CN8';
NODE_NAME     U26 CN13
 '@T6G_MB_LIB.T6G(SCH_1):PAGE59_I3@PURE_QUANTA.GENOA_SP5(CHIPS)':
 'VSS_CN13': CDS_PINID='VSS_CN13';
NODE_NAME     U26 CN15
 '@T6G_MB_LIB.T6G(SCH_1):PAGE59_I3@PURE_QUANTA.GENOA_SP5(CHIPS)':
 'VSS_CN15': CDS_PINID='VSS_CN15';
NODE_NAME     U26 CN20
 '@T6G_MB_LIB.T6G(SCH_1):PAGE59_I3@PURE_QUANTA.GENOA_SP5(CHIPS)':
 'VSS_CN20': CDS_PINID='VSS_CN20';
NODE_NAME     U26 CN22
 '@T6G_MB_LIB.T6G(SCH_1):PAGE59_I3@PURE_QUANTA.GENOA_SP5(CHIPS)':
 'VSS_CN22': CDS_PINID='VSS_CN22';
NODE_NAME     U26 CN25
 '@T6G_MB_LIB.T6G(SCH_1):PAGE59_I3@PURE_QUANTA.GENOA_SP5(CHIPS)':
 'VSS_CN25': CDS_PINID='VSS_CN25';
NODE_NAME     U26 CN28
 '@T6G_MB_LIB.T6G(SCH_1):PAGE59_I3@PURE_QUANTA.GENOA_SP5(CHIPS)':
 'VSS_CN28': CDS_PINID='VSS_CN28';
NODE_NAME     U26 CN31
 '@T6G_MB_LIB.T6G(SCH_1):PAGE59_I3@PURE_QUANTA.GENOA_SP5(CHIPS)':
 'VSS_CN31': CDS_PINID='VSS_CN31';
NODE_NAME     U26 CN34
 '@T6G_MB_LIB.T6G(SCH_1):PAGE59_I3@PURE_QUANTA.GENOA_SP5(CHIPS)':
 'VSS_CN34': CDS_PINID='VSS_CN34';
NODE_NAME     U26 CN42
 '@T6G_MB_LIB.T6G(SCH_1):PAGE59_I3@PURE_QUANTA.GENOA_SP5(CHIPS)':
 'VSS_CN42': CDS_PINID='VSS_CN42';
NODE_NAME     U26 CN45
 '@T6G_MB_LIB.T6G(SCH_1):PAGE59_I3@PURE_QUANTA.GENOA_SP5(CHIPS)':
 'VSS_CN45': CDS_PINID='VSS_CN45';
NODE_NAME     U26 CN48
 '@T6G_MB_LIB.T6G(SCH_1):PAGE59_I3@PURE_QUANTA.GENOA_SP5(CHIPS)':
 'VSS_CN48': CDS_PINID='VSS_CN48';
NODE_NAME     U26 CN51
 '@T6G_MB_LIB.T6G(SCH_1):PAGE59_I3@PURE_QUANTA.GENOA_SP5(CHIPS)':
 'VSS_CN51': CDS_PINID='VSS_CN51';
NODE_NAME     U26 CN56
 '@T6G_MB_LIB.T6G(SCH_1):PAGE59_I3@PURE_QUANTA.GENOA_SP5(CHIPS)':
 'VSS_CN56': CDS_PINID='VSS_CN56';
NODE_NAME     U26 CN61
 '@T6G_MB_LIB.T6G(SCH_1):PAGE59_I3@PURE_QUANTA.GENOA_SP5(CHIPS)':
 'VSS_CN61': CDS_PINID='VSS_CN61';
NODE_NAME     U26 CN63
 '@T6G_MB_LIB.T6G(SCH_1):PAGE59_I3@PURE_QUANTA.GENOA_SP5(CHIPS)':
 'VSS_CN63': CDS_PINID='VSS_CN63';
NODE_NAME     U26 CN68
 '@T6G_MB_LIB.T6G(SCH_1):PAGE59_I3@PURE_QUANTA.GENOA_SP5(CHIPS)':
 'VSS_CN68': CDS_PINID='VSS_CN68';
NODE_NAME     U26 CN70
 '@T6G_MB_LIB.T6G(SCH_1):PAGE59_I3@PURE_QUANTA.GENOA_SP5(CHIPS)':
 'VSS_CN70': CDS_PINID='VSS_CN70';
NODE_NAME     U26 CN75
 '@T6G_MB_LIB.T6G(SCH_1):PAGE59_I3@PURE_QUANTA.GENOA_SP5(CHIPS)':
 'VSS_CN75': CDS_PINID='VSS_CN75';
NODE_NAME     U26 CP3
 '@T6G_MB_LIB.T6G(SCH_1):PAGE59_I3@PURE_QUANTA.GENOA_SP5(CHIPS)':
 'VSS_CP3': CDS_PINID='VSS_CP3';
NODE_NAME     U26 CP5
 '@T6G_MB_LIB.T6G(SCH_1):PAGE59_I3@PURE_QUANTA.GENOA_SP5(CHIPS)':
 'VSS_CP5': CDS_PINID='VSS_CP5';
NODE_NAME     U26 CP8
 '@T6G_MB_LIB.T6G(SCH_1):PAGE59_I3@PURE_QUANTA.GENOA_SP5(CHIPS)':
 'VSS_CP8': CDS_PINID='VSS_CP8';
NODE_NAME     U26 CP10
 '@T6G_MB_LIB.T6G(SCH_1):PAGE59_I3@PURE_QUANTA.GENOA_SP5(CHIPS)':
 'VSS_CP10': CDS_PINID='VSS_CP10';
NODE_NAME     U26 CP12
 '@T6G_MB_LIB.T6G(SCH_1):PAGE59_I3@PURE_QUANTA.GENOA_SP5(CHIPS)':
 'VSS_CP12': CDS_PINID='VSS_CP12';
NODE_NAME     U26 CP15
 '@T6G_MB_LIB.T6G(SCH_1):PAGE59_I3@PURE_QUANTA.GENOA_SP5(CHIPS)':
 'VSS_CP15': CDS_PINID='VSS_CP15';
NODE_NAME     U26 CP17
 '@T6G_MB_LIB.T6G(SCH_1):PAGE59_I3@PURE_QUANTA.GENOA_SP5(CHIPS)':
 'VSS_CP17': CDS_PINID='VSS_CP17';
NODE_NAME     U26 CP19
 '@T6G_MB_LIB.T6G(SCH_1):PAGE59_I3@PURE_QUANTA.GENOA_SP5(CHIPS)':
 'VSS_CP19': CDS_PINID='VSS_CP19';
NODE_NAME     U26 CP22
 '@T6G_MB_LIB.T6G(SCH_1):PAGE59_I4@PURE_QUANTA.GENOA_SP5(CHIPS)':
 'VSS_CP22': CDS_PINID='VSS_CP22';
NODE_NAME     U26 CP25
 '@T6G_MB_LIB.T6G(SCH_1):PAGE59_I4@PURE_QUANTA.GENOA_SP5(CHIPS)':
 'VSS_CP25': CDS_PINID='VSS_CP25';
NODE_NAME     U26 CP28
 '@T6G_MB_LIB.T6G(SCH_1):PAGE59_I4@PURE_QUANTA.GENOA_SP5(CHIPS)':
 'VSS_CP28': CDS_PINID='VSS_CP28';
NODE_NAME     U26 CP31
 '@T6G_MB_LIB.T6G(SCH_1):PAGE59_I4@PURE_QUANTA.GENOA_SP5(CHIPS)':
 'VSS_CP31': CDS_PINID='VSS_CP31';
NODE_NAME     U26 CP34
 '@T6G_MB_LIB.T6G(SCH_1):PAGE59_I4@PURE_QUANTA.GENOA_SP5(CHIPS)':
 'VSS_CP34': CDS_PINID='VSS_CP34';
NODE_NAME     U26 CP37
 '@T6G_MB_LIB.T6G(SCH_1):PAGE59_I4@PURE_QUANTA.GENOA_SP5(CHIPS)':
 'VSS_CP37': CDS_PINID='VSS_CP37';
NODE_NAME     U26 CP39
 '@T6G_MB_LIB.T6G(SCH_1):PAGE59_I4@PURE_QUANTA.GENOA_SP5(CHIPS)':
 'VSS_CP39': CDS_PINID='VSS_CP39';
NODE_NAME     U26 CP42
 '@T6G_MB_LIB.T6G(SCH_1):PAGE59_I4@PURE_QUANTA.GENOA_SP5(CHIPS)':
 'VSS_CP42': CDS_PINID='VSS_CP42';
NODE_NAME     U26 CP45
 '@T6G_MB_LIB.T6G(SCH_1):PAGE59_I4@PURE_QUANTA.GENOA_SP5(CHIPS)':
 'VSS_CP45': CDS_PINID='VSS_CP45';
NODE_NAME     U26 CP48
 '@T6G_MB_LIB.T6G(SCH_1):PAGE59_I4@PURE_QUANTA.GENOA_SP5(CHIPS)':
 'VSS_CP48': CDS_PINID='VSS_CP48';
NODE_NAME     U26 CP51
 '@T6G_MB_LIB.T6G(SCH_1):PAGE59_I4@PURE_QUANTA.GENOA_SP5(CHIPS)':
 'VSS_CP51': CDS_PINID='VSS_CP51';
NODE_NAME     U26 CP54
 '@T6G_MB_LIB.T6G(SCH_1):PAGE59_I4@PURE_QUANTA.GENOA_SP5(CHIPS)':
 'VSS_CP54': CDS_PINID='VSS_CP54';
NODE_NAME     U26 CP57
 '@T6G_MB_LIB.T6G(SCH_1):PAGE59_I4@PURE_QUANTA.GENOA_SP5(CHIPS)':
 'VSS_CP57': CDS_PINID='VSS_CP57';
NODE_NAME     U26 CP59
 '@T6G_MB_LIB.T6G(SCH_1):PAGE59_I4@PURE_QUANTA.GENOA_SP5(CHIPS)':
 'VSS_CP59': CDS_PINID='VSS_CP59';
NODE_NAME     U26 CP61
 '@T6G_MB_LIB.T6G(SCH_1):PAGE59_I4@PURE_QUANTA.GENOA_SP5(CHIPS)':
 'VSS_CP61': CDS_PINID='VSS_CP61';
NODE_NAME     U26 CP64
 '@T6G_MB_LIB.T6G(SCH_1):PAGE59_I4@PURE_QUANTA.GENOA_SP5(CHIPS)':
 'VSS_CP64': CDS_PINID='VSS_CP64';
NODE_NAME     U26 CP66
 '@T6G_MB_LIB.T6G(SCH_1):PAGE59_I4@PURE_QUANTA.GENOA_SP5(CHIPS)':
 'VSS_CP66': CDS_PINID='VSS_CP66';
NODE_NAME     U26 CP68
 '@T6G_MB_LIB.T6G(SCH_1):PAGE59_I4@PURE_QUANTA.GENOA_SP5(CHIPS)':
 'VSS_CP68': CDS_PINID='VSS_CP68';
NODE_NAME     U26 CP71
 '@T6G_MB_LIB.T6G(SCH_1):PAGE59_I4@PURE_QUANTA.GENOA_SP5(CHIPS)':
 'VSS_CP71': CDS_PINID='VSS_CP71';
NODE_NAME     U26 CP73
 '@T6G_MB_LIB.T6G(SCH_1):PAGE59_I4@PURE_QUANTA.GENOA_SP5(CHIPS)':
 'VSS_CP73': CDS_PINID='VSS_CP73';
NODE_NAME     U26 CR1
 '@T6G_MB_LIB.T6G(SCH_1):PAGE59_I4@PURE_QUANTA.GENOA_SP5(CHIPS)':
 'VSS_CR1': CDS_PINID='VSS_CR1';
NODE_NAME     U26 CR4
 '@T6G_MB_LIB.T6G(SCH_1):PAGE59_I4@PURE_QUANTA.GENOA_SP5(CHIPS)':
 'VSS_CR4': CDS_PINID='VSS_CR4';
NODE_NAME     U26 CR6
 '@T6G_MB_LIB.T6G(SCH_1):PAGE59_I4@PURE_QUANTA.GENOA_SP5(CHIPS)':
 'VSS_CR6': CDS_PINID='VSS_CR6';
NODE_NAME     U26 CR8
 '@T6G_MB_LIB.T6G(SCH_1):PAGE59_I4@PURE_QUANTA.GENOA_SP5(CHIPS)':
 'VSS_CR8': CDS_PINID='VSS_CR8';
NODE_NAME     U26 CR11
 '@T6G_MB_LIB.T6G(SCH_1):PAGE59_I4@PURE_QUANTA.GENOA_SP5(CHIPS)':
 'VSS_CR11': CDS_PINID='VSS_CR11';
NODE_NAME     U26 CR13
 '@T6G_MB_LIB.T6G(SCH_1):PAGE59_I4@PURE_QUANTA.GENOA_SP5(CHIPS)':
 'VSS_CR13': CDS_PINID='VSS_CR13';
NODE_NAME     U26 CR15
 '@T6G_MB_LIB.T6G(SCH_1):PAGE59_I4@PURE_QUANTA.GENOA_SP5(CHIPS)':
 'VSS_CR15': CDS_PINID='VSS_CR15';
NODE_NAME     U26 CR18
 '@T6G_MB_LIB.T6G(SCH_1):PAGE59_I4@PURE_QUANTA.GENOA_SP5(CHIPS)':
 'VSS_CR18': CDS_PINID='VSS_CR18';
NODE_NAME     U26 CR20
 '@T6G_MB_LIB.T6G(SCH_1):PAGE59_I4@PURE_QUANTA.GENOA_SP5(CHIPS)':
 'VSS_CR20': CDS_PINID='VSS_CR20';
NODE_NAME     U26 CR22
 '@T6G_MB_LIB.T6G(SCH_1):PAGE59_I4@PURE_QUANTA.GENOA_SP5(CHIPS)':
 'VSS_CR22': CDS_PINID='VSS_CR22';
NODE_NAME     U26 CR25
 '@T6G_MB_LIB.T6G(SCH_1):PAGE59_I4@PURE_QUANTA.GENOA_SP5(CHIPS)':
 'VSS_CR25': CDS_PINID='VSS_CR25';
NODE_NAME     U26 CR28
 '@T6G_MB_LIB.T6G(SCH_1):PAGE59_I4@PURE_QUANTA.GENOA_SP5(CHIPS)':
 'VSS_CR28': CDS_PINID='VSS_CR28';
NODE_NAME     U26 CR31
 '@T6G_MB_LIB.T6G(SCH_1):PAGE59_I4@PURE_QUANTA.GENOA_SP5(CHIPS)':
 'VSS_CR31': CDS_PINID='VSS_CR31';
NODE_NAME     U26 CR34
 '@T6G_MB_LIB.T6G(SCH_1):PAGE59_I4@PURE_QUANTA.GENOA_SP5(CHIPS)':
 'VSS_CR34': CDS_PINID='VSS_CR34';
NODE_NAME     U26 CR35
 '@T6G_MB_LIB.T6G(SCH_1):PAGE59_I4@PURE_QUANTA.GENOA_SP5(CHIPS)':
 'VSS_CR35': CDS_PINID='VSS_CR35';
NODE_NAME     U26 CR36
 '@T6G_MB_LIB.T6G(SCH_1):PAGE59_I4@PURE_QUANTA.GENOA_SP5(CHIPS)':
 'VSS_CR36': CDS_PINID='VSS_CR36';
NODE_NAME     U26 CR40
 '@T6G_MB_LIB.T6G(SCH_1):PAGE59_I4@PURE_QUANTA.GENOA_SP5(CHIPS)':
 'VSS_CR40': CDS_PINID='VSS_CR40';
NODE_NAME     U26 CR41
 '@T6G_MB_LIB.T6G(SCH_1):PAGE59_I4@PURE_QUANTA.GENOA_SP5(CHIPS)':
 'VSS_CR41': CDS_PINID='VSS_CR41';
NODE_NAME     U26 CR42
 '@T6G_MB_LIB.T6G(SCH_1):PAGE59_I4@PURE_QUANTA.GENOA_SP5(CHIPS)':
 'VSS_CR42': CDS_PINID='VSS_CR42';
NODE_NAME     U26 CR45
 '@T6G_MB_LIB.T6G(SCH_1):PAGE59_I4@PURE_QUANTA.GENOA_SP5(CHIPS)':
 'VSS_CR45': CDS_PINID='VSS_CR45';
NODE_NAME     U26 CR48
 '@T6G_MB_LIB.T6G(SCH_1):PAGE59_I4@PURE_QUANTA.GENOA_SP5(CHIPS)':
 'VSS_CR48': CDS_PINID='VSS_CR48';
NODE_NAME     U26 CR51
 '@T6G_MB_LIB.T6G(SCH_1):PAGE59_I4@PURE_QUANTA.GENOA_SP5(CHIPS)':
 'VSS_CR51': CDS_PINID='VSS_CR51';
NODE_NAME     U26 CR54
 '@T6G_MB_LIB.T6G(SCH_1):PAGE59_I4@PURE_QUANTA.GENOA_SP5(CHIPS)':
 'VSS_CR54': CDS_PINID='VSS_CR54';
NODE_NAME     U26 CR56
 '@T6G_MB_LIB.T6G(SCH_1):PAGE59_I4@PURE_QUANTA.GENOA_SP5(CHIPS)':
 'VSS_CR56': CDS_PINID='VSS_CR56';
NODE_NAME     U26 CR58
 '@T6G_MB_LIB.T6G(SCH_1):PAGE59_I4@PURE_QUANTA.GENOA_SP5(CHIPS)':
 'VSS_CR58': CDS_PINID='VSS_CR58';
NODE_NAME     U26 CR61
 '@T6G_MB_LIB.T6G(SCH_1):PAGE59_I4@PURE_QUANTA.GENOA_SP5(CHIPS)':
 'VSS_CR61': CDS_PINID='VSS_CR61';
NODE_NAME     U26 CR63
 '@T6G_MB_LIB.T6G(SCH_1):PAGE59_I4@PURE_QUANTA.GENOA_SP5(CHIPS)':
 'VSS_CR63': CDS_PINID='VSS_CR63';
NODE_NAME     U26 CR65
 '@T6G_MB_LIB.T6G(SCH_1):PAGE59_I4@PURE_QUANTA.GENOA_SP5(CHIPS)':
 'VSS_CR65': CDS_PINID='VSS_CR65';
NODE_NAME     U26 CR68
 '@T6G_MB_LIB.T6G(SCH_1):PAGE59_I4@PURE_QUANTA.GENOA_SP5(CHIPS)':
 'VSS_CR68': CDS_PINID='VSS_CR68';
NODE_NAME     U26 CR70
 '@T6G_MB_LIB.T6G(SCH_1):PAGE59_I4@PURE_QUANTA.GENOA_SP5(CHIPS)':
 'VSS_CR70': CDS_PINID='VSS_CR70';
NODE_NAME     U26 CR72
 '@T6G_MB_LIB.T6G(SCH_1):PAGE59_I4@PURE_QUANTA.GENOA_SP5(CHIPS)':
 'VSS_CR72': CDS_PINID='VSS_CR72';
NODE_NAME     U26 CR75
 '@T6G_MB_LIB.T6G(SCH_1):PAGE59_I4@PURE_QUANTA.GENOA_SP5(CHIPS)':
 'VSS_CR75': CDS_PINID='VSS_CR75';
NODE_NAME     U26 CT3
 '@T6G_MB_LIB.T6G(SCH_1):PAGE59_I4@PURE_QUANTA.GENOA_SP5(CHIPS)':
 'VSS_CT3': CDS_PINID='VSS_CT3';
NODE_NAME     U26 CT8
 '@T6G_MB_LIB.T6G(SCH_1):PAGE59_I4@PURE_QUANTA.GENOA_SP5(CHIPS)':
 'VSS_CT8': CDS_PINID='VSS_CT8';
NODE_NAME     U26 CT10
 '@T6G_MB_LIB.T6G(SCH_1):PAGE59_I4@PURE_QUANTA.GENOA_SP5(CHIPS)':
 'VSS_CT10': CDS_PINID='VSS_CT10';
NODE_NAME     U26 CT15
 '@T6G_MB_LIB.T6G(SCH_1):PAGE59_I4@PURE_QUANTA.GENOA_SP5(CHIPS)':
 'VSS_CT15': CDS_PINID='VSS_CT15';
NODE_NAME     U26 CT17
 '@T6G_MB_LIB.T6G(SCH_1):PAGE59_I4@PURE_QUANTA.GENOA_SP5(CHIPS)':
 'VSS_CT17': CDS_PINID='VSS_CT17';
NODE_NAME     U26 CT23
 '@T6G_MB_LIB.T6G(SCH_1):PAGE59_I4@PURE_QUANTA.GENOA_SP5(CHIPS)':
 'VSS_CT23': CDS_PINID='VSS_CT23';
NODE_NAME     U26 CT24
 '@T6G_MB_LIB.T6G(SCH_1):PAGE59_I4@PURE_QUANTA.GENOA_SP5(CHIPS)':
 'VSS_CT24': CDS_PINID='VSS_CT24';
NODE_NAME     U26 CT25
 '@T6G_MB_LIB.T6G(SCH_1):PAGE59_I4@PURE_QUANTA.GENOA_SP5(CHIPS)':
 'VSS_CT25': CDS_PINID='VSS_CT25';
NODE_NAME     U26 CT26
 '@T6G_MB_LIB.T6G(SCH_1):PAGE59_I4@PURE_QUANTA.GENOA_SP5(CHIPS)':
 'VSS_CT26': CDS_PINID='VSS_CT26';
NODE_NAME     U26 CT27
 '@T6G_MB_LIB.T6G(SCH_1):PAGE59_I4@PURE_QUANTA.GENOA_SP5(CHIPS)':
 'VSS_CT27': CDS_PINID='VSS_CT27';
NODE_NAME     U26 CT28
 '@T6G_MB_LIB.T6G(SCH_1):PAGE59_I4@PURE_QUANTA.GENOA_SP5(CHIPS)':
 'VSS_CT28': CDS_PINID='VSS_CT28';
NODE_NAME     U26 CT29
 '@T6G_MB_LIB.T6G(SCH_1):PAGE59_I4@PURE_QUANTA.GENOA_SP5(CHIPS)':
 'VSS_CT29': CDS_PINID='VSS_CT29';
NODE_NAME     U26 CT30
 '@T6G_MB_LIB.T6G(SCH_1):PAGE59_I4@PURE_QUANTA.GENOA_SP5(CHIPS)':
 'VSS_CT30': CDS_PINID='VSS_CT30';
NODE_NAME     U26 CT31
 '@T6G_MB_LIB.T6G(SCH_1):PAGE59_I4@PURE_QUANTA.GENOA_SP5(CHIPS)':
 'VSS_CT31': CDS_PINID='VSS_CT31';
NODE_NAME     U26 CT32
 '@T6G_MB_LIB.T6G(SCH_1):PAGE59_I4@PURE_QUANTA.GENOA_SP5(CHIPS)':
 'VSS_CT32': CDS_PINID='VSS_CT32';
NODE_NAME     U26 CT33
 '@T6G_MB_LIB.T6G(SCH_1):PAGE59_I4@PURE_QUANTA.GENOA_SP5(CHIPS)':
 'VSS_CT33': CDS_PINID='VSS_CT33';
NODE_NAME     U26 CT34
 '@T6G_MB_LIB.T6G(SCH_1):PAGE59_I4@PURE_QUANTA.GENOA_SP5(CHIPS)':
 'VSS_CT34': CDS_PINID='VSS_CT34';
NODE_NAME     U26 CT37
 '@T6G_MB_LIB.T6G(SCH_1):PAGE59_I4@PURE_QUANTA.GENOA_SP5(CHIPS)':
 'VSS_CT37': CDS_PINID='VSS_CT37';
NODE_NAME     U26 CT39
 '@T6G_MB_LIB.T6G(SCH_1):PAGE59_I4@PURE_QUANTA.GENOA_SP5(CHIPS)':
 'VSS_CT39': CDS_PINID='VSS_CT39';
NODE_NAME     U26 CT42
 '@T6G_MB_LIB.T6G(SCH_1):PAGE59_I4@PURE_QUANTA.GENOA_SP5(CHIPS)':
 'VSS_CT42': CDS_PINID='VSS_CT42';
NODE_NAME     U26 CT43
 '@T6G_MB_LIB.T6G(SCH_1):PAGE59_I4@PURE_QUANTA.GENOA_SP5(CHIPS)':
 'VSS_CT43': CDS_PINID='VSS_CT43';
NODE_NAME     U26 CT44
 '@T6G_MB_LIB.T6G(SCH_1):PAGE59_I4@PURE_QUANTA.GENOA_SP5(CHIPS)':
 'VSS_CT44': CDS_PINID='VSS_CT44';
NODE_NAME     U26 CT45
 '@T6G_MB_LIB.T6G(SCH_1):PAGE59_I4@PURE_QUANTA.GENOA_SP5(CHIPS)':
 'VSS_CT45': CDS_PINID='VSS_CT45';
NODE_NAME     U26 CT46
 '@T6G_MB_LIB.T6G(SCH_1):PAGE59_I4@PURE_QUANTA.GENOA_SP5(CHIPS)':
 'VSS_CT46': CDS_PINID='VSS_CT46';
NODE_NAME     U26 CT47
 '@T6G_MB_LIB.T6G(SCH_1):PAGE59_I4@PURE_QUANTA.GENOA_SP5(CHIPS)':
 'VSS_CT47': CDS_PINID='VSS_CT47';
NODE_NAME     U26 CT48
 '@T6G_MB_LIB.T6G(SCH_1):PAGE59_I4@PURE_QUANTA.GENOA_SP5(CHIPS)':
 'VSS_CT48': CDS_PINID='VSS_CT48';
NODE_NAME     U26 CT49
 '@T6G_MB_LIB.T6G(SCH_1):PAGE59_I4@PURE_QUANTA.GENOA_SP5(CHIPS)':
 'VSS_CT49': CDS_PINID='VSS_CT49';
NODE_NAME     U26 CT50
 '@T6G_MB_LIB.T6G(SCH_1):PAGE59_I4@PURE_QUANTA.GENOA_SP5(CHIPS)':
 'VSS_CT50': CDS_PINID='VSS_CT50';
NODE_NAME     U26 CT51
 '@T6G_MB_LIB.T6G(SCH_1):PAGE59_I4@PURE_QUANTA.GENOA_SP5(CHIPS)':
 'VSS_CT51': CDS_PINID='VSS_CT51';
NODE_NAME     U26 CT53
 '@T6G_MB_LIB.T6G(SCH_1):PAGE59_I4@PURE_QUANTA.GENOA_SP5(CHIPS)':
 'VSS_CT53': CDS_PINID='VSS_CT53';
NODE_NAME     U26 CT59
 '@T6G_MB_LIB.T6G(SCH_1):PAGE59_I4@PURE_QUANTA.GENOA_SP5(CHIPS)':
 'VSS_CT59': CDS_PINID='VSS_CT59';
NODE_NAME     U26 CT61
 '@T6G_MB_LIB.T6G(SCH_1):PAGE59_I4@PURE_QUANTA.GENOA_SP5(CHIPS)':
 'VSS_CT61': CDS_PINID='VSS_CT61';
NODE_NAME     U26 CT66
 '@T6G_MB_LIB.T6G(SCH_1):PAGE59_I4@PURE_QUANTA.GENOA_SP5(CHIPS)':
 'VSS_CT66': CDS_PINID='VSS_CT66';
NODE_NAME     U26 CT68
 '@T6G_MB_LIB.T6G(SCH_1):PAGE59_I4@PURE_QUANTA.GENOA_SP5(CHIPS)':
 'VSS_CT68': CDS_PINID='VSS_CT68';
NODE_NAME     U26 CT73
 '@T6G_MB_LIB.T6G(SCH_1):PAGE59_I4@PURE_QUANTA.GENOA_SP5(CHIPS)':
 'VSS_CT73': CDS_PINID='VSS_CT73';
NODE_NAME     U26 CU1
 '@T6G_MB_LIB.T6G(SCH_1):PAGE59_I4@PURE_QUANTA.GENOA_SP5(CHIPS)':
 'VSS_CU1': CDS_PINID='VSS_CU1';
NODE_NAME     U26 CU4
 '@T6G_MB_LIB.T6G(SCH_1):PAGE59_I4@PURE_QUANTA.GENOA_SP5(CHIPS)':
 'VSS_CU4': CDS_PINID='VSS_CU4';
NODE_NAME     U26 CU6
 '@T6G_MB_LIB.T6G(SCH_1):PAGE59_I4@PURE_QUANTA.GENOA_SP5(CHIPS)':
 'VSS_CU6': CDS_PINID='VSS_CU6';
NODE_NAME     U26 CU8
 '@T6G_MB_LIB.T6G(SCH_1):PAGE59_I4@PURE_QUANTA.GENOA_SP5(CHIPS)':
 'VSS_CU8': CDS_PINID='VSS_CU8';
NODE_NAME     U26 CU11
 '@T6G_MB_LIB.T6G(SCH_1):PAGE59_I4@PURE_QUANTA.GENOA_SP5(CHIPS)':
 'VSS_CU11': CDS_PINID='VSS_CU11';
NODE_NAME     U26 CU13
 '@T6G_MB_LIB.T6G(SCH_1):PAGE59_I4@PURE_QUANTA.GENOA_SP5(CHIPS)':
 'VSS_CU13': CDS_PINID='VSS_CU13';
NODE_NAME     U26 CU15
 '@T6G_MB_LIB.T6G(SCH_1):PAGE59_I4@PURE_QUANTA.GENOA_SP5(CHIPS)':
 'VSS_CU15': CDS_PINID='VSS_CU15';
NODE_NAME     U26 CU18
 '@T6G_MB_LIB.T6G(SCH_1):PAGE59_I4@PURE_QUANTA.GENOA_SP5(CHIPS)':
 'VSS_CU18': CDS_PINID='VSS_CU18';
NODE_NAME     U26 CU20
 '@T6G_MB_LIB.T6G(SCH_1):PAGE59_I4@PURE_QUANTA.GENOA_SP5(CHIPS)':
 'VSS_CU20': CDS_PINID='VSS_CU20';
NODE_NAME     U26 CU22
 '@T6G_MB_LIB.T6G(SCH_1):PAGE59_I4@PURE_QUANTA.GENOA_SP5(CHIPS)':
 'VSS_CU22': CDS_PINID='VSS_CU22';
NODE_NAME     U26 CU25
 '@T6G_MB_LIB.T6G(SCH_1):PAGE59_I4@PURE_QUANTA.GENOA_SP5(CHIPS)':
 'VSS_CU25': CDS_PINID='VSS_CU25';
NODE_NAME     U26 CU28
 '@T6G_MB_LIB.T6G(SCH_1):PAGE59_I4@PURE_QUANTA.GENOA_SP5(CHIPS)':
 'VSS_CU28': CDS_PINID='VSS_CU28';
NODE_NAME     U26 CU31
 '@T6G_MB_LIB.T6G(SCH_1):PAGE59_I4@PURE_QUANTA.GENOA_SP5(CHIPS)':
 'VSS_CU31': CDS_PINID='VSS_CU31';
NODE_NAME     U26 CU34
 '@T6G_MB_LIB.T6G(SCH_1):PAGE59_I4@PURE_QUANTA.GENOA_SP5(CHIPS)':
 'VSS_CU34': CDS_PINID='VSS_CU34';
NODE_NAME     U26 CU42
 '@T6G_MB_LIB.T6G(SCH_1):PAGE59_I4@PURE_QUANTA.GENOA_SP5(CHIPS)':
 'VSS_CU42': CDS_PINID='VSS_CU42';
NODE_NAME     U26 CU45
 '@T6G_MB_LIB.T6G(SCH_1):PAGE59_I4@PURE_QUANTA.GENOA_SP5(CHIPS)':
 'VSS_CU45': CDS_PINID='VSS_CU45';
NODE_NAME     U26 CU48
 '@T6G_MB_LIB.T6G(SCH_1):PAGE59_I4@PURE_QUANTA.GENOA_SP5(CHIPS)':
 'VSS_CU48': CDS_PINID='VSS_CU48';
NODE_NAME     U26 CU51
 '@T6G_MB_LIB.T6G(SCH_1):PAGE59_I4@PURE_QUANTA.GENOA_SP5(CHIPS)':
 'VSS_CU51': CDS_PINID='VSS_CU51';
NODE_NAME     U26 CU54
 '@T6G_MB_LIB.T6G(SCH_1):PAGE59_I4@PURE_QUANTA.GENOA_SP5(CHIPS)':
 'VSS_CU54': CDS_PINID='VSS_CU54';
NODE_NAME     U26 CU56
 '@T6G_MB_LIB.T6G(SCH_1):PAGE59_I4@PURE_QUANTA.GENOA_SP5(CHIPS)':
 'VSS_CU56': CDS_PINID='VSS_CU56';
NODE_NAME     U26 CU61
 '@T6G_MB_LIB.T6G(SCH_1):PAGE59_I4@PURE_QUANTA.GENOA_SP5(CHIPS)':
 'VSS_CU61': CDS_PINID='VSS_CU61';
NODE_NAME     U26 CU63
 '@T6G_MB_LIB.T6G(SCH_1):PAGE59_I4@PURE_QUANTA.GENOA_SP5(CHIPS)':
 'VSS_CU63': CDS_PINID='VSS_CU63';
NODE_NAME     U26 CU65
 '@T6G_MB_LIB.T6G(SCH_1):PAGE59_I4@PURE_QUANTA.GENOA_SP5(CHIPS)':
 'VSS_CU65': CDS_PINID='VSS_CU65';
NODE_NAME     U26 CU68
 '@T6G_MB_LIB.T6G(SCH_1):PAGE59_I4@PURE_QUANTA.GENOA_SP5(CHIPS)':
 'VSS_CU68': CDS_PINID='VSS_CU68';
NODE_NAME     U26 CU70
 '@T6G_MB_LIB.T6G(SCH_1):PAGE59_I4@PURE_QUANTA.GENOA_SP5(CHIPS)':
 'VSS_CU70': CDS_PINID='VSS_CU70';
NODE_NAME     U26 CU72
 '@T6G_MB_LIB.T6G(SCH_1):PAGE59_I4@PURE_QUANTA.GENOA_SP5(CHIPS)':
 'VSS_CU72': CDS_PINID='VSS_CU72';
NODE_NAME     U26 CU75
 '@T6G_MB_LIB.T6G(SCH_1):PAGE59_I4@PURE_QUANTA.GENOA_SP5(CHIPS)':
 'VSS_CU75': CDS_PINID='VSS_CU75';
NODE_NAME     U26 CV3
 '@T6G_MB_LIB.T6G(SCH_1):PAGE59_I4@PURE_QUANTA.GENOA_SP5(CHIPS)':
 'VSS_CV3': CDS_PINID='VSS_CV3';
NODE_NAME     U26 CV5
 '@T6G_MB_LIB.T6G(SCH_1):PAGE59_I4@PURE_QUANTA.GENOA_SP5(CHIPS)':
 'VSS_CV5': CDS_PINID='VSS_CV5';
NODE_NAME     U26 CV8
 '@T6G_MB_LIB.T6G(SCH_1):PAGE59_I4@PURE_QUANTA.GENOA_SP5(CHIPS)':
 'VSS_CV8': CDS_PINID='VSS_CV8';
NODE_NAME     U26 CV10
 '@T6G_MB_LIB.T6G(SCH_1):PAGE59_I4@PURE_QUANTA.GENOA_SP5(CHIPS)':
 'VSS_CV10': CDS_PINID='VSS_CV10';
NODE_NAME     U26 CV12
 '@T6G_MB_LIB.T6G(SCH_1):PAGE59_I4@PURE_QUANTA.GENOA_SP5(CHIPS)':
 'VSS_CV12': CDS_PINID='VSS_CV12';
NODE_NAME     U26 CV15
 '@T6G_MB_LIB.T6G(SCH_1):PAGE59_I4@PURE_QUANTA.GENOA_SP5(CHIPS)':
 'VSS_CV15': CDS_PINID='VSS_CV15';
NODE_NAME     U26 CV17
 '@T6G_MB_LIB.T6G(SCH_1):PAGE59_I4@PURE_QUANTA.GENOA_SP5(CHIPS)':
 'VSS_CV17': CDS_PINID='VSS_CV17';
NODE_NAME     U26 CV19
 '@T6G_MB_LIB.T6G(SCH_1):PAGE59_I4@PURE_QUANTA.GENOA_SP5(CHIPS)':
 'VSS_CV19': CDS_PINID='VSS_CV19';
NODE_NAME     U26 CV22
 '@T6G_MB_LIB.T6G(SCH_1):PAGE59_I4@PURE_QUANTA.GENOA_SP5(CHIPS)':
 'VSS_CV22': CDS_PINID='VSS_CV22';
NODE_NAME     U26 CV25
 '@T6G_MB_LIB.T6G(SCH_1):PAGE59_I4@PURE_QUANTA.GENOA_SP5(CHIPS)':
 'VSS_CV25': CDS_PINID='VSS_CV25';
NODE_NAME     U26 CV28
 '@T6G_MB_LIB.T6G(SCH_1):PAGE59_I4@PURE_QUANTA.GENOA_SP5(CHIPS)':
 'VSS_CV28': CDS_PINID='VSS_CV28';
NODE_NAME     U26 CV31
 '@T6G_MB_LIB.T6G(SCH_1):PAGE59_I4@PURE_QUANTA.GENOA_SP5(CHIPS)':
 'VSS_CV31': CDS_PINID='VSS_CV31';
NODE_NAME     U26 CV34
 '@T6G_MB_LIB.T6G(SCH_1):PAGE59_I4@PURE_QUANTA.GENOA_SP5(CHIPS)':
 'VSS_CV34': CDS_PINID='VSS_CV34';
NODE_NAME     U26 CV37
 '@T6G_MB_LIB.T6G(SCH_1):PAGE59_I4@PURE_QUANTA.GENOA_SP5(CHIPS)':
 'VSS_CV37': CDS_PINID='VSS_CV37';
NODE_NAME     U26 CV39
 '@T6G_MB_LIB.T6G(SCH_1):PAGE59_I4@PURE_QUANTA.GENOA_SP5(CHIPS)':
 'VSS_CV39': CDS_PINID='VSS_CV39';
NODE_NAME     U26 CV42
 '@T6G_MB_LIB.T6G(SCH_1):PAGE59_I4@PURE_QUANTA.GENOA_SP5(CHIPS)':
 'VSS_CV42': CDS_PINID='VSS_CV42';
NODE_NAME     U26 CV45
 '@T6G_MB_LIB.T6G(SCH_1):PAGE59_I4@PURE_QUANTA.GENOA_SP5(CHIPS)':
 'VSS_CV45': CDS_PINID='VSS_CV45';
NODE_NAME     U26 CV48
 '@T6G_MB_LIB.T6G(SCH_1):PAGE59_I4@PURE_QUANTA.GENOA_SP5(CHIPS)':
 'VSS_CV48': CDS_PINID='VSS_CV48';
NODE_NAME     U26 CV51
 '@T6G_MB_LIB.T6G(SCH_1):PAGE59_I4@PURE_QUANTA.GENOA_SP5(CHIPS)':
 'VSS_CV51': CDS_PINID='VSS_CV51';
NODE_NAME     U26 CV54
 '@T6G_MB_LIB.T6G(SCH_1):PAGE59_I4@PURE_QUANTA.GENOA_SP5(CHIPS)':
 'VSS_CV54': CDS_PINID='VSS_CV54';
NODE_NAME     U26 CV57
 '@T6G_MB_LIB.T6G(SCH_1):PAGE59_I4@PURE_QUANTA.GENOA_SP5(CHIPS)':
 'VSS_CV57': CDS_PINID='VSS_CV57';
NODE_NAME     U26 CV59
 '@T6G_MB_LIB.T6G(SCH_1):PAGE59_I4@PURE_QUANTA.GENOA_SP5(CHIPS)':
 'VSS_CV59': CDS_PINID='VSS_CV59';
NODE_NAME     U26 CV61
 '@T6G_MB_LIB.T6G(SCH_1):PAGE59_I4@PURE_QUANTA.GENOA_SP5(CHIPS)':
 'VSS_CV61': CDS_PINID='VSS_CV61';
NODE_NAME     U26 CV64
 '@T6G_MB_LIB.T6G(SCH_1):PAGE59_I4@PURE_QUANTA.GENOA_SP5(CHIPS)':
 'VSS_CV64': CDS_PINID='VSS_CV64';
NODE_NAME     U26 CV66
 '@T6G_MB_LIB.T6G(SCH_1):PAGE59_I4@PURE_QUANTA.GENOA_SP5(CHIPS)':
 'VSS_CV66': CDS_PINID='VSS_CV66';
NODE_NAME     U26 CV68
 '@T6G_MB_LIB.T6G(SCH_1):PAGE59_I4@PURE_QUANTA.GENOA_SP5(CHIPS)':
 'VSS_CV68': CDS_PINID='VSS_CV68';
NODE_NAME     U26 CV71
 '@T6G_MB_LIB.T6G(SCH_1):PAGE59_I4@PURE_QUANTA.GENOA_SP5(CHIPS)':
 'VSS_CV71': CDS_PINID='VSS_CV71';
NODE_NAME     U26 CV73
 '@T6G_MB_LIB.T6G(SCH_1):PAGE59_I4@PURE_QUANTA.GENOA_SP5(CHIPS)':
 'VSS_CV73': CDS_PINID='VSS_CV73';
NODE_NAME     U26 CW1
 '@T6G_MB_LIB.T6G(SCH_1):PAGE59_I4@PURE_QUANTA.GENOA_SP5(CHIPS)':
 'VSS_CW1': CDS_PINID='VSS_CW1';
NODE_NAME     U26 CW6
 '@T6G_MB_LIB.T6G(SCH_1):PAGE59_I4@PURE_QUANTA.GENOA_SP5(CHIPS)':
 'VSS_CW6': CDS_PINID='VSS_CW6';
NODE_NAME     U26 CW8
 '@T6G_MB_LIB.T6G(SCH_1):PAGE59_I4@PURE_QUANTA.GENOA_SP5(CHIPS)':
 'VSS_CW8': CDS_PINID='VSS_CW8';
NODE_NAME     U26 CW13
 '@T6G_MB_LIB.T6G(SCH_1):PAGE59_I4@PURE_QUANTA.GENOA_SP5(CHIPS)':
 'VSS_CW13': CDS_PINID='VSS_CW13';
NODE_NAME     U26 CW15
 '@T6G_MB_LIB.T6G(SCH_1):PAGE59_I4@PURE_QUANTA.GENOA_SP5(CHIPS)':
 'VSS_CW15': CDS_PINID='VSS_CW15';
NODE_NAME     U26 CW20
 '@T6G_MB_LIB.T6G(SCH_1):PAGE59_I4@PURE_QUANTA.GENOA_SP5(CHIPS)':
 'VSS_CW20': CDS_PINID='VSS_CW20';
NODE_NAME     U26 CW22
 '@T6G_MB_LIB.T6G(SCH_1):PAGE59_I4@PURE_QUANTA.GENOA_SP5(CHIPS)':
 'VSS_CW22': CDS_PINID='VSS_CW22';
NODE_NAME     U26 CW25
 '@T6G_MB_LIB.T6G(SCH_1):PAGE59_I4@PURE_QUANTA.GENOA_SP5(CHIPS)':
 'VSS_CW25': CDS_PINID='VSS_CW25';
NODE_NAME     U26 CW28
 '@T6G_MB_LIB.T6G(SCH_1):PAGE59_I4@PURE_QUANTA.GENOA_SP5(CHIPS)':
 'VSS_CW28': CDS_PINID='VSS_CW28';
NODE_NAME     U26 CW31
 '@T6G_MB_LIB.T6G(SCH_1):PAGE59_I4@PURE_QUANTA.GENOA_SP5(CHIPS)':
 'VSS_CW31': CDS_PINID='VSS_CW31';
NODE_NAME     U26 CW34
 '@T6G_MB_LIB.T6G(SCH_1):PAGE59_I4@PURE_QUANTA.GENOA_SP5(CHIPS)':
 'VSS_CW34': CDS_PINID='VSS_CW34';
NODE_NAME     U26 CW35
 '@T6G_MB_LIB.T6G(SCH_1):PAGE59_I4@PURE_QUANTA.GENOA_SP5(CHIPS)':
 'VSS_CW35': CDS_PINID='VSS_CW35';
NODE_NAME     U26 CW36
 '@T6G_MB_LIB.T6G(SCH_1):PAGE59_I4@PURE_QUANTA.GENOA_SP5(CHIPS)':
 'VSS_CW36': CDS_PINID='VSS_CW36';
NODE_NAME     U26 CW40
 '@T6G_MB_LIB.T6G(SCH_1):PAGE59_I4@PURE_QUANTA.GENOA_SP5(CHIPS)':
 'VSS_CW40': CDS_PINID='VSS_CW40';
NODE_NAME     U26 CW41
 '@T6G_MB_LIB.T6G(SCH_1):PAGE59_I4@PURE_QUANTA.GENOA_SP5(CHIPS)':
 'VSS_CW41': CDS_PINID='VSS_CW41';
NODE_NAME     U26 CW42
 '@T6G_MB_LIB.T6G(SCH_1):PAGE59_I4@PURE_QUANTA.GENOA_SP5(CHIPS)':
 'VSS_CW42': CDS_PINID='VSS_CW42';
NODE_NAME     U26 CW45
 '@T6G_MB_LIB.T6G(SCH_1):PAGE59_I4@PURE_QUANTA.GENOA_SP5(CHIPS)':
 'VSS_CW45': CDS_PINID='VSS_CW45';
NODE_NAME     U26 CW48
 '@T6G_MB_LIB.T6G(SCH_1):PAGE59_I4@PURE_QUANTA.GENOA_SP5(CHIPS)':
 'VSS_CW48': CDS_PINID='VSS_CW48';
NODE_NAME     U26 CW51
 '@T6G_MB_LIB.T6G(SCH_1):PAGE59_I4@PURE_QUANTA.GENOA_SP5(CHIPS)':
 'VSS_CW51': CDS_PINID='VSS_CW51';
NODE_NAME     U26 CW54
 '@T6G_MB_LIB.T6G(SCH_1):PAGE59_I4@PURE_QUANTA.GENOA_SP5(CHIPS)':
 'VSS_CW54': CDS_PINID='VSS_CW54';
NODE_NAME     U26 CW56
 '@T6G_MB_LIB.T6G(SCH_1):PAGE59_I4@PURE_QUANTA.GENOA_SP5(CHIPS)':
 'VSS_CW56': CDS_PINID='VSS_CW56';
NODE_NAME     U26 CW61
 '@T6G_MB_LIB.T6G(SCH_1):PAGE59_I4@PURE_QUANTA.GENOA_SP5(CHIPS)':
 'VSS_CW61': CDS_PINID='VSS_CW61';
NODE_NAME     U26 CW63
 '@T6G_MB_LIB.T6G(SCH_1):PAGE59_I4@PURE_QUANTA.GENOA_SP5(CHIPS)':
 'VSS_CW63': CDS_PINID='VSS_CW63';
NODE_NAME     U26 CW68
 '@T6G_MB_LIB.T6G(SCH_1):PAGE59_I4@PURE_QUANTA.GENOA_SP5(CHIPS)':
 'VSS_CW68': CDS_PINID='VSS_CW68';
NODE_NAME     U26 CW70
 '@T6G_MB_LIB.T6G(SCH_1):PAGE59_I4@PURE_QUANTA.GENOA_SP5(CHIPS)':
 'VSS_CW70': CDS_PINID='VSS_CW70';
NODE_NAME     U26 CW75
 '@T6G_MB_LIB.T6G(SCH_1):PAGE59_I4@PURE_QUANTA.GENOA_SP5(CHIPS)':
 'VSS_CW75': CDS_PINID='VSS_CW75';
NODE_NAME     U26 CY3
 '@T6G_MB_LIB.T6G(SCH_1):PAGE59_I4@PURE_QUANTA.GENOA_SP5(CHIPS)':
 'VSS_CY3': CDS_PINID='VSS_CY3';
NODE_NAME     U26 CY5
 '@T6G_MB_LIB.T6G(SCH_1):PAGE59_I4@PURE_QUANTA.GENOA_SP5(CHIPS)':
 'VSS_CY5': CDS_PINID='VSS_CY5';
NODE_NAME     U26 CY8
 '@T6G_MB_LIB.T6G(SCH_1):PAGE59_I4@PURE_QUANTA.GENOA_SP5(CHIPS)':
 'VSS_CY8': CDS_PINID='VSS_CY8';
NODE_NAME     U26 CY10
 '@T6G_MB_LIB.T6G(SCH_1):PAGE59_I4@PURE_QUANTA.GENOA_SP5(CHIPS)':
 'VSS_CY10': CDS_PINID='VSS_CY10';
NODE_NAME     U26 CY12
 '@T6G_MB_LIB.T6G(SCH_1):PAGE59_I4@PURE_QUANTA.GENOA_SP5(CHIPS)':
 'VSS_CY12': CDS_PINID='VSS_CY12';
NODE_NAME     U26 CY15
 '@T6G_MB_LIB.T6G(SCH_1):PAGE59_I4@PURE_QUANTA.GENOA_SP5(CHIPS)':
 'VSS_CY15': CDS_PINID='VSS_CY15';
NODE_NAME     U26 CY17
 '@T6G_MB_LIB.T6G(SCH_1):PAGE59_I4@PURE_QUANTA.GENOA_SP5(CHIPS)':
 'VSS_CY17': CDS_PINID='VSS_CY17';
NODE_NAME     U26 CY19
 '@T6G_MB_LIB.T6G(SCH_1):PAGE59_I4@PURE_QUANTA.GENOA_SP5(CHIPS)':
 'VSS_CY19': CDS_PINID='VSS_CY19';
NODE_NAME     U26 CY23
 '@T6G_MB_LIB.T6G(SCH_1):PAGE59_I4@PURE_QUANTA.GENOA_SP5(CHIPS)':
 'VSS_CY23': CDS_PINID='VSS_CY23';
NODE_NAME     U26 CY24
 '@T6G_MB_LIB.T6G(SCH_1):PAGE59_I4@PURE_QUANTA.GENOA_SP5(CHIPS)':
 'VSS_CY24': CDS_PINID='VSS_CY24';
NODE_NAME     U26 CY25
 '@T6G_MB_LIB.T6G(SCH_1):PAGE59_I4@PURE_QUANTA.GENOA_SP5(CHIPS)':
 'VSS_CY25': CDS_PINID='VSS_CY25';
NODE_NAME     U26 CY26
 '@T6G_MB_LIB.T6G(SCH_1):PAGE59_I4@PURE_QUANTA.GENOA_SP5(CHIPS)':
 'VSS_CY26': CDS_PINID='VSS_CY26';
NODE_NAME     U26 CY27
 '@T6G_MB_LIB.T6G(SCH_1):PAGE59_I4@PURE_QUANTA.GENOA_SP5(CHIPS)':
 'VSS_CY27': CDS_PINID='VSS_CY27';
NODE_NAME     U26 CY28
 '@T6G_MB_LIB.T6G(SCH_1):PAGE59_I4@PURE_QUANTA.GENOA_SP5(CHIPS)':
 'VSS_CY28': CDS_PINID='VSS_CY28';
NODE_NAME     U26 CY29
 '@T6G_MB_LIB.T6G(SCH_1):PAGE59_I4@PURE_QUANTA.GENOA_SP5(CHIPS)':
 'VSS_CY29': CDS_PINID='VSS_CY29';
NODE_NAME     U26 CY30
 '@T6G_MB_LIB.T6G(SCH_1):PAGE59_I4@PURE_QUANTA.GENOA_SP5(CHIPS)':
 'VSS_CY30': CDS_PINID='VSS_CY30';
NODE_NAME     U26 CY31
 '@T6G_MB_LIB.T6G(SCH_1):PAGE59_I4@PURE_QUANTA.GENOA_SP5(CHIPS)':
 'VSS_CY31': CDS_PINID='VSS_CY31';
NODE_NAME     U26 CY32
 '@T6G_MB_LIB.T6G(SCH_1):PAGE59_I4@PURE_QUANTA.GENOA_SP5(CHIPS)':
 'VSS_CY32': CDS_PINID='VSS_CY32';
NODE_NAME     U26 CY33
 '@T6G_MB_LIB.T6G(SCH_1):PAGE59_I4@PURE_QUANTA.GENOA_SP5(CHIPS)':
 'VSS_CY33': CDS_PINID='VSS_CY33';
NODE_NAME     U26 CY34
 '@T6G_MB_LIB.T6G(SCH_1):PAGE59_I4@PURE_QUANTA.GENOA_SP5(CHIPS)':
 'VSS_CY34': CDS_PINID='VSS_CY34';
NODE_NAME     U26 CY37
 '@T6G_MB_LIB.T6G(SCH_1):PAGE59_I4@PURE_QUANTA.GENOA_SP5(CHIPS)':
 'VSS_CY37': CDS_PINID='VSS_CY37';
NODE_NAME     U26 CY39
 '@T6G_MB_LIB.T6G(SCH_1):PAGE59_I4@PURE_QUANTA.GENOA_SP5(CHIPS)':
 'VSS_CY39': CDS_PINID='VSS_CY39';
NODE_NAME     U26 CY42
 '@T6G_MB_LIB.T6G(SCH_1):PAGE59_I4@PURE_QUANTA.GENOA_SP5(CHIPS)':
 'VSS_CY42': CDS_PINID='VSS_CY42';
NODE_NAME     U26 CY43
 '@T6G_MB_LIB.T6G(SCH_1):PAGE59_I4@PURE_QUANTA.GENOA_SP5(CHIPS)':
 'VSS_CY43': CDS_PINID='VSS_CY43';
NODE_NAME     U26 CY44
 '@T6G_MB_LIB.T6G(SCH_1):PAGE59_I4@PURE_QUANTA.GENOA_SP5(CHIPS)':
 'VSS_CY44': CDS_PINID='VSS_CY44';
NODE_NAME     U26 CY45
 '@T6G_MB_LIB.T6G(SCH_1):PAGE59_I4@PURE_QUANTA.GENOA_SP5(CHIPS)':
 'VSS_CY45': CDS_PINID='VSS_CY45';
NODE_NAME     U26 CY46
 '@T6G_MB_LIB.T6G(SCH_1):PAGE59_I4@PURE_QUANTA.GENOA_SP5(CHIPS)':
 'VSS_CY46': CDS_PINID='VSS_CY46';
NODE_NAME     U26 CY47
 '@T6G_MB_LIB.T6G(SCH_1):PAGE59_I4@PURE_QUANTA.GENOA_SP5(CHIPS)':
 'VSS_CY47': CDS_PINID='VSS_CY47';
NODE_NAME     U26 CY48
 '@T6G_MB_LIB.T6G(SCH_1):PAGE59_I4@PURE_QUANTA.GENOA_SP5(CHIPS)':
 'VSS_CY48': CDS_PINID='VSS_CY48';
NODE_NAME     U26 CY49
 '@T6G_MB_LIB.T6G(SCH_1):PAGE59_I4@PURE_QUANTA.GENOA_SP5(CHIPS)':
 'VSS_CY49': CDS_PINID='VSS_CY49';
NODE_NAME     U26 CY50
 '@T6G_MB_LIB.T6G(SCH_1):PAGE59_I4@PURE_QUANTA.GENOA_SP5(CHIPS)':
 'VSS_CY50': CDS_PINID='VSS_CY50';
NODE_NAME     U26 CY51
 '@T6G_MB_LIB.T6G(SCH_1):PAGE59_I4@PURE_QUANTA.GENOA_SP5(CHIPS)':
 'VSS_CY51': CDS_PINID='VSS_CY51';
NODE_NAME     U26 CY52
 '@T6G_MB_LIB.T6G(SCH_1):PAGE59_I4@PURE_QUANTA.GENOA_SP5(CHIPS)':
 'VSS_CY52': CDS_PINID='VSS_CY52';
NODE_NAME     U26 CY53
 '@T6G_MB_LIB.T6G(SCH_1):PAGE59_I4@PURE_QUANTA.GENOA_SP5(CHIPS)':
 'VSS_CY53': CDS_PINID='VSS_CY53';
NODE_NAME     U26 CY59
 '@T6G_MB_LIB.T6G(SCH_1):PAGE59_I4@PURE_QUANTA.GENOA_SP5(CHIPS)':
 'VSS_CY59': CDS_PINID='VSS_CY59';
NODE_NAME     U26 CY61
 '@T6G_MB_LIB.T6G(SCH_1):PAGE59_I4@PURE_QUANTA.GENOA_SP5(CHIPS)':
 'VSS_CY61': CDS_PINID='VSS_CY61';
NODE_NAME     U26 CY64
 '@T6G_MB_LIB.T6G(SCH_1):PAGE59_I4@PURE_QUANTA.GENOA_SP5(CHIPS)':
 'VSS_CY64': CDS_PINID='VSS_CY64';
NODE_NAME     U26 CY66
 '@T6G_MB_LIB.T6G(SCH_1):PAGE59_I4@PURE_QUANTA.GENOA_SP5(CHIPS)':
 'VSS_CY66': CDS_PINID='VSS_CY66';
NODE_NAME     U26 CY68
 '@T6G_MB_LIB.T6G(SCH_1):PAGE59_I4@PURE_QUANTA.GENOA_SP5(CHIPS)':
 'VSS_CY68': CDS_PINID='VSS_CY68';
NODE_NAME     U26 CY71
 '@T6G_MB_LIB.T6G(SCH_1):PAGE59_I4@PURE_QUANTA.GENOA_SP5(CHIPS)':
 'VSS_CY71': CDS_PINID='VSS_CY71';
NODE_NAME     U26 CY73
 '@T6G_MB_LIB.T6G(SCH_1):PAGE59_I4@PURE_QUANTA.GENOA_SP5(CHIPS)':
 'VSS_CY73': CDS_PINID='VSS_CY73';
NODE_NAME     U26 DA1
 '@T6G_MB_LIB.T6G(SCH_1):PAGE59_I4@PURE_QUANTA.GENOA_SP5(CHIPS)':
 'VSS_DA1': CDS_PINID='VSS_DA1';
NODE_NAME     U26 DA4
 '@T6G_MB_LIB.T6G(SCH_1):PAGE59_I4@PURE_QUANTA.GENOA_SP5(CHIPS)':
 'VSS_DA4': CDS_PINID='VSS_DA4';
NODE_NAME     U26 DA6
 '@T6G_MB_LIB.T6G(SCH_1):PAGE59_I4@PURE_QUANTA.GENOA_SP5(CHIPS)':
 'VSS_DA6': CDS_PINID='VSS_DA6';
NODE_NAME     U26 DA8
 '@T6G_MB_LIB.T6G(SCH_1):PAGE59_I4@PURE_QUANTA.GENOA_SP5(CHIPS)':
 'VSS_DA8': CDS_PINID='VSS_DA8';
NODE_NAME     U26 DA11
 '@T6G_MB_LIB.T6G(SCH_1):PAGE59_I4@PURE_QUANTA.GENOA_SP5(CHIPS)':
 'VSS_DA11': CDS_PINID='VSS_DA11';
NODE_NAME     U26 DA13
 '@T6G_MB_LIB.T6G(SCH_1):PAGE59_I4@PURE_QUANTA.GENOA_SP5(CHIPS)':
 'VSS_DA13': CDS_PINID='VSS_DA13';
NODE_NAME     U26 DA15
 '@T6G_MB_LIB.T6G(SCH_1):PAGE59_I4@PURE_QUANTA.GENOA_SP5(CHIPS)':
 'VSS_DA15': CDS_PINID='VSS_DA15';
NODE_NAME     U26 DA18
 '@T6G_MB_LIB.T6G(SCH_1):PAGE59_I4@PURE_QUANTA.GENOA_SP5(CHIPS)':
 'VSS_DA18': CDS_PINID='VSS_DA18';
NODE_NAME     U26 DA20
 '@T6G_MB_LIB.T6G(SCH_1):PAGE59_I4@PURE_QUANTA.GENOA_SP5(CHIPS)':
 'VSS_DA20': CDS_PINID='VSS_DA20';
NODE_NAME     U26 DA22
 '@T6G_MB_LIB.T6G(SCH_1):PAGE59_I4@PURE_QUANTA.GENOA_SP5(CHIPS)':
 'VSS_DA22': CDS_PINID='VSS_DA22';
NODE_NAME     U26 DA25
 '@T6G_MB_LIB.T6G(SCH_1):PAGE59_I4@PURE_QUANTA.GENOA_SP5(CHIPS)':
 'VSS_DA25': CDS_PINID='VSS_DA25';
NODE_NAME     U26 DA28
 '@T6G_MB_LIB.T6G(SCH_1):PAGE59_I4@PURE_QUANTA.GENOA_SP5(CHIPS)':
 'VSS_DA28': CDS_PINID='VSS_DA28';
NODE_NAME     U26 DA31
 '@T6G_MB_LIB.T6G(SCH_1):PAGE59_I4@PURE_QUANTA.GENOA_SP5(CHIPS)':
 'VSS_DA31': CDS_PINID='VSS_DA31';
NODE_NAME     U26 DA34
 '@T6G_MB_LIB.T6G(SCH_1):PAGE59_I4@PURE_QUANTA.GENOA_SP5(CHIPS)':
 'VSS_DA34': CDS_PINID='VSS_DA34';
NODE_NAME     U26 DA42
 '@T6G_MB_LIB.T6G(SCH_1):PAGE59_I4@PURE_QUANTA.GENOA_SP5(CHIPS)':
 'VSS_DA42': CDS_PINID='VSS_DA42';
NODE_NAME     U26 DA45
 '@T6G_MB_LIB.T6G(SCH_1):PAGE59_I4@PURE_QUANTA.GENOA_SP5(CHIPS)':
 'VSS_DA45': CDS_PINID='VSS_DA45';
NODE_NAME     U26 DA48
 '@T6G_MB_LIB.T6G(SCH_1):PAGE59_I4@PURE_QUANTA.GENOA_SP5(CHIPS)':
 'VSS_DA48': CDS_PINID='VSS_DA48';
NODE_NAME     U26 DA51
 '@T6G_MB_LIB.T6G(SCH_1):PAGE59_I4@PURE_QUANTA.GENOA_SP5(CHIPS)':
 'VSS_DA51': CDS_PINID='VSS_DA51';
NODE_NAME     U26 DA54
 '@T6G_MB_LIB.T6G(SCH_1):PAGE59_I4@PURE_QUANTA.GENOA_SP5(CHIPS)':
 'VSS_DA54': CDS_PINID='VSS_DA54';
NODE_NAME     U26 DA58
 '@T6G_MB_LIB.T6G(SCH_1):PAGE59_I4@PURE_QUANTA.GENOA_SP5(CHIPS)':
 'VSS_DA58': CDS_PINID='VSS_DA58';
NODE_NAME     U26 DA61
 '@T6G_MB_LIB.T6G(SCH_1):PAGE59_I4@PURE_QUANTA.GENOA_SP5(CHIPS)':
 'VSS_DA61': CDS_PINID='VSS_DA61';
NODE_NAME     U26 DA63
 '@T6G_MB_LIB.T6G(SCH_1):PAGE59_I4@PURE_QUANTA.GENOA_SP5(CHIPS)':
 'VSS_DA63': CDS_PINID='VSS_DA63';
NODE_NAME     U26 DA65
 '@T6G_MB_LIB.T6G(SCH_1):PAGE59_I4@PURE_QUANTA.GENOA_SP5(CHIPS)':
 'VSS_DA65': CDS_PINID='VSS_DA65';
NODE_NAME     U26 DA68
 '@T6G_MB_LIB.T6G(SCH_1):PAGE59_I4@PURE_QUANTA.GENOA_SP5(CHIPS)':
 'VSS_DA68': CDS_PINID='VSS_DA68';
NODE_NAME     U26 DA70
 '@T6G_MB_LIB.T6G(SCH_1):PAGE59_I4@PURE_QUANTA.GENOA_SP5(CHIPS)':
 'VSS_DA70': CDS_PINID='VSS_DA70';
NODE_NAME     U26 AA42
 '@T6G_MB_LIB.T6G(SCH_1):PAGE60_I3@PURE_QUANTA.GENOA_SP5(CHIPS)':
 'VSS_AA42': CDS_PINID='VSS_AA42';
NODE_NAME     U26 AA72
 '@T6G_MB_LIB.T6G(SCH_1):PAGE60_I3@PURE_QUANTA.GENOA_SP5(CHIPS)':
 'VSS_AA72': CDS_PINID='VSS_AA72';
NODE_NAME     U26 AD31
 '@T6G_MB_LIB.T6G(SCH_1):PAGE60_I3@PURE_QUANTA.GENOA_SP5(CHIPS)':
 'VSS_AD31': CDS_PINID='VSS_AD31';
NODE_NAME     U26 AE4
 '@T6G_MB_LIB.T6G(SCH_1):PAGE60_I3@PURE_QUANTA.GENOA_SP5(CHIPS)':
 'VSS_AE4': CDS_PINID='VSS_AE4';
NODE_NAME     U26 AH33
 '@T6G_MB_LIB.T6G(SCH_1):PAGE60_I3@PURE_QUANTA.GENOA_SP5(CHIPS)':
 'VSS_AH33': CDS_PINID='VSS_AH33';
NODE_NAME     U26 AJ13
 '@T6G_MB_LIB.T6G(SCH_1):PAGE60_I3@PURE_QUANTA.GENOA_SP5(CHIPS)':
 'VSS_AJ13': CDS_PINID='VSS_AJ13';
NODE_NAME     U26 AM37
 '@T6G_MB_LIB.T6G(SCH_1):PAGE60_I3@PURE_QUANTA.GENOA_SP5(CHIPS)':
 'VSS_AM37': CDS_PINID='VSS_AM37';
NODE_NAME     U26 AN20
 '@T6G_MB_LIB.T6G(SCH_1):PAGE60_I3@PURE_QUANTA.GENOA_SP5(CHIPS)':
 'VSS_AN20': CDS_PINID='VSS_AN20';
NODE_NAME     U26 BV42
 '@T6G_MB_LIB.T6G(SCH_1):PAGE60_I3@PURE_QUANTA.GENOA_SP5(CHIPS)':
 'VSS_BV42': CDS_PINID='VSS_BV42';
NODE_NAME     U26 BW25
 '@T6G_MB_LIB.T6G(SCH_1):PAGE60_I3@PURE_QUANTA.GENOA_SP5(CHIPS)':
 'VSS_BW25': CDS_PINID='VSS_BW25';
NODE_NAME     U26 CB44
 '@T6G_MB_LIB.T6G(SCH_1):PAGE60_I3@PURE_QUANTA.GENOA_SP5(CHIPS)':
 'VSS_CB44': CDS_PINID='VSS_CB44';
NODE_NAME     U26 CC22
 '@T6G_MB_LIB.T6G(SCH_1):PAGE60_I3@PURE_QUANTA.GENOA_SP5(CHIPS)':
 'VSS_CC22': CDS_PINID='VSS_CC22';
NODE_NAME     U26 CF46
 '@T6G_MB_LIB.T6G(SCH_1):PAGE60_I3@PURE_QUANTA.GENOA_SP5(CHIPS)':
 'VSS_CF46': CDS_PINID='VSS_CF46';
NODE_NAME     U26 CG42
 '@T6G_MB_LIB.T6G(SCH_1):PAGE60_I3@PURE_QUANTA.GENOA_SP5(CHIPS)':
 'VSS_CG42': CDS_PINID='VSS_CG42';
NODE_NAME     U26 CK10
 '@T6G_MB_LIB.T6G(SCH_1):PAGE60_I3@PURE_QUANTA.GENOA_SP5(CHIPS)':
 'VSS_CK10': CDS_PINID='VSS_CK10';
NODE_NAME     U26 CK31
 '@T6G_MB_LIB.T6G(SCH_1):PAGE60_I3@PURE_QUANTA.GENOA_SP5(CHIPS)':
 'VSS_CK31': CDS_PINID='VSS_CK31';
NODE_NAME     U26 CM50
 '@T6G_MB_LIB.T6G(SCH_1):PAGE60_I3@PURE_QUANTA.GENOA_SP5(CHIPS)':
 'VSS_CM50': CDS_PINID='VSS_CM50';
NODE_NAME     U26 CN54
 '@T6G_MB_LIB.T6G(SCH_1):PAGE60_I3@PURE_QUANTA.GENOA_SP5(CHIPS)':
 'VSS_CN54': CDS_PINID='VSS_CN54';
NODE_NAME     U26 CT52
 '@T6G_MB_LIB.T6G(SCH_1):PAGE60_I3@PURE_QUANTA.GENOA_SP5(CHIPS)':
 'VSS_CT52': CDS_PINID='VSS_CT52';
NODE_NAME     U26 CU58
 '@T6G_MB_LIB.T6G(SCH_1):PAGE60_I3@PURE_QUANTA.GENOA_SP5(CHIPS)':
 'VSS_CU58': CDS_PINID='VSS_CU58';
NODE_NAME     U26 CY57
 '@T6G_MB_LIB.T6G(SCH_1):PAGE60_I3@PURE_QUANTA.GENOA_SP5(CHIPS)':
 'VSS_CY57': CDS_PINID='VSS_CY57';
NODE_NAME     U26 DA56
 '@T6G_MB_LIB.T6G(SCH_1):PAGE60_I3@PURE_QUANTA.GENOA_SP5(CHIPS)':
 'VSS_DA56': CDS_PINID='VSS_DA56';
NODE_NAME     U26 DA72
 '@T6G_MB_LIB.T6G(SCH_1):PAGE60_I3@PURE_QUANTA.GENOA_SP5(CHIPS)':
 'VSS_DA72': CDS_PINID='VSS_DA72';
NODE_NAME     U26 DA75
 '@T6G_MB_LIB.T6G(SCH_1):PAGE60_I3@PURE_QUANTA.GENOA_SP5(CHIPS)':
 'VSS_DA75': CDS_PINID='VSS_DA75';
NODE_NAME     U26 DB3
 '@T6G_MB_LIB.T6G(SCH_1):PAGE60_I3@PURE_QUANTA.GENOA_SP5(CHIPS)':
 'VSS_DB3': CDS_PINID='VSS_DB3';
NODE_NAME     U26 DB8
 '@T6G_MB_LIB.T6G(SCH_1):PAGE60_I3@PURE_QUANTA.GENOA_SP5(CHIPS)':
 'VSS_DB8': CDS_PINID='VSS_DB8';
NODE_NAME     U26 DB10
 '@T6G_MB_LIB.T6G(SCH_1):PAGE60_I3@PURE_QUANTA.GENOA_SP5(CHIPS)':
 'VSS_DB10': CDS_PINID='VSS_DB10';
NODE_NAME     U26 DB15
 '@T6G_MB_LIB.T6G(SCH_1):PAGE60_I3@PURE_QUANTA.GENOA_SP5(CHIPS)':
 'VSS_DB15': CDS_PINID='VSS_DB15';
NODE_NAME     U26 DB17
 '@T6G_MB_LIB.T6G(SCH_1):PAGE60_I3@PURE_QUANTA.GENOA_SP5(CHIPS)':
 'VSS_DB17': CDS_PINID='VSS_DB17';
NODE_NAME     U26 DB22
 '@T6G_MB_LIB.T6G(SCH_1):PAGE60_I3@PURE_QUANTA.GENOA_SP5(CHIPS)':
 'VSS_DB22': CDS_PINID='VSS_DB22';
NODE_NAME     U26 DB25
 '@T6G_MB_LIB.T6G(SCH_1):PAGE60_I3@PURE_QUANTA.GENOA_SP5(CHIPS)':
 'VSS_DB25': CDS_PINID='VSS_DB25';
NODE_NAME     U26 DB28
 '@T6G_MB_LIB.T6G(SCH_1):PAGE60_I3@PURE_QUANTA.GENOA_SP5(CHIPS)':
 'VSS_DB28': CDS_PINID='VSS_DB28';
NODE_NAME     U26 DB31
 '@T6G_MB_LIB.T6G(SCH_1):PAGE60_I3@PURE_QUANTA.GENOA_SP5(CHIPS)':
 'VSS_DB31': CDS_PINID='VSS_DB31';
NODE_NAME     U26 DB34
 '@T6G_MB_LIB.T6G(SCH_1):PAGE60_I3@PURE_QUANTA.GENOA_SP5(CHIPS)':
 'VSS_DB34': CDS_PINID='VSS_DB34';
NODE_NAME     U26 DB37
 '@T6G_MB_LIB.T6G(SCH_1):PAGE60_I3@PURE_QUANTA.GENOA_SP5(CHIPS)':
 'VSS_DB37': CDS_PINID='VSS_DB37';
NODE_NAME     U26 DB39
 '@T6G_MB_LIB.T6G(SCH_1):PAGE60_I3@PURE_QUANTA.GENOA_SP5(CHIPS)':
 'VSS_DB39': CDS_PINID='VSS_DB39';
NODE_NAME     U26 DB42
 '@T6G_MB_LIB.T6G(SCH_1):PAGE60_I3@PURE_QUANTA.GENOA_SP5(CHIPS)':
 'VSS_DB42': CDS_PINID='VSS_DB42';
NODE_NAME     U26 DB45
 '@T6G_MB_LIB.T6G(SCH_1):PAGE60_I3@PURE_QUANTA.GENOA_SP5(CHIPS)':
 'VSS_DB45': CDS_PINID='VSS_DB45';
NODE_NAME     U26 DB48
 '@T6G_MB_LIB.T6G(SCH_1):PAGE60_I3@PURE_QUANTA.GENOA_SP5(CHIPS)':
 'VSS_DB48': CDS_PINID='VSS_DB48';
NODE_NAME     U26 DB51
 '@T6G_MB_LIB.T6G(SCH_1):PAGE60_I3@PURE_QUANTA.GENOA_SP5(CHIPS)':
 'VSS_DB51': CDS_PINID='VSS_DB51';
NODE_NAME     U26 DB54
 '@T6G_MB_LIB.T6G(SCH_1):PAGE60_I3@PURE_QUANTA.GENOA_SP5(CHIPS)':
 'VSS_DB54': CDS_PINID='VSS_DB54';
NODE_NAME     U26 DB59
 '@T6G_MB_LIB.T6G(SCH_1):PAGE60_I3@PURE_QUANTA.GENOA_SP5(CHIPS)':
 'VSS_DB59': CDS_PINID='VSS_DB59';
NODE_NAME     U26 DB61
 '@T6G_MB_LIB.T6G(SCH_1):PAGE60_I3@PURE_QUANTA.GENOA_SP5(CHIPS)':
 'VSS_DB61': CDS_PINID='VSS_DB61';
NODE_NAME     U26 DB66
 '@T6G_MB_LIB.T6G(SCH_1):PAGE60_I3@PURE_QUANTA.GENOA_SP5(CHIPS)':
 'VSS_DB66': CDS_PINID='VSS_DB66';
NODE_NAME     U26 DB68
 '@T6G_MB_LIB.T6G(SCH_1):PAGE60_I3@PURE_QUANTA.GENOA_SP5(CHIPS)':
 'VSS_DB68': CDS_PINID='VSS_DB68';
NODE_NAME     U26 DB73
 '@T6G_MB_LIB.T6G(SCH_1):PAGE60_I3@PURE_QUANTA.GENOA_SP5(CHIPS)':
 'VSS_DB73': CDS_PINID='VSS_DB73';
NODE_NAME     U26 DC1
 '@T6G_MB_LIB.T6G(SCH_1):PAGE60_I3@PURE_QUANTA.GENOA_SP5(CHIPS)':
 'VSS_DC1': CDS_PINID='VSS_DC1';
NODE_NAME     U26 DC4
 '@T6G_MB_LIB.T6G(SCH_1):PAGE60_I3@PURE_QUANTA.GENOA_SP5(CHIPS)':
 'VSS_DC4': CDS_PINID='VSS_DC4';
NODE_NAME     U26 DC6
 '@T6G_MB_LIB.T6G(SCH_1):PAGE60_I3@PURE_QUANTA.GENOA_SP5(CHIPS)':
 'VSS_DC6': CDS_PINID='VSS_DC6';
NODE_NAME     U26 DC8
 '@T6G_MB_LIB.T6G(SCH_1):PAGE60_I3@PURE_QUANTA.GENOA_SP5(CHIPS)':
 'VSS_DC8': CDS_PINID='VSS_DC8';
NODE_NAME     U26 DC11
 '@T6G_MB_LIB.T6G(SCH_1):PAGE60_I3@PURE_QUANTA.GENOA_SP5(CHIPS)':
 'VSS_DC11': CDS_PINID='VSS_DC11';
NODE_NAME     U26 DC13
 '@T6G_MB_LIB.T6G(SCH_1):PAGE60_I3@PURE_QUANTA.GENOA_SP5(CHIPS)':
 'VSS_DC13': CDS_PINID='VSS_DC13';
NODE_NAME     U26 DC15
 '@T6G_MB_LIB.T6G(SCH_1):PAGE60_I3@PURE_QUANTA.GENOA_SP5(CHIPS)':
 'VSS_DC15': CDS_PINID='VSS_DC15';
NODE_NAME     U26 DC18
 '@T6G_MB_LIB.T6G(SCH_1):PAGE60_I3@PURE_QUANTA.GENOA_SP5(CHIPS)':
 'VSS_DC18': CDS_PINID='VSS_DC18';
NODE_NAME     U26 DC20
 '@T6G_MB_LIB.T6G(SCH_1):PAGE60_I3@PURE_QUANTA.GENOA_SP5(CHIPS)':
 'VSS_DC20': CDS_PINID='VSS_DC20';
NODE_NAME     U26 DC22
 '@T6G_MB_LIB.T6G(SCH_1):PAGE60_I3@PURE_QUANTA.GENOA_SP5(CHIPS)':
 'VSS_DC22': CDS_PINID='VSS_DC22';
NODE_NAME     U26 DC25
 '@T6G_MB_LIB.T6G(SCH_1):PAGE60_I3@PURE_QUANTA.GENOA_SP5(CHIPS)':
 'VSS_DC25': CDS_PINID='VSS_DC25';
NODE_NAME     U26 DC28
 '@T6G_MB_LIB.T6G(SCH_1):PAGE60_I3@PURE_QUANTA.GENOA_SP5(CHIPS)':
 'VSS_DC28': CDS_PINID='VSS_DC28';
NODE_NAME     U26 DC31
 '@T6G_MB_LIB.T6G(SCH_1):PAGE60_I3@PURE_QUANTA.GENOA_SP5(CHIPS)':
 'VSS_DC31': CDS_PINID='VSS_DC31';
NODE_NAME     U26 DC34
 '@T6G_MB_LIB.T6G(SCH_1):PAGE60_I3@PURE_QUANTA.GENOA_SP5(CHIPS)':
 'VSS_DC34': CDS_PINID='VSS_DC34';
NODE_NAME     U26 DC42
 '@T6G_MB_LIB.T6G(SCH_1):PAGE60_I3@PURE_QUANTA.GENOA_SP5(CHIPS)':
 'VSS_DC42': CDS_PINID='VSS_DC42';
NODE_NAME     U26 DC45
 '@T6G_MB_LIB.T6G(SCH_1):PAGE60_I3@PURE_QUANTA.GENOA_SP5(CHIPS)':
 'VSS_DC45': CDS_PINID='VSS_DC45';
NODE_NAME     U26 DC48
 '@T6G_MB_LIB.T6G(SCH_1):PAGE60_I3@PURE_QUANTA.GENOA_SP5(CHIPS)':
 'VSS_DC48': CDS_PINID='VSS_DC48';
NODE_NAME     U26 DC51
 '@T6G_MB_LIB.T6G(SCH_1):PAGE60_I3@PURE_QUANTA.GENOA_SP5(CHIPS)':
 'VSS_DC51': CDS_PINID='VSS_DC51';
NODE_NAME     U26 DC54
 '@T6G_MB_LIB.T6G(SCH_1):PAGE60_I3@PURE_QUANTA.GENOA_SP5(CHIPS)':
 'VSS_DC54': CDS_PINID='VSS_DC54';
NODE_NAME     U26 DC56
 '@T6G_MB_LIB.T6G(SCH_1):PAGE60_I3@PURE_QUANTA.GENOA_SP5(CHIPS)':
 'VSS_DC56': CDS_PINID='VSS_DC56';
NODE_NAME     U26 DC58
 '@T6G_MB_LIB.T6G(SCH_1):PAGE60_I3@PURE_QUANTA.GENOA_SP5(CHIPS)':
 'VSS_DC58': CDS_PINID='VSS_DC58';
NODE_NAME     U26 DC61
 '@T6G_MB_LIB.T6G(SCH_1):PAGE60_I3@PURE_QUANTA.GENOA_SP5(CHIPS)':
 'VSS_DC61': CDS_PINID='VSS_DC61';
NODE_NAME     U26 DC63
 '@T6G_MB_LIB.T6G(SCH_1):PAGE60_I3@PURE_QUANTA.GENOA_SP5(CHIPS)':
 'VSS_DC63': CDS_PINID='VSS_DC63';
NODE_NAME     U26 DC65
 '@T6G_MB_LIB.T6G(SCH_1):PAGE60_I3@PURE_QUANTA.GENOA_SP5(CHIPS)':
 'VSS_DC65': CDS_PINID='VSS_DC65';
NODE_NAME     U26 DC68
 '@T6G_MB_LIB.T6G(SCH_1):PAGE60_I3@PURE_QUANTA.GENOA_SP5(CHIPS)':
 'VSS_DC68': CDS_PINID='VSS_DC68';
NODE_NAME     U26 DC70
 '@T6G_MB_LIB.T6G(SCH_1):PAGE60_I3@PURE_QUANTA.GENOA_SP5(CHIPS)':
 'VSS_DC70': CDS_PINID='VSS_DC70';
NODE_NAME     U26 DC72
 '@T6G_MB_LIB.T6G(SCH_1):PAGE60_I3@PURE_QUANTA.GENOA_SP5(CHIPS)':
 'VSS_DC72': CDS_PINID='VSS_DC72';
NODE_NAME     U26 DC75
 '@T6G_MB_LIB.T6G(SCH_1):PAGE60_I3@PURE_QUANTA.GENOA_SP5(CHIPS)':
 'VSS_DC75': CDS_PINID='VSS_DC75';
NODE_NAME     U26 DD3
 '@T6G_MB_LIB.T6G(SCH_1):PAGE60_I3@PURE_QUANTA.GENOA_SP5(CHIPS)':
 'VSS_DD3': CDS_PINID='VSS_DD3';
NODE_NAME     U26 DD5
 '@T6G_MB_LIB.T6G(SCH_1):PAGE60_I3@PURE_QUANTA.GENOA_SP5(CHIPS)':
 'VSS_DD5': CDS_PINID='VSS_DD5';
NODE_NAME     U26 DD8
 '@T6G_MB_LIB.T6G(SCH_1):PAGE60_I3@PURE_QUANTA.GENOA_SP5(CHIPS)':
 'VSS_DD8': CDS_PINID='VSS_DD8';
NODE_NAME     U26 DD10
 '@T6G_MB_LIB.T6G(SCH_1):PAGE60_I3@PURE_QUANTA.GENOA_SP5(CHIPS)':
 'VSS_DD10': CDS_PINID='VSS_DD10';
NODE_NAME     U26 DD12
 '@T6G_MB_LIB.T6G(SCH_1):PAGE60_I3@PURE_QUANTA.GENOA_SP5(CHIPS)':
 'VSS_DD12': CDS_PINID='VSS_DD12';
NODE_NAME     U26 DD15
 '@T6G_MB_LIB.T6G(SCH_1):PAGE60_I3@PURE_QUANTA.GENOA_SP5(CHIPS)':
 'VSS_DD15': CDS_PINID='VSS_DD15';
NODE_NAME     U26 DD17
 '@T6G_MB_LIB.T6G(SCH_1):PAGE60_I3@PURE_QUANTA.GENOA_SP5(CHIPS)':
 'VSS_DD17': CDS_PINID='VSS_DD17';
NODE_NAME     U26 DD19
 '@T6G_MB_LIB.T6G(SCH_1):PAGE60_I3@PURE_QUANTA.GENOA_SP5(CHIPS)':
 'VSS_DD19': CDS_PINID='VSS_DD19';
NODE_NAME     U26 DD23
 '@T6G_MB_LIB.T6G(SCH_1):PAGE60_I3@PURE_QUANTA.GENOA_SP5(CHIPS)':
 'VSS_DD23': CDS_PINID='VSS_DD23';
NODE_NAME     U26 DD24
 '@T6G_MB_LIB.T6G(SCH_1):PAGE60_I3@PURE_QUANTA.GENOA_SP5(CHIPS)':
 'VSS_DD24': CDS_PINID='VSS_DD24';
NODE_NAME     U26 DD26
 '@T6G_MB_LIB.T6G(SCH_1):PAGE60_I3@PURE_QUANTA.GENOA_SP5(CHIPS)':
 'VSS_DD26': CDS_PINID='VSS_DD26';
NODE_NAME     U26 DD27
 '@T6G_MB_LIB.T6G(SCH_1):PAGE60_I3@PURE_QUANTA.GENOA_SP5(CHIPS)':
 'VSS_DD27': CDS_PINID='VSS_DD27';
NODE_NAME     U26 DD29
 '@T6G_MB_LIB.T6G(SCH_1):PAGE60_I3@PURE_QUANTA.GENOA_SP5(CHIPS)':
 'VSS_DD29': CDS_PINID='VSS_DD29';
NODE_NAME     U26 DD30
 '@T6G_MB_LIB.T6G(SCH_1):PAGE60_I3@PURE_QUANTA.GENOA_SP5(CHIPS)':
 'VSS_DD30': CDS_PINID='VSS_DD30';
NODE_NAME     U26 DD32
 '@T6G_MB_LIB.T6G(SCH_1):PAGE60_I3@PURE_QUANTA.GENOA_SP5(CHIPS)':
 'VSS_DD32': CDS_PINID='VSS_DD32';
NODE_NAME     U26 DD33
 '@T6G_MB_LIB.T6G(SCH_1):PAGE60_I3@PURE_QUANTA.GENOA_SP5(CHIPS)':
 'VSS_DD33': CDS_PINID='VSS_DD33';
NODE_NAME     U26 DD35
 '@T6G_MB_LIB.T6G(SCH_1):PAGE60_I3@PURE_QUANTA.GENOA_SP5(CHIPS)':
 'VSS_DD35': CDS_PINID='VSS_DD35';
NODE_NAME     U26 DD36
 '@T6G_MB_LIB.T6G(SCH_1):PAGE60_I3@PURE_QUANTA.GENOA_SP5(CHIPS)':
 'VSS_DD36': CDS_PINID='VSS_DD36';
NODE_NAME     U26 DD37
 '@T6G_MB_LIB.T6G(SCH_1):PAGE60_I3@PURE_QUANTA.GENOA_SP5(CHIPS)':
 'VSS_DD37': CDS_PINID='VSS_DD37';
NODE_NAME     U26 DD39
 '@T6G_MB_LIB.T6G(SCH_1):PAGE60_I3@PURE_QUANTA.GENOA_SP5(CHIPS)':
 'VSS_DD39': CDS_PINID='VSS_DD39';
NODE_NAME     U26 DD40
 '@T6G_MB_LIB.T6G(SCH_1):PAGE60_I3@PURE_QUANTA.GENOA_SP5(CHIPS)':
 'VSS_DD40': CDS_PINID='VSS_DD40';
NODE_NAME     U26 DD41
 '@T6G_MB_LIB.T6G(SCH_1):PAGE60_I3@PURE_QUANTA.GENOA_SP5(CHIPS)':
 'VSS_DD41': CDS_PINID='VSS_DD41';
NODE_NAME     U26 DD43
 '@T6G_MB_LIB.T6G(SCH_1):PAGE60_I3@PURE_QUANTA.GENOA_SP5(CHIPS)':
 'VSS_DD43': CDS_PINID='VSS_DD43';
NODE_NAME     U26 DD44
 '@T6G_MB_LIB.T6G(SCH_1):PAGE60_I3@PURE_QUANTA.GENOA_SP5(CHIPS)':
 'VSS_DD44': CDS_PINID='VSS_DD44';
NODE_NAME     U26 DD46
 '@T6G_MB_LIB.T6G(SCH_1):PAGE60_I3@PURE_QUANTA.GENOA_SP5(CHIPS)':
 'VSS_DD46': CDS_PINID='VSS_DD46';
NODE_NAME     U26 DD47
 '@T6G_MB_LIB.T6G(SCH_1):PAGE60_I3@PURE_QUANTA.GENOA_SP5(CHIPS)':
 'VSS_DD47': CDS_PINID='VSS_DD47';
NODE_NAME     U26 DD49
 '@T6G_MB_LIB.T6G(SCH_1):PAGE60_I3@PURE_QUANTA.GENOA_SP5(CHIPS)':
 'VSS_DD49': CDS_PINID='VSS_DD49';
NODE_NAME     U26 DD50
 '@T6G_MB_LIB.T6G(SCH_1):PAGE60_I3@PURE_QUANTA.GENOA_SP5(CHIPS)':
 'VSS_DD50': CDS_PINID='VSS_DD50';
NODE_NAME     U26 DD52
 '@T6G_MB_LIB.T6G(SCH_1):PAGE60_I3@PURE_QUANTA.GENOA_SP5(CHIPS)':
 'VSS_DD52': CDS_PINID='VSS_DD52';
NODE_NAME     U26 DD53
 '@T6G_MB_LIB.T6G(SCH_1):PAGE60_I3@PURE_QUANTA.GENOA_SP5(CHIPS)':
 'VSS_DD53': CDS_PINID='VSS_DD53';
NODE_NAME     U26 DD57
 '@T6G_MB_LIB.T6G(SCH_1):PAGE60_I3@PURE_QUANTA.GENOA_SP5(CHIPS)':
 'VSS_DD57': CDS_PINID='VSS_DD57';
NODE_NAME     U26 DD59
 '@T6G_MB_LIB.T6G(SCH_1):PAGE60_I3@PURE_QUANTA.GENOA_SP5(CHIPS)':
 'VSS_DD59': CDS_PINID='VSS_DD59';
NODE_NAME     U26 DD61
 '@T6G_MB_LIB.T6G(SCH_1):PAGE60_I3@PURE_QUANTA.GENOA_SP5(CHIPS)':
 'VSS_DD61': CDS_PINID='VSS_DD61';
NODE_NAME     U26 DD64
 '@T6G_MB_LIB.T6G(SCH_1):PAGE60_I3@PURE_QUANTA.GENOA_SP5(CHIPS)':
 'VSS_DD64': CDS_PINID='VSS_DD64';
NODE_NAME     U26 DD66
 '@T6G_MB_LIB.T6G(SCH_1):PAGE60_I3@PURE_QUANTA.GENOA_SP5(CHIPS)':
 'VSS_DD66': CDS_PINID='VSS_DD66';
NODE_NAME     U26 DD68
 '@T6G_MB_LIB.T6G(SCH_1):PAGE60_I3@PURE_QUANTA.GENOA_SP5(CHIPS)':
 'VSS_DD68': CDS_PINID='VSS_DD68';
NODE_NAME     U26 DD71
 '@T6G_MB_LIB.T6G(SCH_1):PAGE60_I3@PURE_QUANTA.GENOA_SP5(CHIPS)':
 'VSS_DD71': CDS_PINID='VSS_DD71';
NODE_NAME     U26 DD73
 '@T6G_MB_LIB.T6G(SCH_1):PAGE60_I3@PURE_QUANTA.GENOA_SP5(CHIPS)':
 'VSS_DD73': CDS_PINID='VSS_DD73';
NODE_NAME     U26 DE1
 '@T6G_MB_LIB.T6G(SCH_1):PAGE60_I3@PURE_QUANTA.GENOA_SP5(CHIPS)':
 'VSS_DE1': CDS_PINID='VSS_DE1';
NODE_NAME     U26 DE6
 '@T6G_MB_LIB.T6G(SCH_1):PAGE60_I3@PURE_QUANTA.GENOA_SP5(CHIPS)':
 'VSS_DE6': CDS_PINID='VSS_DE6';
NODE_NAME     U26 DE8
 '@T6G_MB_LIB.T6G(SCH_1):PAGE60_I3@PURE_QUANTA.GENOA_SP5(CHIPS)':
 'VSS_DE8': CDS_PINID='VSS_DE8';
NODE_NAME     U26 DE13
 '@T6G_MB_LIB.T6G(SCH_1):PAGE60_I3@PURE_QUANTA.GENOA_SP5(CHIPS)':
 'VSS_DE13': CDS_PINID='VSS_DE13';
NODE_NAME     U26 DE15
 '@T6G_MB_LIB.T6G(SCH_1):PAGE60_I3@PURE_QUANTA.GENOA_SP5(CHIPS)':
 'VSS_DE15': CDS_PINID='VSS_DE15';
NODE_NAME     U26 DE20
 '@T6G_MB_LIB.T6G(SCH_1):PAGE60_I3@PURE_QUANTA.GENOA_SP5(CHIPS)':
 'VSS_DE20': CDS_PINID='VSS_DE20';
NODE_NAME     U26 DE23
 '@T6G_MB_LIB.T6G(SCH_1):PAGE60_I3@PURE_QUANTA.GENOA_SP5(CHIPS)':
 'VSS_DE23': CDS_PINID='VSS_DE23';
NODE_NAME     U26 DE26
 '@T6G_MB_LIB.T6G(SCH_1):PAGE60_I3@PURE_QUANTA.GENOA_SP5(CHIPS)':
 'VSS_DE26': CDS_PINID='VSS_DE26';
NODE_NAME     U26 DE29
 '@T6G_MB_LIB.T6G(SCH_1):PAGE60_I3@PURE_QUANTA.GENOA_SP5(CHIPS)':
 'VSS_DE29': CDS_PINID='VSS_DE29';
NODE_NAME     U26 DE33
 '@T6G_MB_LIB.T6G(SCH_1):PAGE60_I3@PURE_QUANTA.GENOA_SP5(CHIPS)':
 'VSS_DE33': CDS_PINID='VSS_DE33';
NODE_NAME     U26 DE56
 '@T6G_MB_LIB.T6G(SCH_1):PAGE60_I3@PURE_QUANTA.GENOA_SP5(CHIPS)':
 'VSS_DE56': CDS_PINID='VSS_DE56';
NODE_NAME     U26 DE61
 '@T6G_MB_LIB.T6G(SCH_1):PAGE60_I3@PURE_QUANTA.GENOA_SP5(CHIPS)':
 'VSS_DE61': CDS_PINID='VSS_DE61';
NODE_NAME     U26 DE63
 '@T6G_MB_LIB.T6G(SCH_1):PAGE60_I3@PURE_QUANTA.GENOA_SP5(CHIPS)':
 'VSS_DE63': CDS_PINID='VSS_DE63';
NODE_NAME     U26 DE68
 '@T6G_MB_LIB.T6G(SCH_1):PAGE60_I3@PURE_QUANTA.GENOA_SP5(CHIPS)':
 'VSS_DE68': CDS_PINID='VSS_DE68';
NODE_NAME     U26 DE70
 '@T6G_MB_LIB.T6G(SCH_1):PAGE60_I3@PURE_QUANTA.GENOA_SP5(CHIPS)':
 'VSS_DE70': CDS_PINID='VSS_DE70';
NODE_NAME     U26 DE75
 '@T6G_MB_LIB.T6G(SCH_1):PAGE60_I3@PURE_QUANTA.GENOA_SP5(CHIPS)':
 'VSS_DE75': CDS_PINID='VSS_DE75';
NODE_NAME     U26 DF3
 '@T6G_MB_LIB.T6G(SCH_1):PAGE60_I3@PURE_QUANTA.GENOA_SP5(CHIPS)':
 'VSS_DF3': CDS_PINID='VSS_DF3';
NODE_NAME     U26 DF4
 '@T6G_MB_LIB.T6G(SCH_1):PAGE60_I3@PURE_QUANTA.GENOA_SP5(CHIPS)':
 'VSS_DF4': CDS_PINID='VSS_DF4';
NODE_NAME     U26 DF5
 '@T6G_MB_LIB.T6G(SCH_1):PAGE60_I3@PURE_QUANTA.GENOA_SP5(CHIPS)':
 'VSS_DF5': CDS_PINID='VSS_DF5';
NODE_NAME     U26 DF6
 '@T6G_MB_LIB.T6G(SCH_1):PAGE60_I3@PURE_QUANTA.GENOA_SP5(CHIPS)':
 'VSS_DF6': CDS_PINID='VSS_DF6';
NODE_NAME     U26 DF8
 '@T6G_MB_LIB.T6G(SCH_1):PAGE60_I3@PURE_QUANTA.GENOA_SP5(CHIPS)':
 'VSS_DF8': CDS_PINID='VSS_DF8';
NODE_NAME     U26 DF10
 '@T6G_MB_LIB.T6G(SCH_1):PAGE60_I3@PURE_QUANTA.GENOA_SP5(CHIPS)':
 'VSS_DF10': CDS_PINID='VSS_DF10';
NODE_NAME     U26 DF11
 '@T6G_MB_LIB.T6G(SCH_1):PAGE60_I3@PURE_QUANTA.GENOA_SP5(CHIPS)':
 'VSS_DF11': CDS_PINID='VSS_DF11';
NODE_NAME     U26 DF12
 '@T6G_MB_LIB.T6G(SCH_1):PAGE60_I3@PURE_QUANTA.GENOA_SP5(CHIPS)':
 'VSS_DF12': CDS_PINID='VSS_DF12';
NODE_NAME     U26 DF13
 '@T6G_MB_LIB.T6G(SCH_1):PAGE60_I3@PURE_QUANTA.GENOA_SP5(CHIPS)':
 'VSS_DF13': CDS_PINID='VSS_DF13';
NODE_NAME     U26 DF15
 '@T6G_MB_LIB.T6G(SCH_1):PAGE60_I3@PURE_QUANTA.GENOA_SP5(CHIPS)':
 'VSS_DF15': CDS_PINID='VSS_DF15';
NODE_NAME     U26 DF17
 '@T6G_MB_LIB.T6G(SCH_1):PAGE60_I3@PURE_QUANTA.GENOA_SP5(CHIPS)':
 'VSS_DF17': CDS_PINID='VSS_DF17';
NODE_NAME     U26 DF18
 '@T6G_MB_LIB.T6G(SCH_1):PAGE60_I3@PURE_QUANTA.GENOA_SP5(CHIPS)':
 'VSS_DF18': CDS_PINID='VSS_DF18';
NODE_NAME     U26 DF19
 '@T6G_MB_LIB.T6G(SCH_1):PAGE60_I3@PURE_QUANTA.GENOA_SP5(CHIPS)':
 'VSS_DF19': CDS_PINID='VSS_DF19';
NODE_NAME     U26 DF20
 '@T6G_MB_LIB.T6G(SCH_1):PAGE60_I3@PURE_QUANTA.GENOA_SP5(CHIPS)':
 'VSS_DF20': CDS_PINID='VSS_DF20';
NODE_NAME     U26 DF22
 '@T6G_MB_LIB.T6G(SCH_1):PAGE60_I3@PURE_QUANTA.GENOA_SP5(CHIPS)':
 'VSS_DF22': CDS_PINID='VSS_DF22';
NODE_NAME     U26 DF23
 '@T6G_MB_LIB.T6G(SCH_1):PAGE60_I3@PURE_QUANTA.GENOA_SP5(CHIPS)':
 'VSS_DF23': CDS_PINID='VSS_DF23';
NODE_NAME     U26 DF26
 '@T6G_MB_LIB.T6G(SCH_1):PAGE60_I3@PURE_QUANTA.GENOA_SP5(CHIPS)':
 'VSS_DF26': CDS_PINID='VSS_DF26';
NODE_NAME     U26 DF29
 '@T6G_MB_LIB.T6G(SCH_1):PAGE60_I3@PURE_QUANTA.GENOA_SP5(CHIPS)':
 'VSS_DF29': CDS_PINID='VSS_DF29';
NODE_NAME     U26 DF32
 '@T6G_MB_LIB.T6G(SCH_1):PAGE60_I3@PURE_QUANTA.GENOA_SP5(CHIPS)':
 'VSS_DF32': CDS_PINID='VSS_DF32';
NODE_NAME     U26 DF35
 '@T6G_MB_LIB.T6G(SCH_1):PAGE60_I3@PURE_QUANTA.GENOA_SP5(CHIPS)':
 'VSS_DF35': CDS_PINID='VSS_DF35';
NODE_NAME     U26 DF37
 '@T6G_MB_LIB.T6G(SCH_1):PAGE60_I3@PURE_QUANTA.GENOA_SP5(CHIPS)':
 'VSS_DF37': CDS_PINID='VSS_DF37';
NODE_NAME     U26 DF39
 '@T6G_MB_LIB.T6G(SCH_1):PAGE60_I3@PURE_QUANTA.GENOA_SP5(CHIPS)':
 'VSS_DF39': CDS_PINID='VSS_DF39';
NODE_NAME     U26 DF42
 '@T6G_MB_LIB.T6G(SCH_1):PAGE60_I3@PURE_QUANTA.GENOA_SP5(CHIPS)':
 'VSS_DF42': CDS_PINID='VSS_DF42';
NODE_NAME     U26 DF43
 '@T6G_MB_LIB.T6G(SCH_1):PAGE60_I3@PURE_QUANTA.GENOA_SP5(CHIPS)':
 'VSS_DF43': CDS_PINID='VSS_DF43';
NODE_NAME     U26 DF44
 '@T6G_MB_LIB.T6G(SCH_1):PAGE60_I3@PURE_QUANTA.GENOA_SP5(CHIPS)':
 'VSS_DF44': CDS_PINID='VSS_DF44';
NODE_NAME     U26 DF45
 '@T6G_MB_LIB.T6G(SCH_1):PAGE60_I3@PURE_QUANTA.GENOA_SP5(CHIPS)':
 'VSS_DF45': CDS_PINID='VSS_DF45';
NODE_NAME     U26 DF46
 '@T6G_MB_LIB.T6G(SCH_1):PAGE60_I3@PURE_QUANTA.GENOA_SP5(CHIPS)':
 'VSS_DF46': CDS_PINID='VSS_DF46';
NODE_NAME     U26 DF47
 '@T6G_MB_LIB.T6G(SCH_1):PAGE60_I3@PURE_QUANTA.GENOA_SP5(CHIPS)':
 'VSS_DF47': CDS_PINID='VSS_DF47';
NODE_NAME     U26 DF48
 '@T6G_MB_LIB.T6G(SCH_1):PAGE60_I3@PURE_QUANTA.GENOA_SP5(CHIPS)':
 'VSS_DF48': CDS_PINID='VSS_DF48';
NODE_NAME     U26 DF49
 '@T6G_MB_LIB.T6G(SCH_1):PAGE60_I3@PURE_QUANTA.GENOA_SP5(CHIPS)':
 'VSS_DF49': CDS_PINID='VSS_DF49';
NODE_NAME     U26 DF50
 '@T6G_MB_LIB.T6G(SCH_1):PAGE60_I3@PURE_QUANTA.GENOA_SP5(CHIPS)':
 'VSS_DF50': CDS_PINID='VSS_DF50';
NODE_NAME     U26 DF51
 '@T6G_MB_LIB.T6G(SCH_1):PAGE60_I3@PURE_QUANTA.GENOA_SP5(CHIPS)':
 'VSS_DF51': CDS_PINID='VSS_DF51';
NODE_NAME     U26 DF52
 '@T6G_MB_LIB.T6G(SCH_1):PAGE60_I3@PURE_QUANTA.GENOA_SP5(CHIPS)':
 'VSS_DF52': CDS_PINID='VSS_DF52';
NODE_NAME     U26 DF53
 '@T6G_MB_LIB.T6G(SCH_1):PAGE60_I3@PURE_QUANTA.GENOA_SP5(CHIPS)':
 'VSS_DF53': CDS_PINID='VSS_DF53';
NODE_NAME     U26 DF54
 '@T6G_MB_LIB.T6G(SCH_1):PAGE60_I3@PURE_QUANTA.GENOA_SP5(CHIPS)':
 'VSS_DF54': CDS_PINID='VSS_DF54';
NODE_NAME     U26 DF56
 '@T6G_MB_LIB.T6G(SCH_1):PAGE60_I3@PURE_QUANTA.GENOA_SP5(CHIPS)':
 'VSS_DF56': CDS_PINID='VSS_DF56';
NODE_NAME     U26 DF57
 '@T6G_MB_LIB.T6G(SCH_1):PAGE60_I3@PURE_QUANTA.GENOA_SP5(CHIPS)':
 'VSS_DF57': CDS_PINID='VSS_DF57';
NODE_NAME     U26 DF58
 '@T6G_MB_LIB.T6G(SCH_1):PAGE60_I3@PURE_QUANTA.GENOA_SP5(CHIPS)':
 'VSS_DF58': CDS_PINID='VSS_DF58';
NODE_NAME     U26 DF59
 '@T6G_MB_LIB.T6G(SCH_1):PAGE60_I3@PURE_QUANTA.GENOA_SP5(CHIPS)':
 'VSS_DF59': CDS_PINID='VSS_DF59';
NODE_NAME     U26 DF61
 '@T6G_MB_LIB.T6G(SCH_1):PAGE60_I3@PURE_QUANTA.GENOA_SP5(CHIPS)':
 'VSS_DF61': CDS_PINID='VSS_DF61';
NODE_NAME     U26 DF63
 '@T6G_MB_LIB.T6G(SCH_1):PAGE60_I3@PURE_QUANTA.GENOA_SP5(CHIPS)':
 'VSS_DF63': CDS_PINID='VSS_DF63';
NODE_NAME     U26 DF64
 '@T6G_MB_LIB.T6G(SCH_1):PAGE60_I3@PURE_QUANTA.GENOA_SP5(CHIPS)':
 'VSS_DF64': CDS_PINID='VSS_DF64';
NODE_NAME     U26 DF65
 '@T6G_MB_LIB.T6G(SCH_1):PAGE60_I3@PURE_QUANTA.GENOA_SP5(CHIPS)':
 'VSS_DF65': CDS_PINID='VSS_DF65';
NODE_NAME     U26 DF66
 '@T6G_MB_LIB.T6G(SCH_1):PAGE60_I3@PURE_QUANTA.GENOA_SP5(CHIPS)':
 'VSS_DF66': CDS_PINID='VSS_DF66';
NODE_NAME     U26 DF68
 '@T6G_MB_LIB.T6G(SCH_1):PAGE60_I3@PURE_QUANTA.GENOA_SP5(CHIPS)':
 'VSS_DF68': CDS_PINID='VSS_DF68';
NODE_NAME     U26 DF70
 '@T6G_MB_LIB.T6G(SCH_1):PAGE60_I3@PURE_QUANTA.GENOA_SP5(CHIPS)':
 'VSS_DF70': CDS_PINID='VSS_DF70';
NODE_NAME     U26 DF71
 '@T6G_MB_LIB.T6G(SCH_1):PAGE60_I3@PURE_QUANTA.GENOA_SP5(CHIPS)':
 'VSS_DF71': CDS_PINID='VSS_DF71';
NODE_NAME     U26 DF72
 '@T6G_MB_LIB.T6G(SCH_1):PAGE60_I3@PURE_QUANTA.GENOA_SP5(CHIPS)':
 'VSS_DF72': CDS_PINID='VSS_DF72';
NODE_NAME     U26 DF73
 '@T6G_MB_LIB.T6G(SCH_1):PAGE60_I3@PURE_QUANTA.GENOA_SP5(CHIPS)':
 'VSS_DF73': CDS_PINID='VSS_DF73';
NODE_NAME     U26 DG1
 '@T6G_MB_LIB.T6G(SCH_1):PAGE60_I3@PURE_QUANTA.GENOA_SP5(CHIPS)':
 'VSS_DG1': CDS_PINID='VSS_DG1';
NODE_NAME     U26 DG2
 '@T6G_MB_LIB.T6G(SCH_1):PAGE60_I3@PURE_QUANTA.GENOA_SP5(CHIPS)':
 'VSS_DG2': CDS_PINID='VSS_DG2';
NODE_NAME     U26 DG6
 '@T6G_MB_LIB.T6G(SCH_1):PAGE60_I3@PURE_QUANTA.GENOA_SP5(CHIPS)':
 'VSS_DG6': CDS_PINID='VSS_DG6';
NODE_NAME     U26 DG7
 '@T6G_MB_LIB.T6G(SCH_1):PAGE60_I3@PURE_QUANTA.GENOA_SP5(CHIPS)':
 'VSS_DG7': CDS_PINID='VSS_DG7';
NODE_NAME     U26 DG8
 '@T6G_MB_LIB.T6G(SCH_1):PAGE60_I3@PURE_QUANTA.GENOA_SP5(CHIPS)':
 'VSS_DG8': CDS_PINID='VSS_DG8';
NODE_NAME     U26 DG9
 '@T6G_MB_LIB.T6G(SCH_1):PAGE60_I3@PURE_QUANTA.GENOA_SP5(CHIPS)':
 'VSS_DG9': CDS_PINID='VSS_DG9';
NODE_NAME     U26 DG13
 '@T6G_MB_LIB.T6G(SCH_1):PAGE60_I3@PURE_QUANTA.GENOA_SP5(CHIPS)':
 'VSS_DG13': CDS_PINID='VSS_DG13';
NODE_NAME     U26 DG14
 '@T6G_MB_LIB.T6G(SCH_1):PAGE60_I3@PURE_QUANTA.GENOA_SP5(CHIPS)':
 'VSS_DG14': CDS_PINID='VSS_DG14';
NODE_NAME     U26 DG15
 '@T6G_MB_LIB.T6G(SCH_1):PAGE60_I3@PURE_QUANTA.GENOA_SP5(CHIPS)':
 'VSS_DG15': CDS_PINID='VSS_DG15';
NODE_NAME     U26 DG16
 '@T6G_MB_LIB.T6G(SCH_1):PAGE60_I3@PURE_QUANTA.GENOA_SP5(CHIPS)':
 'VSS_DG16': CDS_PINID='VSS_DG16';
NODE_NAME     U26 DG18
 '@T6G_MB_LIB.T6G(SCH_1):PAGE60_I3@PURE_QUANTA.GENOA_SP5(CHIPS)':
 'VSS_DG18': CDS_PINID='VSS_DG18';
NODE_NAME     U26 DG20
 '@T6G_MB_LIB.T6G(SCH_1):PAGE60_I3@PURE_QUANTA.GENOA_SP5(CHIPS)':
 'VSS_DG20': CDS_PINID='VSS_DG20';
NODE_NAME     U26 DG21
 '@T6G_MB_LIB.T6G(SCH_1):PAGE60_I3@PURE_QUANTA.GENOA_SP5(CHIPS)':
 'VSS_DG21': CDS_PINID='VSS_DG21';
NODE_NAME     U26 DG24
 '@T6G_MB_LIB.T6G(SCH_1):PAGE60_I3@PURE_QUANTA.GENOA_SP5(CHIPS)':
 'VSS_DG24': CDS_PINID='VSS_DG24';
NODE_NAME     U26 DG27
 '@T6G_MB_LIB.T6G(SCH_1):PAGE60_I3@PURE_QUANTA.GENOA_SP5(CHIPS)':
 'VSS_DG27': CDS_PINID='VSS_DG27';
NODE_NAME     U26 DG30
 '@T6G_MB_LIB.T6G(SCH_1):PAGE60_I3@PURE_QUANTA.GENOA_SP5(CHIPS)':
 'VSS_DG30': CDS_PINID='VSS_DG30';
NODE_NAME     U26 DG33
 '@T6G_MB_LIB.T6G(SCH_1):PAGE60_I3@PURE_QUANTA.GENOA_SP5(CHIPS)':
 'VSS_DG33': CDS_PINID='VSS_DG33';
NODE_NAME     U26 DG41
 '@T6G_MB_LIB.T6G(SCH_1):PAGE60_I3@PURE_QUANTA.GENOA_SP5(CHIPS)':
 'VSS_DG41': CDS_PINID='VSS_DG41';
NODE_NAME     U26 DG43
 '@T6G_MB_LIB.T6G(SCH_1):PAGE60_I3@PURE_QUANTA.GENOA_SP5(CHIPS)':
 'VSS_DG43': CDS_PINID='VSS_DG43';
NODE_NAME     U26 DG46
 '@T6G_MB_LIB.T6G(SCH_1):PAGE60_I3@PURE_QUANTA.GENOA_SP5(CHIPS)':
 'VSS_DG46': CDS_PINID='VSS_DG46';
NODE_NAME     U26 DG49
 '@T6G_MB_LIB.T6G(SCH_1):PAGE60_I3@PURE_QUANTA.GENOA_SP5(CHIPS)':
 'VSS_DG49': CDS_PINID='VSS_DG49';
NODE_NAME     U26 DG52
 '@T6G_MB_LIB.T6G(SCH_1):PAGE60_I3@PURE_QUANTA.GENOA_SP5(CHIPS)':
 'VSS_DG52': CDS_PINID='VSS_DG52';
NODE_NAME     U26 DG55
 '@T6G_MB_LIB.T6G(SCH_1):PAGE60_I3@PURE_QUANTA.GENOA_SP5(CHIPS)':
 'VSS_DG55': CDS_PINID='VSS_DG55';
NODE_NAME     U26 DG56
 '@T6G_MB_LIB.T6G(SCH_1):PAGE60_I3@PURE_QUANTA.GENOA_SP5(CHIPS)':
 'VSS_DG56': CDS_PINID='VSS_DG56';
NODE_NAME     U26 DG59
 '@T6G_MB_LIB.T6G(SCH_1):PAGE60_I3@PURE_QUANTA.GENOA_SP5(CHIPS)':
 'VSS_DG59': CDS_PINID='VSS_DG59';
NODE_NAME     U26 DG60
 '@T6G_MB_LIB.T6G(SCH_1):PAGE60_I3@PURE_QUANTA.GENOA_SP5(CHIPS)':
 'VSS_DG60': CDS_PINID='VSS_DG60';
NODE_NAME     U26 DG61
 '@T6G_MB_LIB.T6G(SCH_1):PAGE60_I3@PURE_QUANTA.GENOA_SP5(CHIPS)':
 'VSS_DG61': CDS_PINID='VSS_DG61';
NODE_NAME     U26 DG62
 '@T6G_MB_LIB.T6G(SCH_1):PAGE60_I3@PURE_QUANTA.GENOA_SP5(CHIPS)':
 'VSS_DG62': CDS_PINID='VSS_DG62';
NODE_NAME     U26 DG63
 '@T6G_MB_LIB.T6G(SCH_1):PAGE60_I3@PURE_QUANTA.GENOA_SP5(CHIPS)':
 'VSS_DG63': CDS_PINID='VSS_DG63';
NODE_NAME     U26 DG65
 '@T6G_MB_LIB.T6G(SCH_1):PAGE60_I3@PURE_QUANTA.GENOA_SP5(CHIPS)':
 'VSS_DG65': CDS_PINID='VSS_DG65';
NODE_NAME     U26 DG66
 '@T6G_MB_LIB.T6G(SCH_1):PAGE60_I3@PURE_QUANTA.GENOA_SP5(CHIPS)':
 'VSS_DG66': CDS_PINID='VSS_DG66';
NODE_NAME     U26 DG67
 '@T6G_MB_LIB.T6G(SCH_1):PAGE60_I3@PURE_QUANTA.GENOA_SP5(CHIPS)':
 'VSS_DG67': CDS_PINID='VSS_DG67';
NODE_NAME     U26 DG68
 '@T6G_MB_LIB.T6G(SCH_1):PAGE60_I3@PURE_QUANTA.GENOA_SP5(CHIPS)':
 'VSS_DG68': CDS_PINID='VSS_DG68';
NODE_NAME     U26 DG69
 '@T6G_MB_LIB.T6G(SCH_1):PAGE60_I3@PURE_QUANTA.GENOA_SP5(CHIPS)':
 'VSS_DG69': CDS_PINID='VSS_DG69';
NODE_NAME     U26 DG70
 '@T6G_MB_LIB.T6G(SCH_1):PAGE60_I3@PURE_QUANTA.GENOA_SP5(CHIPS)':
 'VSS_DG70': CDS_PINID='VSS_DG70';
NODE_NAME     U26 DG74
 '@T6G_MB_LIB.T6G(SCH_1):PAGE60_I3@PURE_QUANTA.GENOA_SP5(CHIPS)':
 'VSS_DG74': CDS_PINID='VSS_DG74';
NODE_NAME     U26 DG75
 '@T6G_MB_LIB.T6G(SCH_1):PAGE60_I3@PURE_QUANTA.GENOA_SP5(CHIPS)':
 'VSS_DG75': CDS_PINID='VSS_DG75';
NODE_NAME     U26 DH5
 '@T6G_MB_LIB.T6G(SCH_1):PAGE60_I3@PURE_QUANTA.GENOA_SP5(CHIPS)':
 'VSS_DH5': CDS_PINID='VSS_DH5';
NODE_NAME     U26 DH11
 '@T6G_MB_LIB.T6G(SCH_1):PAGE60_I3@PURE_QUANTA.GENOA_SP5(CHIPS)':
 'VSS_DH11': CDS_PINID='VSS_DH11';
NODE_NAME     U26 DH18
 '@T6G_MB_LIB.T6G(SCH_1):PAGE60_I3@PURE_QUANTA.GENOA_SP5(CHIPS)':
 'VSS_DH18': CDS_PINID='VSS_DH18';
NODE_NAME     U26 DH37
 '@T6G_MB_LIB.T6G(SCH_1):PAGE60_I3@PURE_QUANTA.GENOA_SP5(CHIPS)':
 'VSS_DH37': CDS_PINID='VSS_DH37';
NODE_NAME     U26 DH39
 '@T6G_MB_LIB.T6G(SCH_1):PAGE60_I3@PURE_QUANTA.GENOA_SP5(CHIPS)':
 'VSS_DH39': CDS_PINID='VSS_DH39';
NODE_NAME     U26 DH43
 '@T6G_MB_LIB.T6G(SCH_1):PAGE60_I3@PURE_QUANTA.GENOA_SP5(CHIPS)':
 'VSS_DH43': CDS_PINID='VSS_DH43';
NODE_NAME     U26 DH46
 '@T6G_MB_LIB.T6G(SCH_1):PAGE60_I3@PURE_QUANTA.GENOA_SP5(CHIPS)':
 'VSS_DH46': CDS_PINID='VSS_DH46';
NODE_NAME     U26 DH49
 '@T6G_MB_LIB.T6G(SCH_1):PAGE60_I3@PURE_QUANTA.GENOA_SP5(CHIPS)':
 'VSS_DH49': CDS_PINID='VSS_DH49';
NODE_NAME     U26 DH52
 '@T6G_MB_LIB.T6G(SCH_1):PAGE60_I3@PURE_QUANTA.GENOA_SP5(CHIPS)':
 'VSS_DH52': CDS_PINID='VSS_DH52';
NODE_NAME     U26 DH55
 '@T6G_MB_LIB.T6G(SCH_1):PAGE60_I3@PURE_QUANTA.GENOA_SP5(CHIPS)':
 'VSS_DH55': CDS_PINID='VSS_DH55';
NODE_NAME     U26 DH59
 '@T6G_MB_LIB.T6G(SCH_1):PAGE60_I3@PURE_QUANTA.GENOA_SP5(CHIPS)':
 'VSS_DH59': CDS_PINID='VSS_DH59';
NODE_NAME     U26 DH61
 '@T6G_MB_LIB.T6G(SCH_1):PAGE60_I3@PURE_QUANTA.GENOA_SP5(CHIPS)':
 'VSS_DH61': CDS_PINID='VSS_DH61';
NODE_NAME     U26 DH63
 '@T6G_MB_LIB.T6G(SCH_1):PAGE60_I3@PURE_QUANTA.GENOA_SP5(CHIPS)':
 'VSS_DH63': CDS_PINID='VSS_DH63';
NODE_NAME     U26 DH64
 '@T6G_MB_LIB.T6G(SCH_1):PAGE60_I3@PURE_QUANTA.GENOA_SP5(CHIPS)':
 'VSS_DH64': CDS_PINID='VSS_DH64';
NODE_NAME     U26 DH66
 '@T6G_MB_LIB.T6G(SCH_1):PAGE60_I3@PURE_QUANTA.GENOA_SP5(CHIPS)':
 'VSS_DH66': CDS_PINID='VSS_DH66';
NODE_NAME     U26 DH68
 '@T6G_MB_LIB.T6G(SCH_1):PAGE60_I3@PURE_QUANTA.GENOA_SP5(CHIPS)':
 'VSS_DH68': CDS_PINID='VSS_DH68';
NODE_NAME     U26 DH70
 '@T6G_MB_LIB.T6G(SCH_1):PAGE60_I3@PURE_QUANTA.GENOA_SP5(CHIPS)':
 'VSS_DH70': CDS_PINID='VSS_DH70';
NODE_NAME     U26 DJ7
 '@T6G_MB_LIB.T6G(SCH_1):PAGE60_I3@PURE_QUANTA.GENOA_SP5(CHIPS)':
 'VSS_DJ7': CDS_PINID='VSS_DJ7';
NODE_NAME     U26 DJ15
 '@T6G_MB_LIB.T6G(SCH_1):PAGE60_I3@PURE_QUANTA.GENOA_SP5(CHIPS)':
 'VSS_DJ15': CDS_PINID='VSS_DJ15';
NODE_NAME     U26 DJ19
 '@T6G_MB_LIB.T6G(SCH_1):PAGE60_I3@PURE_QUANTA.GENOA_SP5(CHIPS)':
 'VSS_DJ19': CDS_PINID='VSS_DJ19';
NODE_NAME     U26 DJ43
 '@T6G_MB_LIB.T6G(SCH_1):PAGE60_I3@PURE_QUANTA.GENOA_SP5(CHIPS)':
 'VSS_DJ43': CDS_PINID='VSS_DJ43';
NODE_NAME     U26 DJ49
 '@T6G_MB_LIB.T6G(SCH_1):PAGE60_I3@PURE_QUANTA.GENOA_SP5(CHIPS)':
 'VSS_DJ49': CDS_PINID='VSS_DJ49';
NODE_NAME     U26 DJ59
 '@T6G_MB_LIB.T6G(SCH_1):PAGE60_I3@PURE_QUANTA.GENOA_SP5(CHIPS)':
 'VSS_DJ59': CDS_PINID='VSS_DJ59';
NODE_NAME     U26 DJ61
 '@T6G_MB_LIB.T6G(SCH_1):PAGE60_I3@PURE_QUANTA.GENOA_SP5(CHIPS)':
 'VSS_DJ61': CDS_PINID='VSS_DJ61';
NODE_NAME     U26 DJ63
 '@T6G_MB_LIB.T6G(SCH_1):PAGE60_I3@PURE_QUANTA.GENOA_SP5(CHIPS)':
 'VSS_DJ63': CDS_PINID='VSS_DJ63';
NODE_NAME     U26 DJ66
 '@T6G_MB_LIB.T6G(SCH_1):PAGE60_I3@PURE_QUANTA.GENOA_SP5(CHIPS)':
 'VSS_DJ66': CDS_PINID='VSS_DJ66';
NODE_NAME     U26 DJ68
 '@T6G_MB_LIB.T6G(SCH_1):PAGE60_I3@PURE_QUANTA.GENOA_SP5(CHIPS)':
 'VSS_DJ68': CDS_PINID='VSS_DJ68';
NODE_NAME     U26 DJ73
 '@T6G_MB_LIB.T6G(SCH_1):PAGE60_I3@PURE_QUANTA.GENOA_SP5(CHIPS)':
 'VSS_DJ73': CDS_PINID='VSS_DJ73';
NODE_NAME     U26 K23
 '@T6G_MB_LIB.T6G(SCH_1):PAGE60_I3@PURE_QUANTA.GENOA_SP5(CHIPS)':
 'VSS_K23': CDS_PINID='VSS_K23';
NODE_NAME     U26 K59
 '@T6G_MB_LIB.T6G(SCH_1):PAGE60_I3@PURE_QUANTA.GENOA_SP5(CHIPS)':
 'VSS_K59': CDS_PINID='VSS_K59';
NODE_NAME     U26 P25
 '@T6G_MB_LIB.T6G(SCH_1):PAGE60_I3@PURE_QUANTA.GENOA_SP5(CHIPS)':
 'VSS_P25': CDS_PINID='VSS_P25';
NODE_NAME     U26 P68
 '@T6G_MB_LIB.T6G(SCH_1):PAGE60_I3@PURE_QUANTA.GENOA_SP5(CHIPS)':
 'VSS_P68': CDS_PINID='VSS_P68';
NODE_NAME     U26 V27
 '@T6G_MB_LIB.T6G(SCH_1):PAGE60_I3@PURE_QUANTA.GENOA_SP5(CHIPS)':
 'VSS_V27': CDS_PINID='VSS_V27';
NODE_NAME     U26 V68
 '@T6G_MB_LIB.T6G(SCH_1):PAGE60_I3@PURE_QUANTA.GENOA_SP5(CHIPS)':
 'VSS_V68': CDS_PINID='VSS_V68';
NODE_NAME     C3888 2
 '@T6G_MB_LIB.T6G(SCH_1):PAGE67_I83@PURE_QUANTA.Q_CAP(CHIPS)':
 'B': CDS_PINID='B';
NODE_NAME     C2130 2
 '@T6G_MB_LIB.T6G(SCH_1):PAGE67_I85@PURE_QUANTA.Q_CAP(CHIPS)':
 'B': CDS_PINID='B';
NODE_NAME     C3889 2
 '@T6G_MB_LIB.T6G(SCH_1):PAGE67_I86@PURE_QUANTA.Q_CAP(CHIPS)':
 'B': CDS_PINID='B';
NODE_NAME     C2135 2
 '@T6G_MB_LIB.T6G(SCH_1):PAGE67_I87@PURE_QUANTA.Q_CAP(CHIPS)':
 'B': CDS_PINID='B';
NODE_NAME     C2129 2
 '@T6G_MB_LIB.T6G(SCH_1):PAGE67_I89@PURE_QUANTA.Q_CAP(CHIPS)':
 'B': CDS_PINID='B';
NODE_NAME     C2134 2
 '@T6G_MB_LIB.T6G(SCH_1):PAGE67_I90@PURE_QUANTA.Q_CAP(CHIPS)':
 'B': CDS_PINID='B';
NODE_NAME     C2140 2
 '@T6G_MB_LIB.T6G(SCH_1):PAGE67_I92@PURE_QUANTA.Q_CAP(CHIPS)':
 'B': CDS_PINID='B';
NODE_NAME     C2144 2
 '@T6G_MB_LIB.T6G(SCH_1):PAGE67_I93@PURE_QUANTA.Q_CAP(CHIPS)':
 'B': CDS_PINID='B';
NODE_NAME     C2148 2
 '@T6G_MB_LIB.T6G(SCH_1):PAGE67_I94@PURE_QUANTA.Q_CAP(CHIPS)':
 'B': CDS_PINID='B';
NODE_NAME     C2139 2
 '@T6G_MB_LIB.T6G(SCH_1):PAGE67_I95@PURE_QUANTA.Q_CAP(CHIPS)':
 'B': CDS_PINID='B';
NODE_NAME     C2143 2
 '@T6G_MB_LIB.T6G(SCH_1):PAGE67_I96@PURE_QUANTA.Q_CAP(CHIPS)':
 'B': CDS_PINID='B';
NODE_NAME     C2152 2
 '@T6G_MB_LIB.T6G(SCH_1):PAGE67_I97@PURE_QUANTA.Q_CAP(CHIPS)':
 'B': CDS_PINID='B';
NODE_NAME     C2155 2
 '@T6G_MB_LIB.T6G(SCH_1):PAGE67_I98@PURE_QUANTA.Q_CAP(CHIPS)':
 'B': CDS_PINID='B';
NODE_NAME     C2151 2
 '@T6G_MB_LIB.T6G(SCH_1):PAGE67_I99@PURE_QUANTA.Q_CAP(CHIPS)':
 'B': CDS_PINID='B';
NODE_NAME     C2154 2
 '@T6G_MB_LIB.T6G(SCH_1):PAGE67_I100@PURE_QUANTA.Q_CAP(CHIPS)':
 'B': CDS_PINID='B';
NODE_NAME     C3894 2
 '@T6G_MB_LIB.T6G(SCH_1):PAGE67_I101@PURE_QUANTA.Q_CAP(CHIPS)':
 'B': CDS_PINID='B';
NODE_NAME     C3895 2
 '@T6G_MB_LIB.T6G(SCH_1):PAGE67_I102@PURE_QUANTA.Q_CAP(CHIPS)':
 'B': CDS_PINID='B';
NODE_NAME     C2157 2
 '@T6G_MB_LIB.T6G(SCH_1):PAGE67_I103@PURE_QUANTA.Q_CAP(CHIPS)':
 'B': CDS_PINID='B';
NODE_NAME     C2159 2
 '@T6G_MB_LIB.T6G(SCH_1):PAGE67_I104@PURE_QUANTA.Q_CAP(CHIPS)':
 'B': CDS_PINID='B';
NODE_NAME     C3896 2
 '@T6G_MB_LIB.T6G(SCH_1):PAGE67_I106@PURE_QUANTA.Q_CAP(CHIPS)':
 'B': CDS_PINID='B';
NODE_NAME     C2161 2
 '@T6G_MB_LIB.T6G(SCH_1):PAGE67_I108@PURE_QUANTA.Q_CAP(CHIPS)':
 'B': CDS_PINID='B';
NODE_NAME     C2147 2
 '@T6G_MB_LIB.T6G(SCH_1):PAGE67_I109@PURE_QUANTA.Q_CAP(CHIPS)':
 'B': CDS_PINID='B';
NODE_NAME     C2133 2
 '@T6G_MB_LIB.T6G(SCH_1):PAGE67_I110@PURE_QUANTA.Q_CAP(CHIPS)':
 'B': CDS_PINID='B';
NODE_NAME     C2138 2
 '@T6G_MB_LIB.T6G(SCH_1):PAGE67_I112@PURE_QUANTA.Q_CAP(CHIPS)':
 'B': CDS_PINID='B';
NODE_NAME     C2132 2
 '@T6G_MB_LIB.T6G(SCH_1):PAGE67_I113@PURE_QUANTA.Q_CAP(CHIPS)':
 'B': CDS_PINID='B';
NODE_NAME     C2137 2
 '@T6G_MB_LIB.T6G(SCH_1):PAGE67_I115@PURE_QUANTA.Q_CAP(CHIPS)':
 'B': CDS_PINID='B';
NODE_NAME     C3890 2
 '@T6G_MB_LIB.T6G(SCH_1):PAGE67_I116@PURE_QUANTA.Q_CAP(CHIPS)':
 'B': CDS_PINID='B';
NODE_NAME     C3891 2
 '@T6G_MB_LIB.T6G(SCH_1):PAGE67_I117@PURE_QUANTA.Q_CAP(CHIPS)':
 'B': CDS_PINID='B';
NODE_NAME     C3892 2
 '@T6G_MB_LIB.T6G(SCH_1):PAGE67_I118@PURE_QUANTA.Q_CAP(CHIPS)':
 'B': CDS_PINID='B';
NODE_NAME     C3893 2
 '@T6G_MB_LIB.T6G(SCH_1):PAGE67_I120@PURE_QUANTA.Q_CAP(CHIPS)':
 'B': CDS_PINID='B';
NODE_NAME     C2142 2
 '@T6G_MB_LIB.T6G(SCH_1):PAGE67_I121@PURE_QUANTA.Q_CAP(CHIPS)':
 'B': CDS_PINID='B';
NODE_NAME     C2146 2
 '@T6G_MB_LIB.T6G(SCH_1):PAGE67_I122@PURE_QUANTA.Q_CAP(CHIPS)':
 'B': CDS_PINID='B';
NODE_NAME     C2150 2
 '@T6G_MB_LIB.T6G(SCH_1):PAGE67_I123@PURE_QUANTA.Q_CAP(CHIPS)':
 'B': CDS_PINID='B';
NODE_NAME     C2153 2
 '@T6G_MB_LIB.T6G(SCH_1):PAGE67_I124@PURE_QUANTA.Q_CAP(CHIPS)':
 'B': CDS_PINID='B';
NODE_NAME     C2156 2
 '@T6G_MB_LIB.T6G(SCH_1):PAGE67_I125@PURE_QUANTA.Q_CAP(CHIPS)':
 'B': CDS_PINID='B';
NODE_NAME     C2158 2
 '@T6G_MB_LIB.T6G(SCH_1):PAGE67_I127@PURE_QUANTA.Q_CAP(CHIPS)':
 'B': CDS_PINID='B';
NODE_NAME     C2160 2
 '@T6G_MB_LIB.T6G(SCH_1):PAGE67_I128@PURE_QUANTA.Q_CAP(CHIPS)':
 'B': CDS_PINID='B';
NODE_NAME     C2162 2
 '@T6G_MB_LIB.T6G(SCH_1):PAGE67_I129@PURE_QUANTA.Q_CAP(CHIPS)':
 'B': CDS_PINID='B';
NODE_NAME     C2163 2
 '@T6G_MB_LIB.T6G(SCH_1):PAGE67_I131@PURE_QUANTA.Q_CAP(CHIPS)':
 'B': CDS_PINID='B';
NODE_NAME     C2164 2
 '@T6G_MB_LIB.T6G(SCH_1):PAGE67_I133@PURE_QUANTA.Q_CAP(CHIPS)':
 'B': CDS_PINID='B';
NODE_NAME     C3897 2
 '@T6G_MB_LIB.T6G(SCH_1):PAGE67_I134@PURE_QUANTA.Q_CAP(CHIPS)':
 'B': CDS_PINID='B';
NODE_NAME     C2131 2
 '@T6G_MB_LIB.T6G(SCH_1):PAGE67_I135@PURE_QUANTA.Q_CAP(CHIPS)':
 'B': CDS_PINID='B';
NODE_NAME     C2136 2
 '@T6G_MB_LIB.T6G(SCH_1):PAGE67_I136@PURE_QUANTA.Q_CAP(CHIPS)':
 'B': CDS_PINID='B';
NODE_NAME     C2141 2
 '@T6G_MB_LIB.T6G(SCH_1):PAGE67_I137@PURE_QUANTA.Q_CAP(CHIPS)':
 'B': CDS_PINID='B';
NODE_NAME     C2145 2
 '@T6G_MB_LIB.T6G(SCH_1):PAGE67_I138@PURE_QUANTA.Q_CAP(CHIPS)':
 'B': CDS_PINID='B';
NODE_NAME     C2149 2
 '@T6G_MB_LIB.T6G(SCH_1):PAGE67_I139@PURE_QUANTA.Q_CAP(CHIPS)':
 'B': CDS_PINID='B';
NODE_NAME     C3898 2
 '@T6G_MB_LIB.T6G(SCH_1):PAGE67_I141@PURE_QUANTA.Q_CAP(CHIPS)':
 'B': CDS_PINID='B';
NODE_NAME     C3899 2
 '@T6G_MB_LIB.T6G(SCH_1):PAGE67_I143@PURE_QUANTA.Q_CAP(CHIPS)':
 'B': CDS_PINID='B';
NODE_NAME     C2167 2
 '@T6G_MB_LIB.T6G(SCH_1):PAGE68_I1@PURE_QUANTA.Q_CAP(CHIPS)':
 'B': CDS_PINID='B';
NODE_NAME     C2171 2
 '@T6G_MB_LIB.T6G(SCH_1):PAGE68_I2@PURE_QUANTA.Q_CAP(CHIPS)':
 'B': CDS_PINID='B';
NODE_NAME     C2166 2
 '@T6G_MB_LIB.T6G(SCH_1):PAGE68_I4@PURE_QUANTA.Q_CAP(CHIPS)':
 'B': CDS_PINID='B';
NODE_NAME     C2170 2
 '@T6G_MB_LIB.T6G(SCH_1):PAGE68_I5@PURE_QUANTA.Q_CAP(CHIPS)':
 'B': CDS_PINID='B';
NODE_NAME     C2165 2
 '@T6G_MB_LIB.T6G(SCH_1):PAGE68_I7@PURE_QUANTA.Q_CAP(CHIPS)':
 'B': CDS_PINID='B';
NODE_NAME     C2169 2
 '@T6G_MB_LIB.T6G(SCH_1):PAGE68_I9@PURE_QUANTA.Q_CAP(CHIPS)':
 'B': CDS_PINID='B';
NODE_NAME     C246 2
 '@T6G_MB_LIB.T6G(SCH_1):PAGE68_I10@PURE_QUANTA.Q_CAP(CHIPS)':
 'B': CDS_PINID='B';
NODE_NAME     C252 2
 '@T6G_MB_LIB.T6G(SCH_1):PAGE68_I12@PURE_QUANTA.Q_CAP(CHIPS)':
 'B': CDS_PINID='B';
NODE_NAME     C245 2
 '@T6G_MB_LIB.T6G(SCH_1):PAGE68_I14@PURE_QUANTA.Q_CAP(CHIPS)':
 'B': CDS_PINID='B';
NODE_NAME     C251 2
 '@T6G_MB_LIB.T6G(SCH_1):PAGE68_I15@PURE_QUANTA.Q_CAP(CHIPS)':
 'B': CDS_PINID='B';
NODE_NAME     C2175 2
 '@T6G_MB_LIB.T6G(SCH_1):PAGE68_I16@PURE_QUANTA.Q_CAP(CHIPS)':
 'B': CDS_PINID='B';
NODE_NAME     C10179 2
 '@T6G_MB_LIB.T6G(SCH_1):PAGE68_I17@PURE_QUANTA.Q_CAP(CHIPS)':
 'B': CDS_PINID='B';
NODE_NAME     C2183 2
 '@T6G_MB_LIB.T6G(SCH_1):PAGE68_I19@PURE_QUANTA.Q_CAP(CHIPS)':
 'B': CDS_PINID='B';
NODE_NAME     C2174 2
 '@T6G_MB_LIB.T6G(SCH_1):PAGE68_I20@PURE_QUANTA.Q_CAP(CHIPS)':
 'B': CDS_PINID='B';
NODE_NAME     C2178 2
 '@T6G_MB_LIB.T6G(SCH_1):PAGE68_I21@PURE_QUANTA.Q_CAP(CHIPS)':
 'B': CDS_PINID='B';
NODE_NAME     C2173 2
 '@T6G_MB_LIB.T6G(SCH_1):PAGE68_I22@PURE_QUANTA.Q_CAP(CHIPS)':
 'B': CDS_PINID='B';
NODE_NAME     C2177 2
 '@T6G_MB_LIB.T6G(SCH_1):PAGE68_I23@PURE_QUANTA.Q_CAP(CHIPS)':
 'B': CDS_PINID='B';
NODE_NAME     C2182 2
 '@T6G_MB_LIB.T6G(SCH_1):PAGE68_I24@PURE_QUANTA.Q_CAP(CHIPS)':
 'B': CDS_PINID='B';
NODE_NAME     C2181 2
 '@T6G_MB_LIB.T6G(SCH_1):PAGE68_I25@PURE_QUANTA.Q_CAP(CHIPS)':
 'B': CDS_PINID='B';
NODE_NAME     C2186 2
 '@T6G_MB_LIB.T6G(SCH_1):PAGE68_I26@PURE_QUANTA.Q_CAP(CHIPS)':
 'B': CDS_PINID='B';
NODE_NAME     C2190 2
 '@T6G_MB_LIB.T6G(SCH_1):PAGE68_I27@PURE_QUANTA.Q_CAP(CHIPS)':
 'B': CDS_PINID='B';
NODE_NAME     C2185 2
 '@T6G_MB_LIB.T6G(SCH_1):PAGE68_I28@PURE_QUANTA.Q_CAP(CHIPS)':
 'B': CDS_PINID='B';
NODE_NAME     C2189 2
 '@T6G_MB_LIB.T6G(SCH_1):PAGE68_I29@PURE_QUANTA.Q_CAP(CHIPS)':
 'B': CDS_PINID='B';
NODE_NAME     C2205 2
 '@T6G_MB_LIB.T6G(SCH_1):PAGE68_I30@PURE_QUANTA.Q_CAP(CHIPS)':
 'B': CDS_PINID='B';
NODE_NAME     C2193 2
 '@T6G_MB_LIB.T6G(SCH_1):PAGE68_I31@PURE_QUANTA.Q_CAP(CHIPS)':
 'B': CDS_PINID='B';
NODE_NAME     C2196 2
 '@T6G_MB_LIB.T6G(SCH_1):PAGE68_I32@PURE_QUANTA.Q_CAP(CHIPS)':
 'B': CDS_PINID='B';
NODE_NAME     C2192 2
 '@T6G_MB_LIB.T6G(SCH_1):PAGE68_I33@PURE_QUANTA.Q_CAP(CHIPS)':
 'B': CDS_PINID='B';
NODE_NAME     C2195 2
 '@T6G_MB_LIB.T6G(SCH_1):PAGE68_I34@PURE_QUANTA.Q_CAP(CHIPS)':
 'B': CDS_PINID='B';
NODE_NAME     C2199 2
 '@T6G_MB_LIB.T6G(SCH_1):PAGE68_I36@PURE_QUANTA.Q_CAP(CHIPS)':
 'B': CDS_PINID='B';
NODE_NAME     C2204 2
 '@T6G_MB_LIB.T6G(SCH_1):PAGE68_I38@PURE_QUANTA.Q_CAP(CHIPS)':
 'B': CDS_PINID='B';
NODE_NAME     C2198 2
 '@T6G_MB_LIB.T6G(SCH_1):PAGE68_I40@PURE_QUANTA.Q_CAP(CHIPS)':
 'B': CDS_PINID='B';
NODE_NAME     C2203 2
 '@T6G_MB_LIB.T6G(SCH_1):PAGE68_I43@PURE_QUANTA.Q_CAP(CHIPS)':
 'B': CDS_PINID='B';
NODE_NAME     C1922 2
 '@T6G_MB_LIB.T6G(SCH_1):PAGE68_I45@PURE_QUANTA.Q_CAP(CHIPS)':
 'B': CDS_PINID='B';
NODE_NAME     C263 2
 '@T6G_MB_LIB.T6G(SCH_1):PAGE68_I46@PURE_QUANTA.Q_CAP(CHIPS)':
 'B': CDS_PINID='B';
NODE_NAME     C4178 2
 '@T6G_MB_LIB.T6G(SCH_1):PAGE68_I47@PURE_QUANTA.Q_CAP(CHIPS)':
 'B': CDS_PINID='B';
NODE_NAME     C4179 2
 '@T6G_MB_LIB.T6G(SCH_1):PAGE68_I48@PURE_QUANTA.Q_CAP(CHIPS)':
 'B': CDS_PINID='B';
NODE_NAME     C268 2
 '@T6G_MB_LIB.T6G(SCH_1):PAGE68_I49@PURE_QUANTA.Q_CAP(CHIPS)':
 'B': CDS_PINID='B';
NODE_NAME     C267 2
 '@T6G_MB_LIB.T6G(SCH_1):PAGE68_I50@PURE_QUANTA.Q_CAP(CHIPS)':
 'B': CDS_PINID='B';
NODE_NAME     C271 2
 '@T6G_MB_LIB.T6G(SCH_1):PAGE68_I51@PURE_QUANTA.Q_CAP(CHIPS)':
 'B': CDS_PINID='B';
NODE_NAME     C273 2
 '@T6G_MB_LIB.T6G(SCH_1):PAGE68_I52@PURE_QUANTA.Q_CAP(CHIPS)':
 'B': CDS_PINID='B';
NODE_NAME     C270 2
 '@T6G_MB_LIB.T6G(SCH_1):PAGE68_I53@PURE_QUANTA.Q_CAP(CHIPS)':
 'B': CDS_PINID='B';
NODE_NAME     C275 2
 '@T6G_MB_LIB.T6G(SCH_1):PAGE68_I54@PURE_QUANTA.Q_CAP(CHIPS)':
 'B': CDS_PINID='B';
NODE_NAME     C277 2
 '@T6G_MB_LIB.T6G(SCH_1):PAGE68_I55@PURE_QUANTA.Q_CAP(CHIPS)':
 'B': CDS_PINID='B';
NODE_NAME     C274 2
 '@T6G_MB_LIB.T6G(SCH_1):PAGE68_I56@PURE_QUANTA.Q_CAP(CHIPS)':
 'B': CDS_PINID='B';
NODE_NAME     C276 2
 '@T6G_MB_LIB.T6G(SCH_1):PAGE68_I57@PURE_QUANTA.Q_CAP(CHIPS)':
 'B': CDS_PINID='B';
NODE_NAME     C279 2
 '@T6G_MB_LIB.T6G(SCH_1):PAGE68_I58@PURE_QUANTA.Q_CAP(CHIPS)':
 'B': CDS_PINID='B';
NODE_NAME     C2202 2
 '@T6G_MB_LIB.T6G(SCH_1):PAGE68_I60@PURE_QUANTA.Q_CAP(CHIPS)':
 'B': CDS_PINID='B';
NODE_NAME     C278 2
 '@T6G_MB_LIB.T6G(SCH_1):PAGE68_I62@PURE_QUANTA.Q_CAP(CHIPS)':
 'B': CDS_PINID='B';
NODE_NAME     C2201 2
 '@T6G_MB_LIB.T6G(SCH_1):PAGE68_I63@PURE_QUANTA.Q_CAP(CHIPS)':
 'B': CDS_PINID='B';
NODE_NAME     C2211 2
 '@T6G_MB_LIB.T6G(SCH_1):PAGE68_I65@PURE_QUANTA.Q_CAP(CHIPS)':
 'B': CDS_PINID='B';
NODE_NAME     C2217 2
 '@T6G_MB_LIB.T6G(SCH_1):PAGE68_I66@PURE_QUANTA.Q_CAP(CHIPS)':
 'B': CDS_PINID='B';
NODE_NAME     C2223 2
 '@T6G_MB_LIB.T6G(SCH_1):PAGE68_I67@PURE_QUANTA.Q_CAP(CHIPS)':
 'B': CDS_PINID='B';
NODE_NAME     C2229 2
 '@T6G_MB_LIB.T6G(SCH_1):PAGE68_I69@PURE_QUANTA.Q_CAP(CHIPS)':
 'B': CDS_PINID='B';
NODE_NAME     C2210 2
 '@T6G_MB_LIB.T6G(SCH_1):PAGE68_I70@PURE_QUANTA.Q_CAP(CHIPS)':
 'B': CDS_PINID='B';
NODE_NAME     C2216 2
 '@T6G_MB_LIB.T6G(SCH_1):PAGE68_I71@PURE_QUANTA.Q_CAP(CHIPS)':
 'B': CDS_PINID='B';
NODE_NAME     C2209 2
 '@T6G_MB_LIB.T6G(SCH_1):PAGE68_I72@PURE_QUANTA.Q_CAP(CHIPS)':
 'B': CDS_PINID='B';
NODE_NAME     C2215 2
 '@T6G_MB_LIB.T6G(SCH_1):PAGE68_I73@PURE_QUANTA.Q_CAP(CHIPS)':
 'B': CDS_PINID='B';
NODE_NAME     C2222 2
 '@T6G_MB_LIB.T6G(SCH_1):PAGE68_I74@PURE_QUANTA.Q_CAP(CHIPS)':
 'B': CDS_PINID='B';
NODE_NAME     C2228 2
 '@T6G_MB_LIB.T6G(SCH_1):PAGE68_I75@PURE_QUANTA.Q_CAP(CHIPS)':
 'B': CDS_PINID='B';
NODE_NAME     C2234 2
 '@T6G_MB_LIB.T6G(SCH_1):PAGE68_I76@PURE_QUANTA.Q_CAP(CHIPS)':
 'B': CDS_PINID='B';
NODE_NAME     C2221 2
 '@T6G_MB_LIB.T6G(SCH_1):PAGE68_I77@PURE_QUANTA.Q_CAP(CHIPS)':
 'B': CDS_PINID='B';
NODE_NAME     C2227 2
 '@T6G_MB_LIB.T6G(SCH_1):PAGE68_I78@PURE_QUANTA.Q_CAP(CHIPS)':
 'B': CDS_PINID='B';
NODE_NAME     C2233 2
 '@T6G_MB_LIB.T6G(SCH_1):PAGE68_I79@PURE_QUANTA.Q_CAP(CHIPS)':
 'B': CDS_PINID='B';
NODE_NAME     C2240 2
 '@T6G_MB_LIB.T6G(SCH_1):PAGE68_I80@PURE_QUANTA.Q_CAP(CHIPS)':
 'B': CDS_PINID='B';
NODE_NAME     C2246 2
 '@T6G_MB_LIB.T6G(SCH_1):PAGE68_I81@PURE_QUANTA.Q_CAP(CHIPS)':
 'B': CDS_PINID='B';
NODE_NAME     C2239 2
 '@T6G_MB_LIB.T6G(SCH_1):PAGE68_I82@PURE_QUANTA.Q_CAP(CHIPS)':
 'B': CDS_PINID='B';
NODE_NAME     C2245 2
 '@T6G_MB_LIB.T6G(SCH_1):PAGE68_I83@PURE_QUANTA.Q_CAP(CHIPS)':
 'B': CDS_PINID='B';
NODE_NAME     C2251 2
 '@T6G_MB_LIB.T6G(SCH_1):PAGE68_I84@PURE_QUANTA.Q_CAP(CHIPS)':
 'B': CDS_PINID='B';
NODE_NAME     C2256 2
 '@T6G_MB_LIB.T6G(SCH_1):PAGE68_I86@PURE_QUANTA.Q_CAP(CHIPS)':
 'B': CDS_PINID='B';
NODE_NAME     C2250 2
 '@T6G_MB_LIB.T6G(SCH_1):PAGE68_I87@PURE_QUANTA.Q_CAP(CHIPS)':
 'B': CDS_PINID='B';
NODE_NAME     C2255 2
 '@T6G_MB_LIB.T6G(SCH_1):PAGE68_I89@PURE_QUANTA.Q_CAP(CHIPS)':
 'B': CDS_PINID='B';
NODE_NAME     C2208 2
 '@T6G_MB_LIB.T6G(SCH_1):PAGE68_I91@PURE_QUANTA.Q_CAP(CHIPS)':
 'B': CDS_PINID='B';
NODE_NAME     C2214 2
 '@T6G_MB_LIB.T6G(SCH_1):PAGE68_I92@PURE_QUANTA.Q_CAP(CHIPS)':
 'B': CDS_PINID='B';
NODE_NAME     C2207 2
 '@T6G_MB_LIB.T6G(SCH_1):PAGE68_I93@PURE_QUANTA.Q_CAP(CHIPS)':
 'B': CDS_PINID='B';
NODE_NAME     C2213 2
 '@T6G_MB_LIB.T6G(SCH_1):PAGE68_I94@PURE_QUANTA.Q_CAP(CHIPS)':
 'B': CDS_PINID='B';
NODE_NAME     C2220 2
 '@T6G_MB_LIB.T6G(SCH_1):PAGE68_I95@PURE_QUANTA.Q_CAP(CHIPS)':
 'B': CDS_PINID='B';
NODE_NAME     C2226 2
 '@T6G_MB_LIB.T6G(SCH_1):PAGE68_I96@PURE_QUANTA.Q_CAP(CHIPS)':
 'B': CDS_PINID='B';
NODE_NAME     C2232 2
 '@T6G_MB_LIB.T6G(SCH_1):PAGE68_I97@PURE_QUANTA.Q_CAP(CHIPS)':
 'B': CDS_PINID='B';
NODE_NAME     C2219 2
 '@T6G_MB_LIB.T6G(SCH_1):PAGE68_I98@PURE_QUANTA.Q_CAP(CHIPS)':
 'B': CDS_PINID='B';
NODE_NAME     C2225 2
 '@T6G_MB_LIB.T6G(SCH_1):PAGE68_I99@PURE_QUANTA.Q_CAP(CHIPS)':
 'B': CDS_PINID='B';
NODE_NAME     C2231 2
 '@T6G_MB_LIB.T6G(SCH_1):PAGE68_I100@PURE_QUANTA.Q_CAP(CHIPS)':
 'B': CDS_PINID='B';
NODE_NAME     C2238 2
 '@T6G_MB_LIB.T6G(SCH_1):PAGE68_I101@PURE_QUANTA.Q_CAP(CHIPS)':
 'B': CDS_PINID='B';
NODE_NAME     C2244 2
 '@T6G_MB_LIB.T6G(SCH_1):PAGE68_I102@PURE_QUANTA.Q_CAP(CHIPS)':
 'B': CDS_PINID='B';
NODE_NAME     C2237 2
 '@T6G_MB_LIB.T6G(SCH_1):PAGE68_I103@PURE_QUANTA.Q_CAP(CHIPS)':
 'B': CDS_PINID='B';
NODE_NAME     C2243 2
 '@T6G_MB_LIB.T6G(SCH_1):PAGE68_I104@PURE_QUANTA.Q_CAP(CHIPS)':
 'B': CDS_PINID='B';
NODE_NAME     C2249 2
 '@T6G_MB_LIB.T6G(SCH_1):PAGE68_I105@PURE_QUANTA.Q_CAP(CHIPS)':
 'B': CDS_PINID='B';
NODE_NAME     C2254 2
 '@T6G_MB_LIB.T6G(SCH_1):PAGE68_I106@PURE_QUANTA.Q_CAP(CHIPS)':
 'B': CDS_PINID='B';
NODE_NAME     C2248 2
 '@T6G_MB_LIB.T6G(SCH_1):PAGE68_I108@PURE_QUANTA.Q_CAP(CHIPS)':
 'B': CDS_PINID='B';
NODE_NAME     C2253 2
 '@T6G_MB_LIB.T6G(SCH_1):PAGE68_I109@PURE_QUANTA.Q_CAP(CHIPS)':
 'B': CDS_PINID='B';
NODE_NAME     C272 2
 '@T6G_MB_LIB.T6G(SCH_1):PAGE68_I110@PURE_QUANTA.Q_CAP(CHIPS)':
 'B': CDS_PINID='B';
NODE_NAME     C3925 2
 '@T6G_MB_LIB.T6G(SCH_1):PAGE69_I1@PURE_QUANTA.Q_CAP(CHIPS)':
 'B': CDS_PINID='B';
NODE_NAME     C3926 2
 '@T6G_MB_LIB.T6G(SCH_1):PAGE69_I3@PURE_QUANTA.Q_CAP(CHIPS)':
 'B': CDS_PINID='B';
NODE_NAME     C2533 2
 '@T6G_MB_LIB.T6G(SCH_1):PAGE69_I4@PURE_QUANTA.Q_CAP(CHIPS)':
 'B': CDS_PINID='B';
NODE_NAME     C2540 2
 '@T6G_MB_LIB.T6G(SCH_1):PAGE69_I6@PURE_QUANTA.Q_CAP(CHIPS)':
 'B': CDS_PINID='B';
NODE_NAME     C2532 2
 '@T6G_MB_LIB.T6G(SCH_1):PAGE69_I7@PURE_QUANTA.Q_CAP(CHIPS)':
 'B': CDS_PINID='B';
NODE_NAME     C2531 2
 '@T6G_MB_LIB.T6G(SCH_1):PAGE69_I9@PURE_QUANTA.Q_CAP(CHIPS)':
 'B': CDS_PINID='B';
NODE_NAME     C2539 2
 '@T6G_MB_LIB.T6G(SCH_1):PAGE69_I10@PURE_QUANTA.Q_CAP(CHIPS)':
 'B': CDS_PINID='B';
NODE_NAME     C2538 2
 '@T6G_MB_LIB.T6G(SCH_1):PAGE69_I11@PURE_QUANTA.Q_CAP(CHIPS)':
 'B': CDS_PINID='B';
NODE_NAME     C2530 2
 '@T6G_MB_LIB.T6G(SCH_1):PAGE69_I13@PURE_QUANTA.Q_CAP(CHIPS)':
 'B': CDS_PINID='B';
NODE_NAME     C2537 2
 '@T6G_MB_LIB.T6G(SCH_1):PAGE69_I15@PURE_QUANTA.Q_CAP(CHIPS)':
 'B': CDS_PINID='B';
NODE_NAME     C2529 2
 '@T6G_MB_LIB.T6G(SCH_1):PAGE69_I16@PURE_QUANTA.Q_CAP(CHIPS)':
 'B': CDS_PINID='B';
NODE_NAME     C2528 2
 '@T6G_MB_LIB.T6G(SCH_1):PAGE69_I18@PURE_QUANTA.Q_CAP(CHIPS)':
 'B': CDS_PINID='B';
NODE_NAME     C2536 2
 '@T6G_MB_LIB.T6G(SCH_1):PAGE69_I19@PURE_QUANTA.Q_CAP(CHIPS)':
 'B': CDS_PINID='B';
NODE_NAME     C2535 2
 '@T6G_MB_LIB.T6G(SCH_1):PAGE69_I20@PURE_QUANTA.Q_CAP(CHIPS)':
 'B': CDS_PINID='B';
NODE_NAME     C2527 2
 '@T6G_MB_LIB.T6G(SCH_1):PAGE69_I22@PURE_QUANTA.Q_CAP(CHIPS)':
 'B': CDS_PINID='B';
NODE_NAME     C2534 2
 '@T6G_MB_LIB.T6G(SCH_1):PAGE69_I24@PURE_QUANTA.Q_CAP(CHIPS)':
 'B': CDS_PINID='B';
NODE_NAME     C3927 2
 '@T6G_MB_LIB.T6G(SCH_1):PAGE69_I25@PURE_QUANTA.Q_CAP(CHIPS)':
 'B': CDS_PINID='B';
NODE_NAME     C3928 2
 '@T6G_MB_LIB.T6G(SCH_1):PAGE69_I26@PURE_QUANTA.Q_CAP(CHIPS)':
 'B': CDS_PINID='B';
NODE_NAME     C3929 2
 '@T6G_MB_LIB.T6G(SCH_1):PAGE69_I27@PURE_QUANTA.Q_CAP(CHIPS)':
 'B': CDS_PINID='B';
NODE_NAME     C2547 2
 '@T6G_MB_LIB.T6G(SCH_1):PAGE69_I28@PURE_QUANTA.Q_CAP(CHIPS)':
 'B': CDS_PINID='B';
NODE_NAME     C2554 2
 '@T6G_MB_LIB.T6G(SCH_1):PAGE69_I29@PURE_QUANTA.Q_CAP(CHIPS)':
 'B': CDS_PINID='B';
NODE_NAME     C2561 2
 '@T6G_MB_LIB.T6G(SCH_1):PAGE69_I30@PURE_QUANTA.Q_CAP(CHIPS)':
 'B': CDS_PINID='B';
NODE_NAME     C3930 2
 '@T6G_MB_LIB.T6G(SCH_1):PAGE69_I31@PURE_QUANTA.Q_CAP(CHIPS)':
 'B': CDS_PINID='B';
NODE_NAME     C3931 2
 '@T6G_MB_LIB.T6G(SCH_1):PAGE69_I33@PURE_QUANTA.Q_CAP(CHIPS)':
 'B': CDS_PINID='B';
NODE_NAME     C2568 2
 '@T6G_MB_LIB.T6G(SCH_1):PAGE69_I34@PURE_QUANTA.Q_CAP(CHIPS)':
 'B': CDS_PINID='B';
NODE_NAME     C2575 2
 '@T6G_MB_LIB.T6G(SCH_1):PAGE69_I35@PURE_QUANTA.Q_CAP(CHIPS)':
 'B': CDS_PINID='B';
NODE_NAME     C2546 2
 '@T6G_MB_LIB.T6G(SCH_1):PAGE69_I36@PURE_QUANTA.Q_CAP(CHIPS)':
 'B': CDS_PINID='B';
NODE_NAME     C2545 2
 '@T6G_MB_LIB.T6G(SCH_1):PAGE69_I37@PURE_QUANTA.Q_CAP(CHIPS)':
 'B': CDS_PINID='B';
NODE_NAME     C2553 2
 '@T6G_MB_LIB.T6G(SCH_1):PAGE69_I38@PURE_QUANTA.Q_CAP(CHIPS)':
 'B': CDS_PINID='B';
NODE_NAME     C2560 2
 '@T6G_MB_LIB.T6G(SCH_1):PAGE69_I39@PURE_QUANTA.Q_CAP(CHIPS)':
 'B': CDS_PINID='B';
NODE_NAME     C2552 2
 '@T6G_MB_LIB.T6G(SCH_1):PAGE69_I40@PURE_QUANTA.Q_CAP(CHIPS)':
 'B': CDS_PINID='B';
NODE_NAME     C2559 2
 '@T6G_MB_LIB.T6G(SCH_1):PAGE69_I41@PURE_QUANTA.Q_CAP(CHIPS)':
 'B': CDS_PINID='B';
NODE_NAME     C2544 2
 '@T6G_MB_LIB.T6G(SCH_1):PAGE69_I42@PURE_QUANTA.Q_CAP(CHIPS)':
 'B': CDS_PINID='B';
NODE_NAME     C2551 2
 '@T6G_MB_LIB.T6G(SCH_1):PAGE69_I43@PURE_QUANTA.Q_CAP(CHIPS)':
 'B': CDS_PINID='B';
NODE_NAME     C2558 2
 '@T6G_MB_LIB.T6G(SCH_1):PAGE69_I44@PURE_QUANTA.Q_CAP(CHIPS)':
 'B': CDS_PINID='B';
NODE_NAME     C2567 2
 '@T6G_MB_LIB.T6G(SCH_1):PAGE69_I45@PURE_QUANTA.Q_CAP(CHIPS)':
 'B': CDS_PINID='B';
NODE_NAME     C2566 2
 '@T6G_MB_LIB.T6G(SCH_1):PAGE69_I46@PURE_QUANTA.Q_CAP(CHIPS)':
 'B': CDS_PINID='B';
NODE_NAME     C2574 2
 '@T6G_MB_LIB.T6G(SCH_1):PAGE69_I47@PURE_QUANTA.Q_CAP(CHIPS)':
 'B': CDS_PINID='B';
NODE_NAME     C2573 2
 '@T6G_MB_LIB.T6G(SCH_1):PAGE69_I48@PURE_QUANTA.Q_CAP(CHIPS)':
 'B': CDS_PINID='B';
NODE_NAME     C2565 2
 '@T6G_MB_LIB.T6G(SCH_1):PAGE69_I49@PURE_QUANTA.Q_CAP(CHIPS)':
 'B': CDS_PINID='B';
NODE_NAME     C2572 2
 '@T6G_MB_LIB.T6G(SCH_1):PAGE69_I50@PURE_QUANTA.Q_CAP(CHIPS)':
 'B': CDS_PINID='B';
NODE_NAME     C2582 2
 '@T6G_MB_LIB.T6G(SCH_1):PAGE69_I51@PURE_QUANTA.Q_CAP(CHIPS)':
 'B': CDS_PINID='B';
NODE_NAME     C2589 2
 '@T6G_MB_LIB.T6G(SCH_1):PAGE69_I52@PURE_QUANTA.Q_CAP(CHIPS)':
 'B': CDS_PINID='B';
NODE_NAME     C3932 2
 '@T6G_MB_LIB.T6G(SCH_1):PAGE69_I53@PURE_QUANTA.Q_CAP(CHIPS)':
 'B': CDS_PINID='B';
NODE_NAME     C2596 2
 '@T6G_MB_LIB.T6G(SCH_1):PAGE69_I56@PURE_QUANTA.Q_CAP(CHIPS)':
 'B': CDS_PINID='B';
NODE_NAME     C2603 2
 '@T6G_MB_LIB.T6G(SCH_1):PAGE69_I58@PURE_QUANTA.Q_CAP(CHIPS)':
 'B': CDS_PINID='B';
NODE_NAME     C2602 2
 '@T6G_MB_LIB.T6G(SCH_1):PAGE69_I60@PURE_QUANTA.Q_CAP(CHIPS)':
 'B': CDS_PINID='B';
NODE_NAME     C2581 2
 '@T6G_MB_LIB.T6G(SCH_1):PAGE69_I61@PURE_QUANTA.Q_CAP(CHIPS)':
 'B': CDS_PINID='B';
NODE_NAME     C2580 2
 '@T6G_MB_LIB.T6G(SCH_1):PAGE69_I62@PURE_QUANTA.Q_CAP(CHIPS)':
 'B': CDS_PINID='B';
NODE_NAME     C2588 2
 '@T6G_MB_LIB.T6G(SCH_1):PAGE69_I63@PURE_QUANTA.Q_CAP(CHIPS)':
 'B': CDS_PINID='B';
NODE_NAME     C2587 2
 '@T6G_MB_LIB.T6G(SCH_1):PAGE69_I64@PURE_QUANTA.Q_CAP(CHIPS)':
 'B': CDS_PINID='B';
NODE_NAME     C2579 2
 '@T6G_MB_LIB.T6G(SCH_1):PAGE69_I65@PURE_QUANTA.Q_CAP(CHIPS)':
 'B': CDS_PINID='B';
NODE_NAME     C2586 2
 '@T6G_MB_LIB.T6G(SCH_1):PAGE69_I66@PURE_QUANTA.Q_CAP(CHIPS)':
 'B': CDS_PINID='B';
NODE_NAME     C2595 2
 '@T6G_MB_LIB.T6G(SCH_1):PAGE69_I67@PURE_QUANTA.Q_CAP(CHIPS)':
 'B': CDS_PINID='B';
NODE_NAME     C2594 2
 '@T6G_MB_LIB.T6G(SCH_1):PAGE69_I69@PURE_QUANTA.Q_CAP(CHIPS)':
 'B': CDS_PINID='B';
NODE_NAME     C2601 2
 '@T6G_MB_LIB.T6G(SCH_1):PAGE69_I71@PURE_QUANTA.Q_CAP(CHIPS)':
 'B': CDS_PINID='B';
NODE_NAME     C2593 2
 '@T6G_MB_LIB.T6G(SCH_1):PAGE69_I74@PURE_QUANTA.Q_CAP(CHIPS)':
 'B': CDS_PINID='B';
NODE_NAME     C2600 2
 '@T6G_MB_LIB.T6G(SCH_1):PAGE69_I76@PURE_QUANTA.Q_CAP(CHIPS)':
 'B': CDS_PINID='B';
NODE_NAME     C2543 2
 '@T6G_MB_LIB.T6G(SCH_1):PAGE69_I78@PURE_QUANTA.Q_CAP(CHIPS)':
 'B': CDS_PINID='B';
NODE_NAME     C2542 2
 '@T6G_MB_LIB.T6G(SCH_1):PAGE69_I79@PURE_QUANTA.Q_CAP(CHIPS)':
 'B': CDS_PINID='B';
NODE_NAME     C2550 2
 '@T6G_MB_LIB.T6G(SCH_1):PAGE69_I80@PURE_QUANTA.Q_CAP(CHIPS)':
 'B': CDS_PINID='B';
NODE_NAME     C2549 2
 '@T6G_MB_LIB.T6G(SCH_1):PAGE69_I81@PURE_QUANTA.Q_CAP(CHIPS)':
 'B': CDS_PINID='B';
NODE_NAME     C2557 2
 '@T6G_MB_LIB.T6G(SCH_1):PAGE69_I82@PURE_QUANTA.Q_CAP(CHIPS)':
 'B': CDS_PINID='B';
NODE_NAME     C2556 2
 '@T6G_MB_LIB.T6G(SCH_1):PAGE69_I83@PURE_QUANTA.Q_CAP(CHIPS)':
 'B': CDS_PINID='B';
NODE_NAME     C2541 2
 '@T6G_MB_LIB.T6G(SCH_1):PAGE69_I84@PURE_QUANTA.Q_CAP(CHIPS)':
 'B': CDS_PINID='B';
NODE_NAME     C2548 2
 '@T6G_MB_LIB.T6G(SCH_1):PAGE69_I85@PURE_QUANTA.Q_CAP(CHIPS)':
 'B': CDS_PINID='B';
NODE_NAME     C2555 2
 '@T6G_MB_LIB.T6G(SCH_1):PAGE69_I86@PURE_QUANTA.Q_CAP(CHIPS)':
 'B': CDS_PINID='B';
NODE_NAME     C2564 2
 '@T6G_MB_LIB.T6G(SCH_1):PAGE69_I87@PURE_QUANTA.Q_CAP(CHIPS)':
 'B': CDS_PINID='B';
NODE_NAME     C2563 2
 '@T6G_MB_LIB.T6G(SCH_1):PAGE69_I88@PURE_QUANTA.Q_CAP(CHIPS)':
 'B': CDS_PINID='B';
NODE_NAME     C2571 2
 '@T6G_MB_LIB.T6G(SCH_1):PAGE69_I89@PURE_QUANTA.Q_CAP(CHIPS)':
 'B': CDS_PINID='B';
NODE_NAME     C2570 2
 '@T6G_MB_LIB.T6G(SCH_1):PAGE69_I90@PURE_QUANTA.Q_CAP(CHIPS)':
 'B': CDS_PINID='B';
NODE_NAME     C2562 2
 '@T6G_MB_LIB.T6G(SCH_1):PAGE69_I91@PURE_QUANTA.Q_CAP(CHIPS)':
 'B': CDS_PINID='B';
NODE_NAME     C2569 2
 '@T6G_MB_LIB.T6G(SCH_1):PAGE69_I92@PURE_QUANTA.Q_CAP(CHIPS)':
 'B': CDS_PINID='B';
NODE_NAME     C2578 2
 '@T6G_MB_LIB.T6G(SCH_1):PAGE69_I93@PURE_QUANTA.Q_CAP(CHIPS)':
 'B': CDS_PINID='B';
NODE_NAME     C2577 2
 '@T6G_MB_LIB.T6G(SCH_1):PAGE69_I94@PURE_QUANTA.Q_CAP(CHIPS)':
 'B': CDS_PINID='B';
NODE_NAME     C2585 2
 '@T6G_MB_LIB.T6G(SCH_1):PAGE69_I95@PURE_QUANTA.Q_CAP(CHIPS)':
 'B': CDS_PINID='B';
NODE_NAME     C2584 2
 '@T6G_MB_LIB.T6G(SCH_1):PAGE69_I96@PURE_QUANTA.Q_CAP(CHIPS)':
 'B': CDS_PINID='B';
NODE_NAME     C2576 2
 '@T6G_MB_LIB.T6G(SCH_1):PAGE69_I97@PURE_QUANTA.Q_CAP(CHIPS)':
 'B': CDS_PINID='B';
NODE_NAME     C2583 2
 '@T6G_MB_LIB.T6G(SCH_1):PAGE69_I98@PURE_QUANTA.Q_CAP(CHIPS)':
 'B': CDS_PINID='B';
NODE_NAME     C2592 2
 '@T6G_MB_LIB.T6G(SCH_1):PAGE69_I99@PURE_QUANTA.Q_CAP(CHIPS)':
 'B': CDS_PINID='B';
NODE_NAME     C2591 2
 '@T6G_MB_LIB.T6G(SCH_1):PAGE69_I101@PURE_QUANTA.Q_CAP(CHIPS)':
 'B': CDS_PINID='B';
NODE_NAME     C2599 2
 '@T6G_MB_LIB.T6G(SCH_1):PAGE69_I102@PURE_QUANTA.Q_CAP(CHIPS)':
 'B': CDS_PINID='B';
NODE_NAME     C2598 2
 '@T6G_MB_LIB.T6G(SCH_1):PAGE69_I104@PURE_QUANTA.Q_CAP(CHIPS)':
 'B': CDS_PINID='B';
NODE_NAME     C2590 2
 '@T6G_MB_LIB.T6G(SCH_1):PAGE69_I106@PURE_QUANTA.Q_CAP(CHIPS)':
 'B': CDS_PINID='B';
NODE_NAME     C2597 2
 '@T6G_MB_LIB.T6G(SCH_1):PAGE69_I108@PURE_QUANTA.Q_CAP(CHIPS)':
 'B': CDS_PINID='B';
NODE_NAME     C3933 2
 '@T6G_MB_LIB.T6G(SCH_1):PAGE69_I111@PURE_QUANTA.Q_CAP(CHIPS)':
 'B': CDS_PINID='B';
NODE_NAME     C2610 2
 '@T6G_MB_LIB.T6G(SCH_1):PAGE69_I112@PURE_QUANTA.Q_CAP(CHIPS)':
 'B': CDS_PINID='B';
NODE_NAME     C2609 2
 '@T6G_MB_LIB.T6G(SCH_1):PAGE69_I113@PURE_QUANTA.Q_CAP(CHIPS)':
 'B': CDS_PINID='B';
NODE_NAME     C2617 2
 '@T6G_MB_LIB.T6G(SCH_1):PAGE69_I114@PURE_QUANTA.Q_CAP(CHIPS)':
 'B': CDS_PINID='B';
NODE_NAME     C2616 2
 '@T6G_MB_LIB.T6G(SCH_1):PAGE69_I115@PURE_QUANTA.Q_CAP(CHIPS)':
 'B': CDS_PINID='B';
NODE_NAME     C2624 2
 '@T6G_MB_LIB.T6G(SCH_1):PAGE69_I116@PURE_QUANTA.Q_CAP(CHIPS)':
 'B': CDS_PINID='B';
NODE_NAME     C2623 2
 '@T6G_MB_LIB.T6G(SCH_1):PAGE69_I117@PURE_QUANTA.Q_CAP(CHIPS)':
 'B': CDS_PINID='B';
NODE_NAME     C2630 2
 '@T6G_MB_LIB.T6G(SCH_1):PAGE69_I118@PURE_QUANTA.Q_CAP(CHIPS)':
 'B': CDS_PINID='B';
NODE_NAME     C2629 2
 '@T6G_MB_LIB.T6G(SCH_1):PAGE69_I119@PURE_QUANTA.Q_CAP(CHIPS)':
 'B': CDS_PINID='B';
NODE_NAME     C2636 2
 '@T6G_MB_LIB.T6G(SCH_1):PAGE69_I120@PURE_QUANTA.Q_CAP(CHIPS)':
 'B': CDS_PINID='B';
NODE_NAME     C2635 2
 '@T6G_MB_LIB.T6G(SCH_1):PAGE69_I121@PURE_QUANTA.Q_CAP(CHIPS)':
 'B': CDS_PINID='B';
NODE_NAME     C2608 2
 '@T6G_MB_LIB.T6G(SCH_1):PAGE69_I122@PURE_QUANTA.Q_CAP(CHIPS)':
 'B': CDS_PINID='B';
NODE_NAME     C2615 2
 '@T6G_MB_LIB.T6G(SCH_1):PAGE69_I123@PURE_QUANTA.Q_CAP(CHIPS)':
 'B': CDS_PINID='B';
NODE_NAME     C2607 2
 '@T6G_MB_LIB.T6G(SCH_1):PAGE69_I124@PURE_QUANTA.Q_CAP(CHIPS)':
 'B': CDS_PINID='B';
NODE_NAME     C2614 2
 '@T6G_MB_LIB.T6G(SCH_1):PAGE69_I125@PURE_QUANTA.Q_CAP(CHIPS)':
 'B': CDS_PINID='B';
NODE_NAME     C2622 2
 '@T6G_MB_LIB.T6G(SCH_1):PAGE69_I126@PURE_QUANTA.Q_CAP(CHIPS)':
 'B': CDS_PINID='B';
NODE_NAME     C2621 2
 '@T6G_MB_LIB.T6G(SCH_1):PAGE69_I127@PURE_QUANTA.Q_CAP(CHIPS)':
 'B': CDS_PINID='B';
NODE_NAME     C2628 2
 '@T6G_MB_LIB.T6G(SCH_1):PAGE69_I129@PURE_QUANTA.Q_CAP(CHIPS)':
 'B': CDS_PINID='B';
NODE_NAME     C2634 2
 '@T6G_MB_LIB.T6G(SCH_1):PAGE69_I130@PURE_QUANTA.Q_CAP(CHIPS)':
 'B': CDS_PINID='B';
NODE_NAME     C2627 2
 '@T6G_MB_LIB.T6G(SCH_1):PAGE69_I131@PURE_QUANTA.Q_CAP(CHIPS)':
 'B': CDS_PINID='B';
NODE_NAME     C2633 2
 '@T6G_MB_LIB.T6G(SCH_1):PAGE69_I132@PURE_QUANTA.Q_CAP(CHIPS)':
 'B': CDS_PINID='B';
NODE_NAME     C2642 2
 '@T6G_MB_LIB.T6G(SCH_1):PAGE69_I133@PURE_QUANTA.Q_CAP(CHIPS)':
 'B': CDS_PINID='B';
NODE_NAME     C2641 2
 '@T6G_MB_LIB.T6G(SCH_1):PAGE69_I134@PURE_QUANTA.Q_CAP(CHIPS)':
 'B': CDS_PINID='B';
NODE_NAME     C2648 2
 '@T6G_MB_LIB.T6G(SCH_1):PAGE69_I135@PURE_QUANTA.Q_CAP(CHIPS)':
 'B': CDS_PINID='B';
NODE_NAME     C2647 2
 '@T6G_MB_LIB.T6G(SCH_1):PAGE69_I136@PURE_QUANTA.Q_CAP(CHIPS)':
 'B': CDS_PINID='B';
NODE_NAME     C3934 2
 '@T6G_MB_LIB.T6G(SCH_1):PAGE69_I138@PURE_QUANTA.Q_CAP(CHIPS)':
 'B': CDS_PINID='B';
NODE_NAME     C2653 2
 '@T6G_MB_LIB.T6G(SCH_1):PAGE69_I139@PURE_QUANTA.Q_CAP(CHIPS)':
 'B': CDS_PINID='B';
NODE_NAME     C3935 2
 '@T6G_MB_LIB.T6G(SCH_1):PAGE69_I140@PURE_QUANTA.Q_CAP(CHIPS)':
 'B': CDS_PINID='B';
NODE_NAME     C2658 2
 '@T6G_MB_LIB.T6G(SCH_1):PAGE69_I142@PURE_QUANTA.Q_CAP(CHIPS)':
 'B': CDS_PINID='B';
NODE_NAME     C2640 2
 '@T6G_MB_LIB.T6G(SCH_1):PAGE69_I143@PURE_QUANTA.Q_CAP(CHIPS)':
 'B': CDS_PINID='B';
NODE_NAME     C2646 2
 '@T6G_MB_LIB.T6G(SCH_1):PAGE69_I144@PURE_QUANTA.Q_CAP(CHIPS)':
 'B': CDS_PINID='B';
NODE_NAME     C2639 2
 '@T6G_MB_LIB.T6G(SCH_1):PAGE69_I145@PURE_QUANTA.Q_CAP(CHIPS)':
 'B': CDS_PINID='B';
NODE_NAME     C2645 2
 '@T6G_MB_LIB.T6G(SCH_1):PAGE69_I146@PURE_QUANTA.Q_CAP(CHIPS)':
 'B': CDS_PINID='B';
NODE_NAME     C2652 2
 '@T6G_MB_LIB.T6G(SCH_1):PAGE69_I147@PURE_QUANTA.Q_CAP(CHIPS)':
 'B': CDS_PINID='B';
NODE_NAME     C2657 2
 '@T6G_MB_LIB.T6G(SCH_1):PAGE69_I149@PURE_QUANTA.Q_CAP(CHIPS)':
 'B': CDS_PINID='B';
NODE_NAME     C2651 2
 '@T6G_MB_LIB.T6G(SCH_1):PAGE69_I151@PURE_QUANTA.Q_CAP(CHIPS)':
 'B': CDS_PINID='B';
NODE_NAME     C2656 2
 '@T6G_MB_LIB.T6G(SCH_1):PAGE69_I152@PURE_QUANTA.Q_CAP(CHIPS)':
 'B': CDS_PINID='B';
NODE_NAME     C2606 2
 '@T6G_MB_LIB.T6G(SCH_1):PAGE69_I153@PURE_QUANTA.Q_CAP(CHIPS)':
 'B': CDS_PINID='B';
NODE_NAME     C2605 2
 '@T6G_MB_LIB.T6G(SCH_1):PAGE69_I154@PURE_QUANTA.Q_CAP(CHIPS)':
 'B': CDS_PINID='B';
NODE_NAME     C2613 2
 '@T6G_MB_LIB.T6G(SCH_1):PAGE69_I155@PURE_QUANTA.Q_CAP(CHIPS)':
 'B': CDS_PINID='B';
NODE_NAME     C2612 2
 '@T6G_MB_LIB.T6G(SCH_1):PAGE69_I156@PURE_QUANTA.Q_CAP(CHIPS)':
 'B': CDS_PINID='B';
NODE_NAME     C2619 2
 '@T6G_MB_LIB.T6G(SCH_1):PAGE69_I157@PURE_QUANTA.Q_CAP(CHIPS)':
 'B': CDS_PINID='B';
NODE_NAME     C2604 2
 '@T6G_MB_LIB.T6G(SCH_1):PAGE69_I158@PURE_QUANTA.Q_CAP(CHIPS)':
 'B': CDS_PINID='B';
NODE_NAME     C2611 2
 '@T6G_MB_LIB.T6G(SCH_1):PAGE69_I159@PURE_QUANTA.Q_CAP(CHIPS)':
 'B': CDS_PINID='B';
NODE_NAME     C2618 2
 '@T6G_MB_LIB.T6G(SCH_1):PAGE69_I160@PURE_QUANTA.Q_CAP(CHIPS)':
 'B': CDS_PINID='B';
NODE_NAME     C2620 2
 '@T6G_MB_LIB.T6G(SCH_1):PAGE69_I161@PURE_QUANTA.Q_CAP(CHIPS)':
 'B': CDS_PINID='B';
NODE_NAME     C2626 2
 '@T6G_MB_LIB.T6G(SCH_1):PAGE69_I162@PURE_QUANTA.Q_CAP(CHIPS)':
 'B': CDS_PINID='B';
NODE_NAME     C2632 2
 '@T6G_MB_LIB.T6G(SCH_1):PAGE69_I163@PURE_QUANTA.Q_CAP(CHIPS)':
 'B': CDS_PINID='B';
NODE_NAME     C2625 2
 '@T6G_MB_LIB.T6G(SCH_1):PAGE69_I164@PURE_QUANTA.Q_CAP(CHIPS)':
 'B': CDS_PINID='B';
NODE_NAME     C2631 2
 '@T6G_MB_LIB.T6G(SCH_1):PAGE69_I165@PURE_QUANTA.Q_CAP(CHIPS)':
 'B': CDS_PINID='B';
NODE_NAME     C2638 2
 '@T6G_MB_LIB.T6G(SCH_1):PAGE69_I166@PURE_QUANTA.Q_CAP(CHIPS)':
 'B': CDS_PINID='B';
NODE_NAME     C2644 2
 '@T6G_MB_LIB.T6G(SCH_1):PAGE69_I167@PURE_QUANTA.Q_CAP(CHIPS)':
 'B': CDS_PINID='B';
NODE_NAME     C2637 2
 '@T6G_MB_LIB.T6G(SCH_1):PAGE69_I168@PURE_QUANTA.Q_CAP(CHIPS)':
 'B': CDS_PINID='B';
NODE_NAME     C2643 2
 '@T6G_MB_LIB.T6G(SCH_1):PAGE69_I169@PURE_QUANTA.Q_CAP(CHIPS)':
 'B': CDS_PINID='B';
NODE_NAME     C2650 2
 '@T6G_MB_LIB.T6G(SCH_1):PAGE69_I170@PURE_QUANTA.Q_CAP(CHIPS)':
 'B': CDS_PINID='B';
NODE_NAME     C2655 2
 '@T6G_MB_LIB.T6G(SCH_1):PAGE69_I172@PURE_QUANTA.Q_CAP(CHIPS)':
 'B': CDS_PINID='B';
NODE_NAME     C2649 2
 '@T6G_MB_LIB.T6G(SCH_1):PAGE69_I173@PURE_QUANTA.Q_CAP(CHIPS)':
 'B': CDS_PINID='B';
NODE_NAME     C2654 2
 '@T6G_MB_LIB.T6G(SCH_1):PAGE69_I175@PURE_QUANTA.Q_CAP(CHIPS)':
 'B': CDS_PINID='B';
NODE_NAME     C2514 2
 '@T6G_MB_LIB.T6G(SCH_1):PAGE70_I1@PURE_QUANTA.Q_CAP(CHIPS)':
 'B': CDS_PINID='B';
NODE_NAME     C2513 2
 '@T6G_MB_LIB.T6G(SCH_1):PAGE70_I3@PURE_QUANTA.Q_CAP(CHIPS)':
 'B': CDS_PINID='B';
NODE_NAME     C2517 2
 '@T6G_MB_LIB.T6G(SCH_1):PAGE70_I8@PURE_QUANTA.Q_CAP(CHIPS)':
 'B': CDS_PINID='B';
NODE_NAME     C2516 2
 '@T6G_MB_LIB.T6G(SCH_1):PAGE70_I9@PURE_QUANTA.Q_CAP(CHIPS)':
 'B': CDS_PINID='B';
NODE_NAME     C2518 2
 '@T6G_MB_LIB.T6G(SCH_1):PAGE70_I10@PURE_QUANTA.Q_CAP(CHIPS)':
 'B': CDS_PINID='B';
NODE_NAME     C2520 2
 '@T6G_MB_LIB.T6G(SCH_1):PAGE70_I11@PURE_QUANTA.Q_CAP(CHIPS)':
 'B': CDS_PINID='B';
NODE_NAME     C2521 2
 '@T6G_MB_LIB.T6G(SCH_1):PAGE70_I12@PURE_QUANTA.Q_CAP(CHIPS)':
 'B': CDS_PINID='B';
NODE_NAME     C2522 2
 '@T6G_MB_LIB.T6G(SCH_1):PAGE70_I13@PURE_QUANTA.Q_CAP(CHIPS)':
 'B': CDS_PINID='B';
NODE_NAME     C2523 2
 '@T6G_MB_LIB.T6G(SCH_1):PAGE70_I14@PURE_QUANTA.Q_CAP(CHIPS)':
 'B': CDS_PINID='B';
NODE_NAME     C2524 2
 '@T6G_MB_LIB.T6G(SCH_1):PAGE70_I15@PURE_QUANTA.Q_CAP(CHIPS)':
 'B': CDS_PINID='B';
NODE_NAME     C2525 2
 '@T6G_MB_LIB.T6G(SCH_1):PAGE70_I16@PURE_QUANTA.Q_CAP(CHIPS)':
 'B': CDS_PINID='B';
NODE_NAME     C2526 2
 '@T6G_MB_LIB.T6G(SCH_1):PAGE70_I18@PURE_QUANTA.Q_CAP(CHIPS)':
 'B': CDS_PINID='B';
NODE_NAME     C2262 2
 '@T6G_MB_LIB.T6G(SCH_1):PAGE71_I1@PURE_QUANTA.Q_CAP(CHIPS)':
 'B': CDS_PINID='B';
NODE_NAME     C2261 2
 '@T6G_MB_LIB.T6G(SCH_1):PAGE71_I3@PURE_QUANTA.Q_CAP(CHIPS)':
 'B': CDS_PINID='B';
NODE_NAME     C3900 2
 '@T6G_MB_LIB.T6G(SCH_1):PAGE71_I5@PURE_QUANTA.Q_CAP(CHIPS)':
 'B': CDS_PINID='B';
NODE_NAME     C2259 2
 '@T6G_MB_LIB.T6G(SCH_1):PAGE71_I7@PURE_QUANTA.Q_CAP(CHIPS)':
 'B': CDS_PINID='B';
NODE_NAME     C2258 2
 '@T6G_MB_LIB.T6G(SCH_1):PAGE71_I9@PURE_QUANTA.Q_CAP(CHIPS)':
 'B': CDS_PINID='B';
NODE_NAME     C2267 2
 '@T6G_MB_LIB.T6G(SCH_1):PAGE71_I11@PURE_QUANTA.Q_CAP(CHIPS)':
 'B': CDS_PINID='B';
NODE_NAME     C3902 2
 '@T6G_MB_LIB.T6G(SCH_1):PAGE71_I12@PURE_QUANTA.Q_CAP(CHIPS)':
 'B': CDS_PINID='B';
NODE_NAME     C2266 2
 '@T6G_MB_LIB.T6G(SCH_1):PAGE71_I13@PURE_QUANTA.Q_CAP(CHIPS)':
 'B': CDS_PINID='B';
NODE_NAME     C2271 2
 '@T6G_MB_LIB.T6G(SCH_1):PAGE71_I14@PURE_QUANTA.Q_CAP(CHIPS)':
 'B': CDS_PINID='B';
NODE_NAME     C3903 2
 '@T6G_MB_LIB.T6G(SCH_1):PAGE71_I15@PURE_QUANTA.Q_CAP(CHIPS)':
 'B': CDS_PINID='B';
NODE_NAME     C3904 2
 '@T6G_MB_LIB.T6G(SCH_1):PAGE71_I16@PURE_QUANTA.Q_CAP(CHIPS)':
 'B': CDS_PINID='B';
NODE_NAME     C3905 2
 '@T6G_MB_LIB.T6G(SCH_1):PAGE71_I18@PURE_QUANTA.Q_CAP(CHIPS)':
 'B': CDS_PINID='B';
NODE_NAME     C2275 2
 '@T6G_MB_LIB.T6G(SCH_1):PAGE71_I19@PURE_QUANTA.Q_CAP(CHIPS)':
 'B': CDS_PINID='B';
NODE_NAME     C2279 2
 '@T6G_MB_LIB.T6G(SCH_1):PAGE71_I20@PURE_QUANTA.Q_CAP(CHIPS)':
 'B': CDS_PINID='B';
NODE_NAME     C2282 2
 '@T6G_MB_LIB.T6G(SCH_1):PAGE71_I21@PURE_QUANTA.Q_CAP(CHIPS)':
 'B': CDS_PINID='B';
NODE_NAME     C3901 2
 '@T6G_MB_LIB.T6G(SCH_1):PAGE71_I23@PURE_QUANTA.Q_CAP(CHIPS)':
 'B': CDS_PINID='B';
NODE_NAME     C2285 2
 '@T6G_MB_LIB.T6G(SCH_1):PAGE71_I24@PURE_QUANTA.Q_CAP(CHIPS)':
 'B': CDS_PINID='B';
NODE_NAME     C2287 2
 '@T6G_MB_LIB.T6G(SCH_1):PAGE71_I25@PURE_QUANTA.Q_CAP(CHIPS)':
 'B': CDS_PINID='B';
NODE_NAME     C2289 2
 '@T6G_MB_LIB.T6G(SCH_1):PAGE71_I26@PURE_QUANTA.Q_CAP(CHIPS)':
 'B': CDS_PINID='B';
NODE_NAME     C2291 2
 '@T6G_MB_LIB.T6G(SCH_1):PAGE71_I28@PURE_QUANTA.Q_CAP(CHIPS)':
 'B': CDS_PINID='B';
NODE_NAME     C2264 2
 '@T6G_MB_LIB.T6G(SCH_1):PAGE71_I30@PURE_QUANTA.Q_CAP(CHIPS)':
 'B': CDS_PINID='B';
NODE_NAME     C2263 2
 '@T6G_MB_LIB.T6G(SCH_1):PAGE71_I31@PURE_QUANTA.Q_CAP(CHIPS)':
 'B': CDS_PINID='B';
NODE_NAME     C2269 2
 '@T6G_MB_LIB.T6G(SCH_1):PAGE71_I32@PURE_QUANTA.Q_CAP(CHIPS)':
 'B': CDS_PINID='B';
NODE_NAME     C2268 2
 '@T6G_MB_LIB.T6G(SCH_1):PAGE71_I33@PURE_QUANTA.Q_CAP(CHIPS)':
 'B': CDS_PINID='B';
NODE_NAME     C2272 2
 '@T6G_MB_LIB.T6G(SCH_1):PAGE71_I34@PURE_QUANTA.Q_CAP(CHIPS)':
 'B': CDS_PINID='B';
NODE_NAME     C2273 2
 '@T6G_MB_LIB.T6G(SCH_1):PAGE71_I35@PURE_QUANTA.Q_CAP(CHIPS)':
 'B': CDS_PINID='B';
NODE_NAME     C2277 2
 '@T6G_MB_LIB.T6G(SCH_1):PAGE71_I36@PURE_QUANTA.Q_CAP(CHIPS)':
 'B': CDS_PINID='B';
NODE_NAME     C2281 2
 '@T6G_MB_LIB.T6G(SCH_1):PAGE71_I37@PURE_QUANTA.Q_CAP(CHIPS)':
 'B': CDS_PINID='B';
NODE_NAME     C2280 2
 '@T6G_MB_LIB.T6G(SCH_1):PAGE71_I38@PURE_QUANTA.Q_CAP(CHIPS)':
 'B': CDS_PINID='B';
NODE_NAME     C2284 2
 '@T6G_MB_LIB.T6G(SCH_1):PAGE71_I39@PURE_QUANTA.Q_CAP(CHIPS)':
 'B': CDS_PINID='B';
NODE_NAME     C2283 2
 '@T6G_MB_LIB.T6G(SCH_1):PAGE71_I40@PURE_QUANTA.Q_CAP(CHIPS)':
 'B': CDS_PINID='B';
NODE_NAME     C3906 2
 '@T6G_MB_LIB.T6G(SCH_1):PAGE71_I41@PURE_QUANTA.Q_CAP(CHIPS)':
 'B': CDS_PINID='B';
NODE_NAME     C2286 2
 '@T6G_MB_LIB.T6G(SCH_1):PAGE71_I42@PURE_QUANTA.Q_CAP(CHIPS)':
 'B': CDS_PINID='B';
NODE_NAME     C3907 2
 '@T6G_MB_LIB.T6G(SCH_1):PAGE71_I43@PURE_QUANTA.Q_CAP(CHIPS)':
 'B': CDS_PINID='B';
NODE_NAME     C2288 2
 '@T6G_MB_LIB.T6G(SCH_1):PAGE71_I44@PURE_QUANTA.Q_CAP(CHIPS)':
 'B': CDS_PINID='B';
NODE_NAME     C3908 2
 '@T6G_MB_LIB.T6G(SCH_1):PAGE71_I45@PURE_QUANTA.Q_CAP(CHIPS)':
 'B': CDS_PINID='B';
NODE_NAME     C2290 2
 '@T6G_MB_LIB.T6G(SCH_1):PAGE71_I47@PURE_QUANTA.Q_CAP(CHIPS)':
 'B': CDS_PINID='B';
NODE_NAME     C2292 2
 '@T6G_MB_LIB.T6G(SCH_1):PAGE71_I49@PURE_QUANTA.Q_CAP(CHIPS)':
 'B': CDS_PINID='B';
NODE_NAME     C2293 2
 '@T6G_MB_LIB.T6G(SCH_1):PAGE71_I50@PURE_QUANTA.Q_CAP(CHIPS)':
 'B': CDS_PINID='B';
NODE_NAME     C3909 2
 '@T6G_MB_LIB.T6G(SCH_1):PAGE71_I52@PURE_QUANTA.Q_CAP(CHIPS)':
 'B': CDS_PINID='B';
NODE_NAME     C2260 2
 '@T6G_MB_LIB.T6G(SCH_1):PAGE71_I53@PURE_QUANTA.Q_CAP(CHIPS)':
 'B': CDS_PINID='B';
NODE_NAME     C2265 2
 '@T6G_MB_LIB.T6G(SCH_1):PAGE71_I54@PURE_QUANTA.Q_CAP(CHIPS)':
 'B': CDS_PINID='B';
NODE_NAME     C2270 2
 '@T6G_MB_LIB.T6G(SCH_1):PAGE71_I56@PURE_QUANTA.Q_CAP(CHIPS)':
 'B': CDS_PINID='B';
NODE_NAME     C2274 2
 '@T6G_MB_LIB.T6G(SCH_1):PAGE71_I57@PURE_QUANTA.Q_CAP(CHIPS)':
 'B': CDS_PINID='B';
NODE_NAME     C2278 2
 '@T6G_MB_LIB.T6G(SCH_1):PAGE71_I58@PURE_QUANTA.Q_CAP(CHIPS)':
 'B': CDS_PINID='B';
NODE_NAME     C3910 2
 '@T6G_MB_LIB.T6G(SCH_1):PAGE71_I59@PURE_QUANTA.Q_CAP(CHIPS)':
 'B': CDS_PINID='B';
NODE_NAME     C3911 2
 '@T6G_MB_LIB.T6G(SCH_1):PAGE71_I61@PURE_QUANTA.Q_CAP(CHIPS)':
 'B': CDS_PINID='B';
NODE_NAME     C2276 2
 '@T6G_MB_LIB.T6G(SCH_1):PAGE71_I62@PURE_QUANTA.Q_CAP(CHIPS)':
 'B': CDS_PINID='B';
NODE_NAME     C2298 2
 '@T6G_MB_LIB.T6G(SCH_1):PAGE72_I1@PURE_QUANTA.Q_CAP(CHIPS)':
 'B': CDS_PINID='B';
NODE_NAME     C2304 2
 '@T6G_MB_LIB.T6G(SCH_1):PAGE72_I3@PURE_QUANTA.Q_CAP(CHIPS)':
 'B': CDS_PINID='B';
NODE_NAME     C2310 2
 '@T6G_MB_LIB.T6G(SCH_1):PAGE72_I4@PURE_QUANTA.Q_CAP(CHIPS)':
 'B': CDS_PINID='B';
NODE_NAME     C2297 2
 '@T6G_MB_LIB.T6G(SCH_1):PAGE72_I5@PURE_QUANTA.Q_CAP(CHIPS)':
 'B': CDS_PINID='B';
NODE_NAME     C2296 2
 '@T6G_MB_LIB.T6G(SCH_1):PAGE72_I7@PURE_QUANTA.Q_CAP(CHIPS)':
 'B': CDS_PINID='B';
NODE_NAME     C2295 2
 '@T6G_MB_LIB.T6G(SCH_1):PAGE72_I9@PURE_QUANTA.Q_CAP(CHIPS)':
 'B': CDS_PINID='B';
NODE_NAME     C2303 2
 '@T6G_MB_LIB.T6G(SCH_1):PAGE72_I10@PURE_QUANTA.Q_CAP(CHIPS)':
 'B': CDS_PINID='B';
NODE_NAME     C2309 2
 '@T6G_MB_LIB.T6G(SCH_1):PAGE72_I11@PURE_QUANTA.Q_CAP(CHIPS)':
 'B': CDS_PINID='B';
NODE_NAME     C2302 2
 '@T6G_MB_LIB.T6G(SCH_1):PAGE72_I12@PURE_QUANTA.Q_CAP(CHIPS)':
 'B': CDS_PINID='B';
NODE_NAME     C2301 2
 '@T6G_MB_LIB.T6G(SCH_1):PAGE72_I13@PURE_QUANTA.Q_CAP(CHIPS)':
 'B': CDS_PINID='B';
NODE_NAME     C2308 2
 '@T6G_MB_LIB.T6G(SCH_1):PAGE72_I14@PURE_QUANTA.Q_CAP(CHIPS)':
 'B': CDS_PINID='B';
NODE_NAME     C2307 2
 '@T6G_MB_LIB.T6G(SCH_1):PAGE72_I15@PURE_QUANTA.Q_CAP(CHIPS)':
 'B': CDS_PINID='B';
NODE_NAME     C2294 2
 '@T6G_MB_LIB.T6G(SCH_1):PAGE72_I17@PURE_QUANTA.Q_CAP(CHIPS)':
 'B': CDS_PINID='B';
NODE_NAME     C2300 2
 '@T6G_MB_LIB.T6G(SCH_1):PAGE72_I19@PURE_QUANTA.Q_CAP(CHIPS)':
 'B': CDS_PINID='B';
NODE_NAME     C2306 2
 '@T6G_MB_LIB.T6G(SCH_1):PAGE72_I20@PURE_QUANTA.Q_CAP(CHIPS)':
 'B': CDS_PINID='B';
NODE_NAME     C2316 2
 '@T6G_MB_LIB.T6G(SCH_1):PAGE72_I21@PURE_QUANTA.Q_CAP(CHIPS)':
 'B': CDS_PINID='B';
NODE_NAME     C2322 2
 '@T6G_MB_LIB.T6G(SCH_1):PAGE72_I23@PURE_QUANTA.Q_CAP(CHIPS)':
 'B': CDS_PINID='B';
NODE_NAME     C2315 2
 '@T6G_MB_LIB.T6G(SCH_1):PAGE72_I24@PURE_QUANTA.Q_CAP(CHIPS)':
 'B': CDS_PINID='B';
NODE_NAME     C2321 2
 '@T6G_MB_LIB.T6G(SCH_1):PAGE72_I25@PURE_QUANTA.Q_CAP(CHIPS)':
 'B': CDS_PINID='B';
NODE_NAME     C2327 2
 '@T6G_MB_LIB.T6G(SCH_1):PAGE72_I26@PURE_QUANTA.Q_CAP(CHIPS)':
 'B': CDS_PINID='B';
NODE_NAME     C2314 2
 '@T6G_MB_LIB.T6G(SCH_1):PAGE72_I27@PURE_QUANTA.Q_CAP(CHIPS)':
 'B': CDS_PINID='B';
NODE_NAME     C2313 2
 '@T6G_MB_LIB.T6G(SCH_1):PAGE72_I28@PURE_QUANTA.Q_CAP(CHIPS)':
 'B': CDS_PINID='B';
NODE_NAME     C2320 2
 '@T6G_MB_LIB.T6G(SCH_1):PAGE72_I29@PURE_QUANTA.Q_CAP(CHIPS)':
 'B': CDS_PINID='B';
NODE_NAME     C2326 2
 '@T6G_MB_LIB.T6G(SCH_1):PAGE72_I30@PURE_QUANTA.Q_CAP(CHIPS)':
 'B': CDS_PINID='B';
NODE_NAME     C2319 2
 '@T6G_MB_LIB.T6G(SCH_1):PAGE72_I31@PURE_QUANTA.Q_CAP(CHIPS)':
 'B': CDS_PINID='B';
NODE_NAME     C2325 2
 '@T6G_MB_LIB.T6G(SCH_1):PAGE72_I32@PURE_QUANTA.Q_CAP(CHIPS)':
 'B': CDS_PINID='B';
NODE_NAME     C2333 2
 '@T6G_MB_LIB.T6G(SCH_1):PAGE72_I33@PURE_QUANTA.Q_CAP(CHIPS)':
 'B': CDS_PINID='B';
NODE_NAME     C2338 2
 '@T6G_MB_LIB.T6G(SCH_1):PAGE72_I34@PURE_QUANTA.Q_CAP(CHIPS)':
 'B': CDS_PINID='B';
NODE_NAME     C2332 2
 '@T6G_MB_LIB.T6G(SCH_1):PAGE72_I35@PURE_QUANTA.Q_CAP(CHIPS)':
 'B': CDS_PINID='B';
NODE_NAME     C2331 2
 '@T6G_MB_LIB.T6G(SCH_1):PAGE72_I36@PURE_QUANTA.Q_CAP(CHIPS)':
 'B': CDS_PINID='B';
NODE_NAME     C2337 2
 '@T6G_MB_LIB.T6G(SCH_1):PAGE72_I37@PURE_QUANTA.Q_CAP(CHIPS)':
 'B': CDS_PINID='B';
NODE_NAME     C2336 2
 '@T6G_MB_LIB.T6G(SCH_1):PAGE72_I38@PURE_QUANTA.Q_CAP(CHIPS)':
 'B': CDS_PINID='B';
NODE_NAME     C2354 2
 '@T6G_MB_LIB.T6G(SCH_1):PAGE72_I40@PURE_QUANTA.Q_CAP(CHIPS)':
 'B': CDS_PINID='B';
NODE_NAME     C2360 2
 '@T6G_MB_LIB.T6G(SCH_1):PAGE72_I41@PURE_QUANTA.Q_CAP(CHIPS)':
 'B': CDS_PINID='B';
NODE_NAME     C2343 2
 '@T6G_MB_LIB.T6G(SCH_1):PAGE72_I42@PURE_QUANTA.Q_CAP(CHIPS)':
 'B': CDS_PINID='B';
NODE_NAME     C2348 2
 '@T6G_MB_LIB.T6G(SCH_1):PAGE72_I44@PURE_QUANTA.Q_CAP(CHIPS)':
 'B': CDS_PINID='B';
NODE_NAME     C2342 2
 '@T6G_MB_LIB.T6G(SCH_1):PAGE72_I46@PURE_QUANTA.Q_CAP(CHIPS)':
 'B': CDS_PINID='B';
NODE_NAME     C2341 2
 '@T6G_MB_LIB.T6G(SCH_1):PAGE72_I47@PURE_QUANTA.Q_CAP(CHIPS)':
 'B': CDS_PINID='B';
NODE_NAME     C2347 2
 '@T6G_MB_LIB.T6G(SCH_1):PAGE72_I48@PURE_QUANTA.Q_CAP(CHIPS)':
 'B': CDS_PINID='B';
NODE_NAME     C2346 2
 '@T6G_MB_LIB.T6G(SCH_1):PAGE72_I50@PURE_QUANTA.Q_CAP(CHIPS)':
 'B': CDS_PINID='B';
NODE_NAME     C2353 2
 '@T6G_MB_LIB.T6G(SCH_1):PAGE72_I51@PURE_QUANTA.Q_CAP(CHIPS)':
 'B': CDS_PINID='B';
NODE_NAME     C2359 2
 '@T6G_MB_LIB.T6G(SCH_1):PAGE72_I53@PURE_QUANTA.Q_CAP(CHIPS)':
 'B': CDS_PINID='B';
NODE_NAME     C2352 2
 '@T6G_MB_LIB.T6G(SCH_1):PAGE72_I55@PURE_QUANTA.Q_CAP(CHIPS)':
 'B': CDS_PINID='B';
NODE_NAME     C2351 2
 '@T6G_MB_LIB.T6G(SCH_1):PAGE72_I56@PURE_QUANTA.Q_CAP(CHIPS)':
 'B': CDS_PINID='B';
NODE_NAME     C2358 2
 '@T6G_MB_LIB.T6G(SCH_1):PAGE72_I57@PURE_QUANTA.Q_CAP(CHIPS)':
 'B': CDS_PINID='B';
NODE_NAME     C2357 2
 '@T6G_MB_LIB.T6G(SCH_1):PAGE72_I58@PURE_QUANTA.Q_CAP(CHIPS)':
 'B': CDS_PINID='B';
NODE_NAME     C2312 2
 '@T6G_MB_LIB.T6G(SCH_1):PAGE72_I59@PURE_QUANTA.Q_CAP(CHIPS)':
 'B': CDS_PINID='B';
NODE_NAME     C2318 2
 '@T6G_MB_LIB.T6G(SCH_1):PAGE72_I60@PURE_QUANTA.Q_CAP(CHIPS)':
 'B': CDS_PINID='B';
NODE_NAME     C2324 2
 '@T6G_MB_LIB.T6G(SCH_1):PAGE72_I61@PURE_QUANTA.Q_CAP(CHIPS)':
 'B': CDS_PINID='B';
NODE_NAME     C2330 2
 '@T6G_MB_LIB.T6G(SCH_1):PAGE72_I62@PURE_QUANTA.Q_CAP(CHIPS)':
 'B': CDS_PINID='B';
NODE_NAME     C2335 2
 '@T6G_MB_LIB.T6G(SCH_1):PAGE72_I63@PURE_QUANTA.Q_CAP(CHIPS)':
 'B': CDS_PINID='B';
NODE_NAME     C2340 2
 '@T6G_MB_LIB.T6G(SCH_1):PAGE72_I64@PURE_QUANTA.Q_CAP(CHIPS)':
 'B': CDS_PINID='B';
NODE_NAME     C2345 2
 '@T6G_MB_LIB.T6G(SCH_1):PAGE72_I66@PURE_QUANTA.Q_CAP(CHIPS)':
 'B': CDS_PINID='B';
NODE_NAME     C2356 2
 '@T6G_MB_LIB.T6G(SCH_1):PAGE72_I68@PURE_QUANTA.Q_CAP(CHIPS)':
 'B': CDS_PINID='B';
NODE_NAME     C2366 2
 '@T6G_MB_LIB.T6G(SCH_1):PAGE72_I70@PURE_QUANTA.Q_CAP(CHIPS)':
 'B': CDS_PINID='B';
NODE_NAME     C2372 2
 '@T6G_MB_LIB.T6G(SCH_1):PAGE72_I71@PURE_QUANTA.Q_CAP(CHIPS)':
 'B': CDS_PINID='B';
NODE_NAME     C2378 2
 '@T6G_MB_LIB.T6G(SCH_1):PAGE72_I72@PURE_QUANTA.Q_CAP(CHIPS)':
 'B': CDS_PINID='B';
NODE_NAME     C2365 2
 '@T6G_MB_LIB.T6G(SCH_1):PAGE72_I74@PURE_QUANTA.Q_CAP(CHIPS)':
 'B': CDS_PINID='B';
NODE_NAME     C2371 2
 '@T6G_MB_LIB.T6G(SCH_1):PAGE72_I75@PURE_QUANTA.Q_CAP(CHIPS)':
 'B': CDS_PINID='B';
NODE_NAME     C2364 2
 '@T6G_MB_LIB.T6G(SCH_1):PAGE72_I76@PURE_QUANTA.Q_CAP(CHIPS)':
 'B': CDS_PINID='B';
NODE_NAME     C2363 2
 '@T6G_MB_LIB.T6G(SCH_1):PAGE72_I77@PURE_QUANTA.Q_CAP(CHIPS)':
 'B': CDS_PINID='B';
NODE_NAME     C2370 2
 '@T6G_MB_LIB.T6G(SCH_1):PAGE72_I78@PURE_QUANTA.Q_CAP(CHIPS)':
 'B': CDS_PINID='B';
NODE_NAME     C2369 2
 '@T6G_MB_LIB.T6G(SCH_1):PAGE72_I79@PURE_QUANTA.Q_CAP(CHIPS)':
 'B': CDS_PINID='B';
NODE_NAME     C2376 2
 '@T6G_MB_LIB.T6G(SCH_1):PAGE72_I80@PURE_QUANTA.Q_CAP(CHIPS)':
 'B': CDS_PINID='B';
NODE_NAME     C2377 2
 '@T6G_MB_LIB.T6G(SCH_1):PAGE72_I81@PURE_QUANTA.Q_CAP(CHIPS)':
 'B': CDS_PINID='B';
NODE_NAME     C2383 2
 '@T6G_MB_LIB.T6G(SCH_1):PAGE72_I82@PURE_QUANTA.Q_CAP(CHIPS)':
 'B': CDS_PINID='B';
NODE_NAME     C2389 2
 '@T6G_MB_LIB.T6G(SCH_1):PAGE72_I83@PURE_QUANTA.Q_CAP(CHIPS)':
 'B': CDS_PINID='B';
NODE_NAME     C2382 2
 '@T6G_MB_LIB.T6G(SCH_1):PAGE72_I84@PURE_QUANTA.Q_CAP(CHIPS)':
 'B': CDS_PINID='B';
NODE_NAME     C2375 2
 '@T6G_MB_LIB.T6G(SCH_1):PAGE72_I85@PURE_QUANTA.Q_CAP(CHIPS)':
 'B': CDS_PINID='B';
NODE_NAME     C2381 2
 '@T6G_MB_LIB.T6G(SCH_1):PAGE72_I86@PURE_QUANTA.Q_CAP(CHIPS)':
 'B': CDS_PINID='B';
NODE_NAME     C2388 2
 '@T6G_MB_LIB.T6G(SCH_1):PAGE72_I87@PURE_QUANTA.Q_CAP(CHIPS)':
 'B': CDS_PINID='B';
NODE_NAME     C2387 2
 '@T6G_MB_LIB.T6G(SCH_1):PAGE72_I88@PURE_QUANTA.Q_CAP(CHIPS)':
 'B': CDS_PINID='B';
NODE_NAME     C2395 2
 '@T6G_MB_LIB.T6G(SCH_1):PAGE72_I89@PURE_QUANTA.Q_CAP(CHIPS)':
 'B': CDS_PINID='B';
NODE_NAME     C2400 2
 '@T6G_MB_LIB.T6G(SCH_1):PAGE72_I90@PURE_QUANTA.Q_CAP(CHIPS)':
 'B': CDS_PINID='B';
NODE_NAME     C2394 2
 '@T6G_MB_LIB.T6G(SCH_1):PAGE72_I91@PURE_QUANTA.Q_CAP(CHIPS)':
 'B': CDS_PINID='B';
NODE_NAME     C2393 2
 '@T6G_MB_LIB.T6G(SCH_1):PAGE72_I92@PURE_QUANTA.Q_CAP(CHIPS)':
 'B': CDS_PINID='B';
NODE_NAME     C2399 2
 '@T6G_MB_LIB.T6G(SCH_1):PAGE72_I93@PURE_QUANTA.Q_CAP(CHIPS)':
 'B': CDS_PINID='B';
NODE_NAME     C2398 2
 '@T6G_MB_LIB.T6G(SCH_1):PAGE72_I94@PURE_QUANTA.Q_CAP(CHIPS)':
 'B': CDS_PINID='B';
NODE_NAME     C2405 2
 '@T6G_MB_LIB.T6G(SCH_1):PAGE72_I96@PURE_QUANTA.Q_CAP(CHIPS)':
 'B': CDS_PINID='B';
NODE_NAME     C2404 2
 '@T6G_MB_LIB.T6G(SCH_1):PAGE72_I98@PURE_QUANTA.Q_CAP(CHIPS)':
 'B': CDS_PINID='B';
NODE_NAME     C2403 2
 '@T6G_MB_LIB.T6G(SCH_1):PAGE72_I100@PURE_QUANTA.Q_CAP(CHIPS)':
 'B': CDS_PINID='B';
NODE_NAME     C2362 2
 '@T6G_MB_LIB.T6G(SCH_1):PAGE72_I101@PURE_QUANTA.Q_CAP(CHIPS)':
 'B': CDS_PINID='B';
NODE_NAME     C2368 2
 '@T6G_MB_LIB.T6G(SCH_1):PAGE72_I102@PURE_QUANTA.Q_CAP(CHIPS)':
 'B': CDS_PINID='B';
NODE_NAME     C2374 2
 '@T6G_MB_LIB.T6G(SCH_1):PAGE72_I103@PURE_QUANTA.Q_CAP(CHIPS)':
 'B': CDS_PINID='B';
NODE_NAME     C2380 2
 '@T6G_MB_LIB.T6G(SCH_1):PAGE72_I104@PURE_QUANTA.Q_CAP(CHIPS)':
 'B': CDS_PINID='B';
NODE_NAME     C2386 2
 '@T6G_MB_LIB.T6G(SCH_1):PAGE72_I105@PURE_QUANTA.Q_CAP(CHIPS)':
 'B': CDS_PINID='B';
NODE_NAME     C2392 2
 '@T6G_MB_LIB.T6G(SCH_1):PAGE72_I106@PURE_QUANTA.Q_CAP(CHIPS)':
 'B': CDS_PINID='B';
NODE_NAME     C2397 2
 '@T6G_MB_LIB.T6G(SCH_1):PAGE72_I107@PURE_QUANTA.Q_CAP(CHIPS)':
 'B': CDS_PINID='B';
NODE_NAME     C2402 2
 '@T6G_MB_LIB.T6G(SCH_1):PAGE72_I109@PURE_QUANTA.Q_CAP(CHIPS)':
 'B': CDS_PINID='B';
NODE_NAME     C2350 2
 '@T6G_MB_LIB.T6G(SCH_1):PAGE72_I110@PURE_QUANTA.Q_CAP(CHIPS)':
 'B': CDS_PINID='B';
NODE_NAME     C3912 2
 '@T6G_MB_LIB.T6G(SCH_1):PAGE73_I1@PURE_QUANTA.Q_CAP(CHIPS)':
 'B': CDS_PINID='B';
NODE_NAME     C2413 2
 '@T6G_MB_LIB.T6G(SCH_1):PAGE73_I3@PURE_QUANTA.Q_CAP(CHIPS)':
 'B': CDS_PINID='B';
NODE_NAME     C3913 2
 '@T6G_MB_LIB.T6G(SCH_1):PAGE73_I4@PURE_QUANTA.Q_CAP(CHIPS)':
 'B': CDS_PINID='B';
NODE_NAME     C2420 2
 '@T6G_MB_LIB.T6G(SCH_1):PAGE73_I5@PURE_QUANTA.Q_CAP(CHIPS)':
 'B': CDS_PINID='B';
NODE_NAME     C3914 2
 '@T6G_MB_LIB.T6G(SCH_1):PAGE73_I6@PURE_QUANTA.Q_CAP(CHIPS)':
 'B': CDS_PINID='B';
NODE_NAME     C2427 2
 '@T6G_MB_LIB.T6G(SCH_1):PAGE73_I7@PURE_QUANTA.Q_CAP(CHIPS)':
 'B': CDS_PINID='B';
NODE_NAME     C3915 2
 '@T6G_MB_LIB.T6G(SCH_1):PAGE73_I8@PURE_QUANTA.Q_CAP(CHIPS)':
 'B': CDS_PINID='B';
NODE_NAME     C2434 2
 '@T6G_MB_LIB.T6G(SCH_1):PAGE73_I9@PURE_QUANTA.Q_CAP(CHIPS)':
 'B': CDS_PINID='B';
NODE_NAME     C2412 2
 '@T6G_MB_LIB.T6G(SCH_1):PAGE73_I11@PURE_QUANTA.Q_CAP(CHIPS)':
 'B': CDS_PINID='B';
NODE_NAME     C2419 2
 '@T6G_MB_LIB.T6G(SCH_1):PAGE73_I13@PURE_QUANTA.Q_CAP(CHIPS)':
 'B': CDS_PINID='B';
NODE_NAME     C2411 2
 '@T6G_MB_LIB.T6G(SCH_1):PAGE73_I14@PURE_QUANTA.Q_CAP(CHIPS)':
 'B': CDS_PINID='B';
NODE_NAME     C2410 2
 '@T6G_MB_LIB.T6G(SCH_1):PAGE73_I16@PURE_QUANTA.Q_CAP(CHIPS)':
 'B': CDS_PINID='B';
NODE_NAME     C2418 2
 '@T6G_MB_LIB.T6G(SCH_1):PAGE73_I17@PURE_QUANTA.Q_CAP(CHIPS)':
 'B': CDS_PINID='B';
NODE_NAME     C2417 2
 '@T6G_MB_LIB.T6G(SCH_1):PAGE73_I18@PURE_QUANTA.Q_CAP(CHIPS)':
 'B': CDS_PINID='B';
NODE_NAME     C2426 2
 '@T6G_MB_LIB.T6G(SCH_1):PAGE73_I19@PURE_QUANTA.Q_CAP(CHIPS)':
 'B': CDS_PINID='B';
NODE_NAME     C2433 2
 '@T6G_MB_LIB.T6G(SCH_1):PAGE73_I20@PURE_QUANTA.Q_CAP(CHIPS)':
 'B': CDS_PINID='B';
NODE_NAME     C2425 2
 '@T6G_MB_LIB.T6G(SCH_1):PAGE73_I21@PURE_QUANTA.Q_CAP(CHIPS)':
 'B': CDS_PINID='B';
NODE_NAME     C2424 2
 '@T6G_MB_LIB.T6G(SCH_1):PAGE73_I22@PURE_QUANTA.Q_CAP(CHIPS)':
 'B': CDS_PINID='B';
NODE_NAME     C2432 2
 '@T6G_MB_LIB.T6G(SCH_1):PAGE73_I23@PURE_QUANTA.Q_CAP(CHIPS)':
 'B': CDS_PINID='B';
NODE_NAME     C2431 2
 '@T6G_MB_LIB.T6G(SCH_1):PAGE73_I24@PURE_QUANTA.Q_CAP(CHIPS)':
 'B': CDS_PINID='B';
NODE_NAME     C3916 2
 '@T6G_MB_LIB.T6G(SCH_1):PAGE73_I25@PURE_QUANTA.Q_CAP(CHIPS)':
 'B': CDS_PINID='B';
NODE_NAME     C2441 2
 '@T6G_MB_LIB.T6G(SCH_1):PAGE73_I26@PURE_QUANTA.Q_CAP(CHIPS)':
 'B': CDS_PINID='B';
NODE_NAME     C3917 2
 '@T6G_MB_LIB.T6G(SCH_1):PAGE73_I27@PURE_QUANTA.Q_CAP(CHIPS)':
 'B': CDS_PINID='B';
NODE_NAME     C2448 2
 '@T6G_MB_LIB.T6G(SCH_1):PAGE73_I28@PURE_QUANTA.Q_CAP(CHIPS)':
 'B': CDS_PINID='B';
NODE_NAME     C2455 2
 '@T6G_MB_LIB.T6G(SCH_1):PAGE73_I29@PURE_QUANTA.Q_CAP(CHIPS)':
 'B': CDS_PINID='B';
NODE_NAME     C3918 2
 '@T6G_MB_LIB.T6G(SCH_1):PAGE73_I30@PURE_QUANTA.Q_CAP(CHIPS)':
 'B': CDS_PINID='B';
NODE_NAME     C2462 2
 '@T6G_MB_LIB.T6G(SCH_1):PAGE73_I32@PURE_QUANTA.Q_CAP(CHIPS)':
 'B': CDS_PINID='B';
NODE_NAME     C2469 2
 '@T6G_MB_LIB.T6G(SCH_1):PAGE73_I33@PURE_QUANTA.Q_CAP(CHIPS)':
 'B': CDS_PINID='B';
NODE_NAME     C2440 2
 '@T6G_MB_LIB.T6G(SCH_1):PAGE73_I34@PURE_QUANTA.Q_CAP(CHIPS)':
 'B': CDS_PINID='B';
NODE_NAME     C2447 2
 '@T6G_MB_LIB.T6G(SCH_1):PAGE73_I35@PURE_QUANTA.Q_CAP(CHIPS)':
 'B': CDS_PINID='B';
NODE_NAME     C2439 2
 '@T6G_MB_LIB.T6G(SCH_1):PAGE73_I36@PURE_QUANTA.Q_CAP(CHIPS)':
 'B': CDS_PINID='B';
NODE_NAME     C2438 2
 '@T6G_MB_LIB.T6G(SCH_1):PAGE73_I37@PURE_QUANTA.Q_CAP(CHIPS)':
 'B': CDS_PINID='B';
NODE_NAME     C2446 2
 '@T6G_MB_LIB.T6G(SCH_1):PAGE73_I38@PURE_QUANTA.Q_CAP(CHIPS)':
 'B': CDS_PINID='B';
NODE_NAME     C2445 2
 '@T6G_MB_LIB.T6G(SCH_1):PAGE73_I39@PURE_QUANTA.Q_CAP(CHIPS)':
 'B': CDS_PINID='B';
NODE_NAME     C2452 2
 '@T6G_MB_LIB.T6G(SCH_1):PAGE73_I40@PURE_QUANTA.Q_CAP(CHIPS)':
 'B': CDS_PINID='B';
NODE_NAME     C2453 2
 '@T6G_MB_LIB.T6G(SCH_1):PAGE73_I41@PURE_QUANTA.Q_CAP(CHIPS)':
 'B': CDS_PINID='B';
NODE_NAME     C2454 2
 '@T6G_MB_LIB.T6G(SCH_1):PAGE73_I42@PURE_QUANTA.Q_CAP(CHIPS)':
 'B': CDS_PINID='B';
NODE_NAME     C2461 2
 '@T6G_MB_LIB.T6G(SCH_1):PAGE73_I43@PURE_QUANTA.Q_CAP(CHIPS)':
 'B': CDS_PINID='B';
NODE_NAME     C2468 2
 '@T6G_MB_LIB.T6G(SCH_1):PAGE73_I44@PURE_QUANTA.Q_CAP(CHIPS)':
 'B': CDS_PINID='B';
NODE_NAME     C2460 2
 '@T6G_MB_LIB.T6G(SCH_1):PAGE73_I45@PURE_QUANTA.Q_CAP(CHIPS)':
 'B': CDS_PINID='B';
NODE_NAME     C2459 2
 '@T6G_MB_LIB.T6G(SCH_1):PAGE73_I46@PURE_QUANTA.Q_CAP(CHIPS)':
 'B': CDS_PINID='B';
NODE_NAME     C2467 2
 '@T6G_MB_LIB.T6G(SCH_1):PAGE73_I47@PURE_QUANTA.Q_CAP(CHIPS)':
 'B': CDS_PINID='B';
NODE_NAME     C2466 2
 '@T6G_MB_LIB.T6G(SCH_1):PAGE73_I48@PURE_QUANTA.Q_CAP(CHIPS)':
 'B': CDS_PINID='B';
NODE_NAME     C2409 2
 '@T6G_MB_LIB.T6G(SCH_1):PAGE73_I50@PURE_QUANTA.Q_CAP(CHIPS)':
 'B': CDS_PINID='B';
NODE_NAME     C2416 2
 '@T6G_MB_LIB.T6G(SCH_1):PAGE73_I52@PURE_QUANTA.Q_CAP(CHIPS)':
 'B': CDS_PINID='B';
NODE_NAME     C2408 2
 '@T6G_MB_LIB.T6G(SCH_1):PAGE73_I53@PURE_QUANTA.Q_CAP(CHIPS)':
 'B': CDS_PINID='B';
NODE_NAME     C2407 2
 '@T6G_MB_LIB.T6G(SCH_1):PAGE73_I55@PURE_QUANTA.Q_CAP(CHIPS)':
 'B': CDS_PINID='B';
NODE_NAME     C2415 2
 '@T6G_MB_LIB.T6G(SCH_1):PAGE73_I56@PURE_QUANTA.Q_CAP(CHIPS)':
 'B': CDS_PINID='B';
NODE_NAME     C2414 2
 '@T6G_MB_LIB.T6G(SCH_1):PAGE73_I57@PURE_QUANTA.Q_CAP(CHIPS)':
 'B': CDS_PINID='B';
NODE_NAME     C2423 2
 '@T6G_MB_LIB.T6G(SCH_1):PAGE73_I58@PURE_QUANTA.Q_CAP(CHIPS)':
 'B': CDS_PINID='B';
NODE_NAME     C2430 2
 '@T6G_MB_LIB.T6G(SCH_1):PAGE73_I59@PURE_QUANTA.Q_CAP(CHIPS)':
 'B': CDS_PINID='B';
NODE_NAME     C2422 2
 '@T6G_MB_LIB.T6G(SCH_1):PAGE73_I60@PURE_QUANTA.Q_CAP(CHIPS)':
 'B': CDS_PINID='B';
NODE_NAME     C2421 2
 '@T6G_MB_LIB.T6G(SCH_1):PAGE73_I61@PURE_QUANTA.Q_CAP(CHIPS)':
 'B': CDS_PINID='B';
NODE_NAME     C2429 2
 '@T6G_MB_LIB.T6G(SCH_1):PAGE73_I62@PURE_QUANTA.Q_CAP(CHIPS)':
 'B': CDS_PINID='B';
NODE_NAME     C2437 2
 '@T6G_MB_LIB.T6G(SCH_1):PAGE73_I64@PURE_QUANTA.Q_CAP(CHIPS)':
 'B': CDS_PINID='B';
NODE_NAME     C2444 2
 '@T6G_MB_LIB.T6G(SCH_1):PAGE73_I65@PURE_QUANTA.Q_CAP(CHIPS)':
 'B': CDS_PINID='B';
NODE_NAME     C2436 2
 '@T6G_MB_LIB.T6G(SCH_1):PAGE73_I66@PURE_QUANTA.Q_CAP(CHIPS)':
 'B': CDS_PINID='B';
NODE_NAME     C2443 2
 '@T6G_MB_LIB.T6G(SCH_1):PAGE73_I67@PURE_QUANTA.Q_CAP(CHIPS)':
 'B': CDS_PINID='B';
NODE_NAME     C2449 2
 '@T6G_MB_LIB.T6G(SCH_1):PAGE73_I68@PURE_QUANTA.Q_CAP(CHIPS)':
 'B': CDS_PINID='B';
NODE_NAME     C2450 2
 '@T6G_MB_LIB.T6G(SCH_1):PAGE73_I69@PURE_QUANTA.Q_CAP(CHIPS)':
 'B': CDS_PINID='B';
NODE_NAME     C2451 2
 '@T6G_MB_LIB.T6G(SCH_1):PAGE73_I70@PURE_QUANTA.Q_CAP(CHIPS)':
 'B': CDS_PINID='B';
NODE_NAME     C2458 2
 '@T6G_MB_LIB.T6G(SCH_1):PAGE73_I71@PURE_QUANTA.Q_CAP(CHIPS)':
 'B': CDS_PINID='B';
NODE_NAME     C2465 2
 '@T6G_MB_LIB.T6G(SCH_1):PAGE73_I72@PURE_QUANTA.Q_CAP(CHIPS)':
 'B': CDS_PINID='B';
NODE_NAME     C2457 2
 '@T6G_MB_LIB.T6G(SCH_1):PAGE73_I73@PURE_QUANTA.Q_CAP(CHIPS)':
 'B': CDS_PINID='B';
NODE_NAME     C2456 2
 '@T6G_MB_LIB.T6G(SCH_1):PAGE73_I74@PURE_QUANTA.Q_CAP(CHIPS)':
 'B': CDS_PINID='B';
NODE_NAME     C2464 2
 '@T6G_MB_LIB.T6G(SCH_1):PAGE73_I75@PURE_QUANTA.Q_CAP(CHIPS)':
 'B': CDS_PINID='B';
NODE_NAME     C2463 2
 '@T6G_MB_LIB.T6G(SCH_1):PAGE73_I76@PURE_QUANTA.Q_CAP(CHIPS)':
 'B': CDS_PINID='B';
NODE_NAME     C3919 2
 '@T6G_MB_LIB.T6G(SCH_1):PAGE73_I77@PURE_QUANTA.Q_CAP(CHIPS)':
 'B': CDS_PINID='B';
NODE_NAME     C2476 2
 '@T6G_MB_LIB.T6G(SCH_1):PAGE73_I79@PURE_QUANTA.Q_CAP(CHIPS)':
 'B': CDS_PINID='B';
NODE_NAME     C2483 2
 '@T6G_MB_LIB.T6G(SCH_1):PAGE73_I81@PURE_QUANTA.Q_CAP(CHIPS)':
 'B': CDS_PINID='B';
NODE_NAME     C3920 2
 '@T6G_MB_LIB.T6G(SCH_1):PAGE73_I84@PURE_QUANTA.Q_CAP(CHIPS)':
 'B': CDS_PINID='B';
NODE_NAME     C2488 2
 '@T6G_MB_LIB.T6G(SCH_1):PAGE73_I85@PURE_QUANTA.Q_CAP(CHIPS)':
 'B': CDS_PINID='B';
NODE_NAME     C2492 2
 '@T6G_MB_LIB.T6G(SCH_1):PAGE73_I86@PURE_QUANTA.Q_CAP(CHIPS)':
 'B': CDS_PINID='B';
NODE_NAME     C2475 2
 '@T6G_MB_LIB.T6G(SCH_1):PAGE73_I88@PURE_QUANTA.Q_CAP(CHIPS)':
 'B': CDS_PINID='B';
NODE_NAME     C2482 2
 '@T6G_MB_LIB.T6G(SCH_1):PAGE73_I90@PURE_QUANTA.Q_CAP(CHIPS)':
 'B': CDS_PINID='B';
NODE_NAME     C2481 2
 '@T6G_MB_LIB.T6G(SCH_1):PAGE73_I92@PURE_QUANTA.Q_CAP(CHIPS)':
 'B': CDS_PINID='B';
NODE_NAME     C2474 2
 '@T6G_MB_LIB.T6G(SCH_1):PAGE73_I94@PURE_QUANTA.Q_CAP(CHIPS)':
 'B': CDS_PINID='B';
NODE_NAME     C2473 2
 '@T6G_MB_LIB.T6G(SCH_1):PAGE73_I96@PURE_QUANTA.Q_CAP(CHIPS)':
 'B': CDS_PINID='B';
NODE_NAME     C2480 2
 '@T6G_MB_LIB.T6G(SCH_1):PAGE73_I97@PURE_QUANTA.Q_CAP(CHIPS)':
 'B': CDS_PINID='B';
NODE_NAME     C2487 2
 '@T6G_MB_LIB.T6G(SCH_1):PAGE73_I99@PURE_QUANTA.Q_CAP(CHIPS)':
 'B': CDS_PINID='B';
NODE_NAME     C2486 2
 '@T6G_MB_LIB.T6G(SCH_1):PAGE73_I100@PURE_QUANTA.Q_CAP(CHIPS)':
 'B': CDS_PINID='B';
NODE_NAME     C2491 2
 '@T6G_MB_LIB.T6G(SCH_1):PAGE73_I101@PURE_QUANTA.Q_CAP(CHIPS)':
 'B': CDS_PINID='B';
NODE_NAME     C2490 2
 '@T6G_MB_LIB.T6G(SCH_1):PAGE73_I102@PURE_QUANTA.Q_CAP(CHIPS)':
 'B': CDS_PINID='B';
NODE_NAME     C2485 2
 '@T6G_MB_LIB.T6G(SCH_1):PAGE73_I103@PURE_QUANTA.Q_CAP(CHIPS)':
 'B': CDS_PINID='B';
NODE_NAME     C2489 2
 '@T6G_MB_LIB.T6G(SCH_1):PAGE73_I104@PURE_QUANTA.Q_CAP(CHIPS)':
 'B': CDS_PINID='B';
NODE_NAME     C2497 2
 '@T6G_MB_LIB.T6G(SCH_1):PAGE73_I105@PURE_QUANTA.Q_CAP(CHIPS)':
 'B': CDS_PINID='B';
NODE_NAME     C2502 2
 '@T6G_MB_LIB.T6G(SCH_1):PAGE73_I106@PURE_QUANTA.Q_CAP(CHIPS)':
 'B': CDS_PINID='B';
NODE_NAME     C2506 2
 '@T6G_MB_LIB.T6G(SCH_1):PAGE73_I107@PURE_QUANTA.Q_CAP(CHIPS)':
 'B': CDS_PINID='B';
NODE_NAME     C2115 2
 '@T6G_MB_LIB.T6G(SCH_1):PAGE73_I108@PURE_QUANTA.Q_CAP(CHIPS)':
 'B': CDS_PINID='B';
NODE_NAME     C2121 2
 '@T6G_MB_LIB.T6G(SCH_1):PAGE73_I109@PURE_QUANTA.Q_CAP(CHIPS)':
 'B': CDS_PINID='B';
NODE_NAME     C2496 2
 '@T6G_MB_LIB.T6G(SCH_1):PAGE73_I110@PURE_QUANTA.Q_CAP(CHIPS)':
 'B': CDS_PINID='B';
NODE_NAME     C2495 2
 '@T6G_MB_LIB.T6G(SCH_1):PAGE73_I111@PURE_QUANTA.Q_CAP(CHIPS)':
 'B': CDS_PINID='B';
NODE_NAME     C2501 2
 '@T6G_MB_LIB.T6G(SCH_1):PAGE73_I112@PURE_QUANTA.Q_CAP(CHIPS)':
 'B': CDS_PINID='B';
NODE_NAME     C2500 2
 '@T6G_MB_LIB.T6G(SCH_1):PAGE73_I113@PURE_QUANTA.Q_CAP(CHIPS)':
 'B': CDS_PINID='B';
NODE_NAME     C2494 2
 '@T6G_MB_LIB.T6G(SCH_1):PAGE73_I114@PURE_QUANTA.Q_CAP(CHIPS)':
 'B': CDS_PINID='B';
NODE_NAME     C2499 2
 '@T6G_MB_LIB.T6G(SCH_1):PAGE73_I116@PURE_QUANTA.Q_CAP(CHIPS)':
 'B': CDS_PINID='B';
NODE_NAME     C2505 2
 '@T6G_MB_LIB.T6G(SCH_1):PAGE73_I117@PURE_QUANTA.Q_CAP(CHIPS)':
 'B': CDS_PINID='B';
NODE_NAME     C2504 2
 '@T6G_MB_LIB.T6G(SCH_1):PAGE73_I118@PURE_QUANTA.Q_CAP(CHIPS)':
 'B': CDS_PINID='B';
NODE_NAME     C2113 2
 '@T6G_MB_LIB.T6G(SCH_1):PAGE73_I119@PURE_QUANTA.Q_CAP(CHIPS)':
 'B': CDS_PINID='B';
NODE_NAME     C2114 2
 '@T6G_MB_LIB.T6G(SCH_1):PAGE73_I120@PURE_QUANTA.Q_CAP(CHIPS)':
 'B': CDS_PINID='B';
NODE_NAME     C2120 2
 '@T6G_MB_LIB.T6G(SCH_1):PAGE73_I121@PURE_QUANTA.Q_CAP(CHIPS)':
 'B': CDS_PINID='B';
NODE_NAME     C2119 2
 '@T6G_MB_LIB.T6G(SCH_1):PAGE73_I122@PURE_QUANTA.Q_CAP(CHIPS)':
 'B': CDS_PINID='B';
NODE_NAME     C2503 2
 '@T6G_MB_LIB.T6G(SCH_1):PAGE73_I123@PURE_QUANTA.Q_CAP(CHIPS)':
 'B': CDS_PINID='B';
NODE_NAME     C2508 2
 '@T6G_MB_LIB.T6G(SCH_1):PAGE73_I124@PURE_QUANTA.Q_CAP(CHIPS)':
 'B': CDS_PINID='B';
NODE_NAME     C2118 2
 '@T6G_MB_LIB.T6G(SCH_1):PAGE73_I125@PURE_QUANTA.Q_CAP(CHIPS)':
 'B': CDS_PINID='B';
NODE_NAME     C2472 2
 '@T6G_MB_LIB.T6G(SCH_1):PAGE73_I127@PURE_QUANTA.Q_CAP(CHIPS)':
 'B': CDS_PINID='B';
NODE_NAME     C2479 2
 '@T6G_MB_LIB.T6G(SCH_1):PAGE73_I129@PURE_QUANTA.Q_CAP(CHIPS)':
 'B': CDS_PINID='B';
NODE_NAME     C2471 2
 '@T6G_MB_LIB.T6G(SCH_1):PAGE73_I131@PURE_QUANTA.Q_CAP(CHIPS)':
 'B': CDS_PINID='B';
NODE_NAME     C2470 2
 '@T6G_MB_LIB.T6G(SCH_1):PAGE73_I133@PURE_QUANTA.Q_CAP(CHIPS)':
 'B': CDS_PINID='B';
NODE_NAME     C2478 2
 '@T6G_MB_LIB.T6G(SCH_1):PAGE73_I134@PURE_QUANTA.Q_CAP(CHIPS)':
 'B': CDS_PINID='B';
NODE_NAME     C2477 2
 '@T6G_MB_LIB.T6G(SCH_1):PAGE73_I136@PURE_QUANTA.Q_CAP(CHIPS)':
 'B': CDS_PINID='B';
NODE_NAME     C2103 2
 '@T6G_MB_LIB.T6G(SCH_1):PAGE73_I137@PURE_QUANTA.Q_CAP(CHIPS)':
 'B': CDS_PINID='B';
NODE_NAME     C2106 2
 '@T6G_MB_LIB.T6G(SCH_1):PAGE73_I138@PURE_QUANTA.Q_CAP(CHIPS)':
 'B': CDS_PINID='B';
NODE_NAME     C2484 2
 '@T6G_MB_LIB.T6G(SCH_1):PAGE73_I139@PURE_QUANTA.Q_CAP(CHIPS)':
 'B': CDS_PINID='B';
NODE_NAME     C2102 2
 '@T6G_MB_LIB.T6G(SCH_1):PAGE73_I140@PURE_QUANTA.Q_CAP(CHIPS)':
 'B': CDS_PINID='B';
NODE_NAME     C2105 2
 '@T6G_MB_LIB.T6G(SCH_1):PAGE73_I141@PURE_QUANTA.Q_CAP(CHIPS)':
 'B': CDS_PINID='B';
NODE_NAME     C2104 2
 '@T6G_MB_LIB.T6G(SCH_1):PAGE73_I142@PURE_QUANTA.Q_CAP(CHIPS)':
 'B': CDS_PINID='B';
NODE_NAME     C2108 2
 '@T6G_MB_LIB.T6G(SCH_1):PAGE73_I144@PURE_QUANTA.Q_CAP(CHIPS)':
 'B': CDS_PINID='B';
NODE_NAME     C2107 2
 '@T6G_MB_LIB.T6G(SCH_1):PAGE73_I145@PURE_QUANTA.Q_CAP(CHIPS)':
 'B': CDS_PINID='B';
NODE_NAME     C2493 2
 '@T6G_MB_LIB.T6G(SCH_1):PAGE73_I146@PURE_QUANTA.Q_CAP(CHIPS)':
 'B': CDS_PINID='B';
NODE_NAME     C2498 2
 '@T6G_MB_LIB.T6G(SCH_1):PAGE73_I147@PURE_QUANTA.Q_CAP(CHIPS)':
 'B': CDS_PINID='B';
NODE_NAME     C2109 2
 '@T6G_MB_LIB.T6G(SCH_1):PAGE73_I148@PURE_QUANTA.Q_CAP(CHIPS)':
 'B': CDS_PINID='B';
NODE_NAME     C2111 2
 '@T6G_MB_LIB.T6G(SCH_1):PAGE73_I149@PURE_QUANTA.Q_CAP(CHIPS)':
 'B': CDS_PINID='B';
NODE_NAME     C2112 2
 '@T6G_MB_LIB.T6G(SCH_1):PAGE73_I150@PURE_QUANTA.Q_CAP(CHIPS)':
 'B': CDS_PINID='B';
NODE_NAME     C2110 2
 '@T6G_MB_LIB.T6G(SCH_1):PAGE73_I151@PURE_QUANTA.Q_CAP(CHIPS)':
 'B': CDS_PINID='B';
NODE_NAME     C2507 2
 '@T6G_MB_LIB.T6G(SCH_1):PAGE73_I152@PURE_QUANTA.Q_CAP(CHIPS)':
 'B': CDS_PINID='B';
NODE_NAME     C2117 2
 '@T6G_MB_LIB.T6G(SCH_1):PAGE73_I153@PURE_QUANTA.Q_CAP(CHIPS)':
 'B': CDS_PINID='B';
NODE_NAME     C2116 2
 '@T6G_MB_LIB.T6G(SCH_1):PAGE73_I154@PURE_QUANTA.Q_CAP(CHIPS)':
 'B': CDS_PINID='B';
NODE_NAME     C3921 2
 '@T6G_MB_LIB.T6G(SCH_1):PAGE73_I155@PURE_QUANTA.Q_CAP(CHIPS)':
 'B': CDS_PINID='B';
NODE_NAME     C3922 2
 '@T6G_MB_LIB.T6G(SCH_1):PAGE73_I157@PURE_QUANTA.Q_CAP(CHIPS)':
 'B': CDS_PINID='B';
NODE_NAME     C2126 2
 '@T6G_MB_LIB.T6G(SCH_1):PAGE73_I159@PURE_QUANTA.Q_CAP(CHIPS)':
 'B': CDS_PINID='B';
NODE_NAME     C2125 2
 '@T6G_MB_LIB.T6G(SCH_1):PAGE73_I160@PURE_QUANTA.Q_CAP(CHIPS)':
 'B': CDS_PINID='B';
NODE_NAME     C2511 2
 '@T6G_MB_LIB.T6G(SCH_1):PAGE73_I161@PURE_QUANTA.Q_CAP(CHIPS)':
 'B': CDS_PINID='B';
NODE_NAME     C2510 2
 '@T6G_MB_LIB.T6G(SCH_1):PAGE73_I163@PURE_QUANTA.Q_CAP(CHIPS)':
 'B': CDS_PINID='B';
NODE_NAME     C2124 2
 '@T6G_MB_LIB.T6G(SCH_1):PAGE73_I164@PURE_QUANTA.Q_CAP(CHIPS)':
 'B': CDS_PINID='B';
NODE_NAME     C2128 2
 '@T6G_MB_LIB.T6G(SCH_1):PAGE73_I166@PURE_QUANTA.Q_CAP(CHIPS)':
 'B': CDS_PINID='B';
NODE_NAME     C2123 2
 '@T6G_MB_LIB.T6G(SCH_1):PAGE73_I168@PURE_QUANTA.Q_CAP(CHIPS)':
 'B': CDS_PINID='B';
NODE_NAME     C2122 2
 '@T6G_MB_LIB.T6G(SCH_1):PAGE73_I169@PURE_QUANTA.Q_CAP(CHIPS)':
 'B': CDS_PINID='B';
NODE_NAME     C2509 2
 '@T6G_MB_LIB.T6G(SCH_1):PAGE73_I170@PURE_QUANTA.Q_CAP(CHIPS)':
 'B': CDS_PINID='B';
NODE_NAME     C2127 2
 '@T6G_MB_LIB.T6G(SCH_1):PAGE73_I172@PURE_QUANTA.Q_CAP(CHIPS)':
 'B': CDS_PINID='B';
NODE_NAME     C2442 2
 '@T6G_MB_LIB.T6G(SCH_1):PAGE73_I173@PURE_QUANTA.Q_CAP(CHIPS)':
 'B': CDS_PINID='B';
NODE_NAME     C2435 2
 '@T6G_MB_LIB.T6G(SCH_1):PAGE73_I174@PURE_QUANTA.Q_CAP(CHIPS)':
 'B': CDS_PINID='B';
NODE_NAME     C2428 2
 '@T6G_MB_LIB.T6G(SCH_1):PAGE73_I175@PURE_QUANTA.Q_CAP(CHIPS)':
 'B': CDS_PINID='B';
NODE_NAME     C2661 2
 '@T6G_MB_LIB.T6G(SCH_1):PAGE74_I1@PURE_QUANTA.Q_CAP(CHIPS)':
 'B': CDS_PINID='B';
NODE_NAME     C2660 2
 '@T6G_MB_LIB.T6G(SCH_1):PAGE74_I3@PURE_QUANTA.Q_CAP(CHIPS)':
 'B': CDS_PINID='B';
NODE_NAME     C2664 2
 '@T6G_MB_LIB.T6G(SCH_1):PAGE74_I8@PURE_QUANTA.Q_CAP(CHIPS)':
 'B': CDS_PINID='B';
NODE_NAME     C2663 2
 '@T6G_MB_LIB.T6G(SCH_1):PAGE74_I9@PURE_QUANTA.Q_CAP(CHIPS)':
 'B': CDS_PINID='B';
NODE_NAME     C2665 2
 '@T6G_MB_LIB.T6G(SCH_1):PAGE74_I10@PURE_QUANTA.Q_CAP(CHIPS)':
 'B': CDS_PINID='B';
NODE_NAME     C2667 2
 '@T6G_MB_LIB.T6G(SCH_1):PAGE74_I11@PURE_QUANTA.Q_CAP(CHIPS)':
 'B': CDS_PINID='B';
NODE_NAME     C2668 2
 '@T6G_MB_LIB.T6G(SCH_1):PAGE74_I12@PURE_QUANTA.Q_CAP(CHIPS)':
 'B': CDS_PINID='B';
NODE_NAME     C2669 2
 '@T6G_MB_LIB.T6G(SCH_1):PAGE74_I13@PURE_QUANTA.Q_CAP(CHIPS)':
 'B': CDS_PINID='B';
NODE_NAME     C2670 2
 '@T6G_MB_LIB.T6G(SCH_1):PAGE74_I14@PURE_QUANTA.Q_CAP(CHIPS)':
 'B': CDS_PINID='B';
NODE_NAME     C2671 2
 '@T6G_MB_LIB.T6G(SCH_1):PAGE74_I15@PURE_QUANTA.Q_CAP(CHIPS)':
 'B': CDS_PINID='B';
NODE_NAME     C2672 2
 '@T6G_MB_LIB.T6G(SCH_1):PAGE74_I16@PURE_QUANTA.Q_CAP(CHIPS)':
 'B': CDS_PINID='B';
NODE_NAME     C2673 2
 '@T6G_MB_LIB.T6G(SCH_1):PAGE74_I18@PURE_QUANTA.Q_CAP(CHIPS)':
 'B': CDS_PINID='B';
NODE_NAME     R747 1
 '@T6G_MB_LIB.T6G(SCH_1):PAGE75_I8@PURE_QUANTA.Q_RES(CHIPS)':
 'A': CDS_PINID='A';
NODE_NAME     R748 1
 '@T6G_MB_LIB.T6G(SCH_1):PAGE75_I9@PURE_QUANTA.Q_RES(CHIPS)':
 'A': CDS_PINID='A';
NODE_NAME     R751 1
 '@T6G_MB_LIB.T6G(SCH_1):PAGE75_I12@PURE_QUANTA.Q_RES(CHIPS)':
 'A': CDS_PINID='A';
NODE_NAME     R750 1
 '@T6G_MB_LIB.T6G(SCH_1):PAGE75_I74@PURE_QUANTA.Q_RES(CHIPS)':
 'A': CDS_PINID='A';
NODE_NAME     R753 1
 '@T6G_MB_LIB.T6G(SCH_1):PAGE75_I75@PURE_QUANTA.Q_RES(CHIPS)':
 'A': CDS_PINID='A';
NODE_NAME     C1104 2
 '@T6G_MB_LIB.T6G(SCH_1):PAGE76_I50@PURE_QUANTA.Q_CAP(CHIPS)':
 'B': CDS_PINID='B';
NODE_NAME     C1102 2
 '@T6G_MB_LIB.T6G(SCH_1):PAGE76_I53@PURE_QUANTA.Q_CAP(CHIPS)':
 'B': CDS_PINID='B';
NODE_NAME     C1105 2
 '@T6G_MB_LIB.T6G(SCH_1):PAGE76_I59@PURE_QUANTA.Q_CAP(CHIPS)':
 'B': CDS_PINID='B';
NODE_NAME     U53 10
 '@T6G_MB_LIB.T6G(SCH_1):PAGE76_I63@PURE_QUANTA.SN74AVC4T774PWR(CHIPS)':
 'GND': CDS_PINID='GND';
NODE_NAME     C1103 2
 '@T6G_MB_LIB.T6G(SCH_1):PAGE76_I65@PURE_QUANTA.Q_CAP(CHIPS)':
 'B': CDS_PINID='B';
NODE_NAME     U54 6
 '@T6G_MB_LIB.T6G(SCH_1):PAGE76_I67@PURE_QUANTA.PI4ULS3V304AZMAEX(CHIPS)':
 'GND': CDS_PINID='GND';
NODE_NAME     R702 2
 '@T6G_MB_LIB.T6G(SCH_1):PAGE77_I1@PURE_QUANTA.Q_RES(CHIPS)':
 'B': CDS_PINID='B';
NODE_NAME     R703 2
 '@T6G_MB_LIB.T6G(SCH_1):PAGE77_I5@PURE_QUANTA.Q_RES(CHIPS)':
 'B': CDS_PINID='B';
NODE_NAME     C223 2
 '@T6G_MB_LIB.T6G(SCH_1):PAGE77_I11@PURE_QUANTA.Q_CAP(CHIPS)':
 'B': CDS_PINID='B';
NODE_NAME     U29 2
 '@T6G_MB_LIB.T6G(SCH_1):PAGE77_I15@PURE_QUANTA.SN74LVC2G07DCKR(CHIPS)':
 'GND': CDS_PINID='GND';
NODE_NAME     C224 2
 '@T6G_MB_LIB.T6G(SCH_1):PAGE77_I19@PURE_QUANTA.Q_CAP(CHIPS)':
 'B': CDS_PINID='B';
NODE_NAME     U40 2
 '@T6G_MB_LIB.T6G(SCH_1):PAGE77_I21@PURE_QUANTA.SN74LVC2G07DCKR(CHIPS)':
 'GND': CDS_PINID='GND';
NODE_NAME     R7 2
 '@T6G_MB_LIB.T6G(SCH_1):PAGE85_I499@PURE_QUANTA.Q_RES(CHIPS)':
 'B':XNET_PINS='2',
 CDS_PINID='B';
NODE_NAME     C89 2
 '@T6G_MB_LIB.T6G(SCH_1):PAGE85_I519@PURE_QUANTA.Q_CAP(CHIPS)':
 'B': CDS_PINID='B';
NODE_NAME     C88 2
 '@T6G_MB_LIB.T6G(SCH_1):PAGE85_I523@PURE_QUANTA.Q_CAP(CHIPS)':
 'B': CDS_PINID='B';
NODE_NAME     C142 2
 '@T6G_MB_LIB.T6G(SCH_1):PAGE85_I534@PURE_QUANTA.Q_CAP(CHIPS)':
 'B': CDS_PINID='B';
NODE_NAME     R761 2
 '@T6G_MB_LIB.T6G(SCH_1):PAGE86_I349@PURE_QUANTA.Q_RES(CHIPS)':
 'B': CDS_PINID='B';
NODE_NAME     J15 G1
 '@T6G_MB_LIB.T6G(SCH_1):PAGE86_I352@PURE_QUANTA.SCONN288_DDR506112002KQ(CHIPS)':
 'G1': CDS_PINID='G1';
NODE_NAME     J15 G2
 '@T6G_MB_LIB.T6G(SCH_1):PAGE86_I352@PURE_QUANTA.SCONN288_DDR506112002KQ(CHIPS)':
 'G2': CDS_PINID='G2';
NODE_NAME     J15 G3
 '@T6G_MB_LIB.T6G(SCH_1):PAGE86_I352@PURE_QUANTA.SCONN288_DDR506112002KQ(CHIPS)':
 'G3': CDS_PINID='G3';
NODE_NAME     J15 6
 '@T6G_MB_LIB.T6G(SCH_1):PAGE86_I352@PURE_QUANTA.SCONN288_DDR506112002KQ(CHIPS)':
 'VSS0': CDS_PINID='VSS0';
NODE_NAME     J15 8
 '@T6G_MB_LIB.T6G(SCH_1):PAGE86_I352@PURE_QUANTA.SCONN288_DDR506112002KQ(CHIPS)':
 'VSS1': CDS_PINID='VSS1';
NODE_NAME     J15 10
 '@T6G_MB_LIB.T6G(SCH_1):PAGE86_I352@PURE_QUANTA.SCONN288_DDR506112002KQ(CHIPS)':
 'VSS2': CDS_PINID='VSS2';
NODE_NAME     J15 13
 '@T6G_MB_LIB.T6G(SCH_1):PAGE86_I352@PURE_QUANTA.SCONN288_DDR506112002KQ(CHIPS)':
 'VSS3': CDS_PINID='VSS3';
NODE_NAME     J15 15
 '@T6G_MB_LIB.T6G(SCH_1):PAGE86_I352@PURE_QUANTA.SCONN288_DDR506112002KQ(CHIPS)':
 'VSS4': CDS_PINID='VSS4';
NODE_NAME     J15 17
 '@T6G_MB_LIB.T6G(SCH_1):PAGE86_I352@PURE_QUANTA.SCONN288_DDR506112002KQ(CHIPS)':
 'VSS5': CDS_PINID='VSS5';
NODE_NAME     J15 19
 '@T6G_MB_LIB.T6G(SCH_1):PAGE86_I352@PURE_QUANTA.SCONN288_DDR506112002KQ(CHIPS)':
 'VSS6': CDS_PINID='VSS6';
NODE_NAME     J15 21
 '@T6G_MB_LIB.T6G(SCH_1):PAGE86_I352@PURE_QUANTA.SCONN288_DDR506112002KQ(CHIPS)':
 'VSS7': CDS_PINID='VSS7';
NODE_NAME     J15 24
 '@T6G_MB_LIB.T6G(SCH_1):PAGE86_I352@PURE_QUANTA.SCONN288_DDR506112002KQ(CHIPS)':
 'VSS8': CDS_PINID='VSS8';
NODE_NAME     J15 26
 '@T6G_MB_LIB.T6G(SCH_1):PAGE86_I352@PURE_QUANTA.SCONN288_DDR506112002KQ(CHIPS)':
 'VSS9': CDS_PINID='VSS9';
NODE_NAME     J15 28
 '@T6G_MB_LIB.T6G(SCH_1):PAGE86_I352@PURE_QUANTA.SCONN288_DDR506112002KQ(CHIPS)':
 'VSS10': CDS_PINID='VSS10';
NODE_NAME     J15 30
 '@T6G_MB_LIB.T6G(SCH_1):PAGE86_I352@PURE_QUANTA.SCONN288_DDR506112002KQ(CHIPS)':
 'VSS11': CDS_PINID='VSS11';
NODE_NAME     J15 32
 '@T6G_MB_LIB.T6G(SCH_1):PAGE86_I352@PURE_QUANTA.SCONN288_DDR506112002KQ(CHIPS)':
 'VSS12': CDS_PINID='VSS12';
NODE_NAME     J15 35
 '@T6G_MB_LIB.T6G(SCH_1):PAGE86_I352@PURE_QUANTA.SCONN288_DDR506112002KQ(CHIPS)':
 'VSS13': CDS_PINID='VSS13';
NODE_NAME     J15 37
 '@T6G_MB_LIB.T6G(SCH_1):PAGE86_I352@PURE_QUANTA.SCONN288_DDR506112002KQ(CHIPS)':
 'VSS14': CDS_PINID='VSS14';
NODE_NAME     J15 39
 '@T6G_MB_LIB.T6G(SCH_1):PAGE86_I352@PURE_QUANTA.SCONN288_DDR506112002KQ(CHIPS)':
 'VSS15': CDS_PINID='VSS15';
NODE_NAME     J15 41
 '@T6G_MB_LIB.T6G(SCH_1):PAGE86_I352@PURE_QUANTA.SCONN288_DDR506112002KQ(CHIPS)':
 'VSS16': CDS_PINID='VSS16';
NODE_NAME     J15 43
 '@T6G_MB_LIB.T6G(SCH_1):PAGE86_I352@PURE_QUANTA.SCONN288_DDR506112002KQ(CHIPS)':
 'VSS17': CDS_PINID='VSS17';
NODE_NAME     J15 46
 '@T6G_MB_LIB.T6G(SCH_1):PAGE86_I352@PURE_QUANTA.SCONN288_DDR506112002KQ(CHIPS)':
 'VSS18': CDS_PINID='VSS18';
NODE_NAME     J15 48
 '@T6G_MB_LIB.T6G(SCH_1):PAGE86_I352@PURE_QUANTA.SCONN288_DDR506112002KQ(CHIPS)':
 'VSS19': CDS_PINID='VSS19';
NODE_NAME     J15 50
 '@T6G_MB_LIB.T6G(SCH_1):PAGE86_I352@PURE_QUANTA.SCONN288_DDR506112002KQ(CHIPS)':
 'VSS20': CDS_PINID='VSS20';
NODE_NAME     J15 52
 '@T6G_MB_LIB.T6G(SCH_1):PAGE86_I352@PURE_QUANTA.SCONN288_DDR506112002KQ(CHIPS)':
 'VSS21': CDS_PINID='VSS21';
NODE_NAME     J15 54
 '@T6G_MB_LIB.T6G(SCH_1):PAGE86_I352@PURE_QUANTA.SCONN288_DDR506112002KQ(CHIPS)':
 'VSS22': CDS_PINID='VSS22';
NODE_NAME     J15 57
 '@T6G_MB_LIB.T6G(SCH_1):PAGE86_I352@PURE_QUANTA.SCONN288_DDR506112002KQ(CHIPS)':
 'VSS23': CDS_PINID='VSS23';
NODE_NAME     J15 59
 '@T6G_MB_LIB.T6G(SCH_1):PAGE86_I352@PURE_QUANTA.SCONN288_DDR506112002KQ(CHIPS)':
 'VSS24': CDS_PINID='VSS24';
NODE_NAME     J15 61
 '@T6G_MB_LIB.T6G(SCH_1):PAGE86_I352@PURE_QUANTA.SCONN288_DDR506112002KQ(CHIPS)':
 'VSS25': CDS_PINID='VSS25';
NODE_NAME     J15 63
 '@T6G_MB_LIB.T6G(SCH_1):PAGE86_I352@PURE_QUANTA.SCONN288_DDR506112002KQ(CHIPS)':
 'VSS26': CDS_PINID='VSS26';
NODE_NAME     J15 65
 '@T6G_MB_LIB.T6G(SCH_1):PAGE86_I352@PURE_QUANTA.SCONN288_DDR506112002KQ(CHIPS)':
 'VSS27': CDS_PINID='VSS27';
NODE_NAME     J15 67
 '@T6G_MB_LIB.T6G(SCH_1):PAGE86_I352@PURE_QUANTA.SCONN288_DDR506112002KQ(CHIPS)':
 'VSS28': CDS_PINID='VSS28';
NODE_NAME     J15 69
 '@T6G_MB_LIB.T6G(SCH_1):PAGE86_I352@PURE_QUANTA.SCONN288_DDR506112002KQ(CHIPS)':
 'VSS29': CDS_PINID='VSS29';
NODE_NAME     J15 71
 '@T6G_MB_LIB.T6G(SCH_1):PAGE86_I352@PURE_QUANTA.SCONN288_DDR506112002KQ(CHIPS)':
 'VSS30': CDS_PINID='VSS30';
NODE_NAME     J15 73
 '@T6G_MB_LIB.T6G(SCH_1):PAGE86_I352@PURE_QUANTA.SCONN288_DDR506112002KQ(CHIPS)':
 'VSS31': CDS_PINID='VSS31';
NODE_NAME     J15 75
 '@T6G_MB_LIB.T6G(SCH_1):PAGE86_I352@PURE_QUANTA.SCONN288_DDR506112002KQ(CHIPS)':
 'VSS32': CDS_PINID='VSS32';
NODE_NAME     J15 77
 '@T6G_MB_LIB.T6G(SCH_1):PAGE86_I352@PURE_QUANTA.SCONN288_DDR506112002KQ(CHIPS)':
 'VSS33': CDS_PINID='VSS33';
NODE_NAME     J15 79
 '@T6G_MB_LIB.T6G(SCH_1):PAGE86_I352@PURE_QUANTA.SCONN288_DDR506112002KQ(CHIPS)':
 'VSS34': CDS_PINID='VSS34';
NODE_NAME     J15 81
 '@T6G_MB_LIB.T6G(SCH_1):PAGE86_I352@PURE_QUANTA.SCONN288_DDR506112002KQ(CHIPS)':
 'VSS35': CDS_PINID='VSS35';
NODE_NAME     J15 83
 '@T6G_MB_LIB.T6G(SCH_1):PAGE86_I352@PURE_QUANTA.SCONN288_DDR506112002KQ(CHIPS)':
 'VSS36': CDS_PINID='VSS36';
NODE_NAME     J15 85
 '@T6G_MB_LIB.T6G(SCH_1):PAGE86_I352@PURE_QUANTA.SCONN288_DDR506112002KQ(CHIPS)':
 'VSS37': CDS_PINID='VSS37';
NODE_NAME     J15 88
 '@T6G_MB_LIB.T6G(SCH_1):PAGE86_I352@PURE_QUANTA.SCONN288_DDR506112002KQ(CHIPS)':
 'VSS38': CDS_PINID='VSS38';
NODE_NAME     J15 90
 '@T6G_MB_LIB.T6G(SCH_1):PAGE86_I352@PURE_QUANTA.SCONN288_DDR506112002KQ(CHIPS)':
 'VSS39': CDS_PINID='VSS39';
NODE_NAME     J15 92
 '@T6G_MB_LIB.T6G(SCH_1):PAGE86_I352@PURE_QUANTA.SCONN288_DDR506112002KQ(CHIPS)':
 'VSS40': CDS_PINID='VSS40';
NODE_NAME     J15 95
 '@T6G_MB_LIB.T6G(SCH_1):PAGE86_I352@PURE_QUANTA.SCONN288_DDR506112002KQ(CHIPS)':
 'VSS41': CDS_PINID='VSS41';
NODE_NAME     J15 97
 '@T6G_MB_LIB.T6G(SCH_1):PAGE86_I352@PURE_QUANTA.SCONN288_DDR506112002KQ(CHIPS)':
 'VSS42': CDS_PINID='VSS42';
NODE_NAME     J15 99
 '@T6G_MB_LIB.T6G(SCH_1):PAGE86_I352@PURE_QUANTA.SCONN288_DDR506112002KQ(CHIPS)':
 'VSS43': CDS_PINID='VSS43';
NODE_NAME     J15 101
 '@T6G_MB_LIB.T6G(SCH_1):PAGE86_I352@PURE_QUANTA.SCONN288_DDR506112002KQ(CHIPS)':
 'VSS44': CDS_PINID='VSS44';
NODE_NAME     J15 103
 '@T6G_MB_LIB.T6G(SCH_1):PAGE86_I352@PURE_QUANTA.SCONN288_DDR506112002KQ(CHIPS)':
 'VSS45': CDS_PINID='VSS45';
NODE_NAME     J15 106
 '@T6G_MB_LIB.T6G(SCH_1):PAGE86_I352@PURE_QUANTA.SCONN288_DDR506112002KQ(CHIPS)':
 'VSS46': CDS_PINID='VSS46';
NODE_NAME     J15 108
 '@T6G_MB_LIB.T6G(SCH_1):PAGE86_I352@PURE_QUANTA.SCONN288_DDR506112002KQ(CHIPS)':
 'VSS47': CDS_PINID='VSS47';
NODE_NAME     J15 110
 '@T6G_MB_LIB.T6G(SCH_1):PAGE86_I352@PURE_QUANTA.SCONN288_DDR506112002KQ(CHIPS)':
 'VSS48': CDS_PINID='VSS48';
NODE_NAME     J15 112
 '@T6G_MB_LIB.T6G(SCH_1):PAGE86_I352@PURE_QUANTA.SCONN288_DDR506112002KQ(CHIPS)':
 'VSS49': CDS_PINID='VSS49';
NODE_NAME     J15 114
 '@T6G_MB_LIB.T6G(SCH_1):PAGE86_I352@PURE_QUANTA.SCONN288_DDR506112002KQ(CHIPS)':
 'VSS50': CDS_PINID='VSS50';
NODE_NAME     J15 117
 '@T6G_MB_LIB.T6G(SCH_1):PAGE86_I352@PURE_QUANTA.SCONN288_DDR506112002KQ(CHIPS)':
 'VSS51': CDS_PINID='VSS51';
NODE_NAME     J15 119
 '@T6G_MB_LIB.T6G(SCH_1):PAGE86_I352@PURE_QUANTA.SCONN288_DDR506112002KQ(CHIPS)':
 'VSS52': CDS_PINID='VSS52';
NODE_NAME     J15 121
 '@T6G_MB_LIB.T6G(SCH_1):PAGE86_I352@PURE_QUANTA.SCONN288_DDR506112002KQ(CHIPS)':
 'VSS53': CDS_PINID='VSS53';
NODE_NAME     J15 123
 '@T6G_MB_LIB.T6G(SCH_1):PAGE86_I352@PURE_QUANTA.SCONN288_DDR506112002KQ(CHIPS)':
 'VSS54': CDS_PINID='VSS54';
NODE_NAME     J15 125
 '@T6G_MB_LIB.T6G(SCH_1):PAGE86_I352@PURE_QUANTA.SCONN288_DDR506112002KQ(CHIPS)':
 'VSS55': CDS_PINID='VSS55';
NODE_NAME     J15 128
 '@T6G_MB_LIB.T6G(SCH_1):PAGE86_I352@PURE_QUANTA.SCONN288_DDR506112002KQ(CHIPS)':
 'VSS56': CDS_PINID='VSS56';
NODE_NAME     J15 130
 '@T6G_MB_LIB.T6G(SCH_1):PAGE86_I352@PURE_QUANTA.SCONN288_DDR506112002KQ(CHIPS)':
 'VSS57': CDS_PINID='VSS57';
NODE_NAME     J15 132
 '@T6G_MB_LIB.T6G(SCH_1):PAGE86_I352@PURE_QUANTA.SCONN288_DDR506112002KQ(CHIPS)':
 'VSS58': CDS_PINID='VSS58';
NODE_NAME     J15 134
 '@T6G_MB_LIB.T6G(SCH_1):PAGE86_I352@PURE_QUANTA.SCONN288_DDR506112002KQ(CHIPS)':
 'VSS59': CDS_PINID='VSS59';
NODE_NAME     J15 136
 '@T6G_MB_LIB.T6G(SCH_1):PAGE86_I352@PURE_QUANTA.SCONN288_DDR506112002KQ(CHIPS)':
 'VSS60': CDS_PINID='VSS60';
NODE_NAME     J15 139
 '@T6G_MB_LIB.T6G(SCH_1):PAGE86_I352@PURE_QUANTA.SCONN288_DDR506112002KQ(CHIPS)':
 'VSS61': CDS_PINID='VSS61';
NODE_NAME     J15 141
 '@T6G_MB_LIB.T6G(SCH_1):PAGE86_I352@PURE_QUANTA.SCONN288_DDR506112002KQ(CHIPS)':
 'VSS62': CDS_PINID='VSS62';
NODE_NAME     J15 143
 '@T6G_MB_LIB.T6G(SCH_1):PAGE86_I352@PURE_QUANTA.SCONN288_DDR506112002KQ(CHIPS)':
 'VSS63': CDS_PINID='VSS63';
NODE_NAME     J15 151
 '@T6G_MB_LIB.T6G(SCH_1):PAGE86_I352@PURE_QUANTA.SCONN288_DDR506112002KQ(CHIPS)':
 'VSS64': CDS_PINID='VSS64';
NODE_NAME     J15 153
 '@T6G_MB_LIB.T6G(SCH_1):PAGE86_I352@PURE_QUANTA.SCONN288_DDR506112002KQ(CHIPS)':
 'VSS65': CDS_PINID='VSS65';
NODE_NAME     J15 155
 '@T6G_MB_LIB.T6G(SCH_1):PAGE86_I352@PURE_QUANTA.SCONN288_DDR506112002KQ(CHIPS)':
 'VSS66': CDS_PINID='VSS66';
NODE_NAME     J15 158
 '@T6G_MB_LIB.T6G(SCH_1):PAGE86_I352@PURE_QUANTA.SCONN288_DDR506112002KQ(CHIPS)':
 'VSS67': CDS_PINID='VSS67';
NODE_NAME     J15 160
 '@T6G_MB_LIB.T6G(SCH_1):PAGE86_I352@PURE_QUANTA.SCONN288_DDR506112002KQ(CHIPS)':
 'VSS68': CDS_PINID='VSS68';
NODE_NAME     J15 162
 '@T6G_MB_LIB.T6G(SCH_1):PAGE86_I352@PURE_QUANTA.SCONN288_DDR506112002KQ(CHIPS)':
 'VSS69': CDS_PINID='VSS69';
NODE_NAME     J15 164
 '@T6G_MB_LIB.T6G(SCH_1):PAGE86_I352@PURE_QUANTA.SCONN288_DDR506112002KQ(CHIPS)':
 'VSS70': CDS_PINID='VSS70';
NODE_NAME     J15 166
 '@T6G_MB_LIB.T6G(SCH_1):PAGE86_I352@PURE_QUANTA.SCONN288_DDR506112002KQ(CHIPS)':
 'VSS71': CDS_PINID='VSS71';
NODE_NAME     J15 169
 '@T6G_MB_LIB.T6G(SCH_1):PAGE86_I352@PURE_QUANTA.SCONN288_DDR506112002KQ(CHIPS)':
 'VSS72': CDS_PINID='VSS72';
NODE_NAME     J15 171
 '@T6G_MB_LIB.T6G(SCH_1):PAGE86_I352@PURE_QUANTA.SCONN288_DDR506112002KQ(CHIPS)':
 'VSS73': CDS_PINID='VSS73';
NODE_NAME     J15 173
 '@T6G_MB_LIB.T6G(SCH_1):PAGE86_I352@PURE_QUANTA.SCONN288_DDR506112002KQ(CHIPS)':
 'VSS74': CDS_PINID='VSS74';
NODE_NAME     J15 175
 '@T6G_MB_LIB.T6G(SCH_1):PAGE86_I352@PURE_QUANTA.SCONN288_DDR506112002KQ(CHIPS)':
 'VSS75': CDS_PINID='VSS75';
NODE_NAME     J15 177
 '@T6G_MB_LIB.T6G(SCH_1):PAGE86_I352@PURE_QUANTA.SCONN288_DDR506112002KQ(CHIPS)':
 'VSS76': CDS_PINID='VSS76';
NODE_NAME     J15 180
 '@T6G_MB_LIB.T6G(SCH_1):PAGE86_I352@PURE_QUANTA.SCONN288_DDR506112002KQ(CHIPS)':
 'VSS77': CDS_PINID='VSS77';
NODE_NAME     J15 182
 '@T6G_MB_LIB.T6G(SCH_1):PAGE86_I352@PURE_QUANTA.SCONN288_DDR506112002KQ(CHIPS)':
 'VSS78': CDS_PINID='VSS78';
NODE_NAME     J15 184
 '@T6G_MB_LIB.T6G(SCH_1):PAGE86_I352@PURE_QUANTA.SCONN288_DDR506112002KQ(CHIPS)':
 'VSS79': CDS_PINID='VSS79';
NODE_NAME     J15 186
 '@T6G_MB_LIB.T6G(SCH_1):PAGE86_I352@PURE_QUANTA.SCONN288_DDR506112002KQ(CHIPS)':
 'VSS80': CDS_PINID='VSS80';
NODE_NAME     J15 188
 '@T6G_MB_LIB.T6G(SCH_1):PAGE86_I352@PURE_QUANTA.SCONN288_DDR506112002KQ(CHIPS)':
 'VSS81': CDS_PINID='VSS81';
NODE_NAME     J15 191
 '@T6G_MB_LIB.T6G(SCH_1):PAGE86_I352@PURE_QUANTA.SCONN288_DDR506112002KQ(CHIPS)':
 'VSS82': CDS_PINID='VSS82';
NODE_NAME     J15 193
 '@T6G_MB_LIB.T6G(SCH_1):PAGE86_I352@PURE_QUANTA.SCONN288_DDR506112002KQ(CHIPS)':
 'VSS83': CDS_PINID='VSS83';
NODE_NAME     J15 195
 '@T6G_MB_LIB.T6G(SCH_1):PAGE86_I352@PURE_QUANTA.SCONN288_DDR506112002KQ(CHIPS)':
 'VSS84': CDS_PINID='VSS84';
NODE_NAME     J15 197
 '@T6G_MB_LIB.T6G(SCH_1):PAGE86_I352@PURE_QUANTA.SCONN288_DDR506112002KQ(CHIPS)':
 'VSS85': CDS_PINID='VSS85';
NODE_NAME     J15 199
 '@T6G_MB_LIB.T6G(SCH_1):PAGE86_I352@PURE_QUANTA.SCONN288_DDR506112002KQ(CHIPS)':
 'VSS86': CDS_PINID='VSS86';
NODE_NAME     J15 202
 '@T6G_MB_LIB.T6G(SCH_1):PAGE86_I352@PURE_QUANTA.SCONN288_DDR506112002KQ(CHIPS)':
 'VSS87': CDS_PINID='VSS87';
NODE_NAME     J15 204
 '@T6G_MB_LIB.T6G(SCH_1):PAGE86_I352@PURE_QUANTA.SCONN288_DDR506112002KQ(CHIPS)':
 'VSS88': CDS_PINID='VSS88';
NODE_NAME     J15 206
 '@T6G_MB_LIB.T6G(SCH_1):PAGE86_I352@PURE_QUANTA.SCONN288_DDR506112002KQ(CHIPS)':
 'VSS89': CDS_PINID='VSS89';
NODE_NAME     J15 208
 '@T6G_MB_LIB.T6G(SCH_1):PAGE86_I352@PURE_QUANTA.SCONN288_DDR506112002KQ(CHIPS)':
 'VSS90': CDS_PINID='VSS90';
NODE_NAME     J15 210
 '@T6G_MB_LIB.T6G(SCH_1):PAGE86_I352@PURE_QUANTA.SCONN288_DDR506112002KQ(CHIPS)':
 'VSS91': CDS_PINID='VSS91';
NODE_NAME     J15 212
 '@T6G_MB_LIB.T6G(SCH_1):PAGE86_I352@PURE_QUANTA.SCONN288_DDR506112002KQ(CHIPS)':
 'VSS92': CDS_PINID='VSS92';
NODE_NAME     J15 214
 '@T6G_MB_LIB.T6G(SCH_1):PAGE86_I352@PURE_QUANTA.SCONN288_DDR506112002KQ(CHIPS)':
 'VSS93': CDS_PINID='VSS93';
NODE_NAME     J15 216
 '@T6G_MB_LIB.T6G(SCH_1):PAGE86_I352@PURE_QUANTA.SCONN288_DDR506112002KQ(CHIPS)':
 'VSS94': CDS_PINID='VSS94';
NODE_NAME     J15 219
 '@T6G_MB_LIB.T6G(SCH_1):PAGE86_I352@PURE_QUANTA.SCONN288_DDR506112002KQ(CHIPS)':
 'VSS95': CDS_PINID='VSS95';
NODE_NAME     J15 222
 '@T6G_MB_LIB.T6G(SCH_1):PAGE86_I352@PURE_QUANTA.SCONN288_DDR506112002KQ(CHIPS)':
 'VSS96': CDS_PINID='VSS96';
NODE_NAME     J15 224
 '@T6G_MB_LIB.T6G(SCH_1):PAGE86_I352@PURE_QUANTA.SCONN288_DDR506112002KQ(CHIPS)':
 'VSS97': CDS_PINID='VSS97';
NODE_NAME     J15 226
 '@T6G_MB_LIB.T6G(SCH_1):PAGE86_I352@PURE_QUANTA.SCONN288_DDR506112002KQ(CHIPS)':
 'VSS98': CDS_PINID='VSS98';
NODE_NAME     J15 228
 '@T6G_MB_LIB.T6G(SCH_1):PAGE86_I352@PURE_QUANTA.SCONN288_DDR506112002KQ(CHIPS)':
 'VSS99': CDS_PINID='VSS99';
NODE_NAME     J15 230
 '@T6G_MB_LIB.T6G(SCH_1):PAGE86_I352@PURE_QUANTA.SCONN288_DDR506112002KQ(CHIPS)':
 'VSS100': CDS_PINID='VSS100';
NODE_NAME     J15 233
 '@T6G_MB_LIB.T6G(SCH_1):PAGE86_I352@PURE_QUANTA.SCONN288_DDR506112002KQ(CHIPS)':
 'VSS101': CDS_PINID='VSS101';
NODE_NAME     J15 235
 '@T6G_MB_LIB.T6G(SCH_1):PAGE86_I352@PURE_QUANTA.SCONN288_DDR506112002KQ(CHIPS)':
 'VSS102': CDS_PINID='VSS102';
NODE_NAME     J15 237
 '@T6G_MB_LIB.T6G(SCH_1):PAGE86_I352@PURE_QUANTA.SCONN288_DDR506112002KQ(CHIPS)':
 'VSS103': CDS_PINID='VSS103';
NODE_NAME     J15 240
 '@T6G_MB_LIB.T6G(SCH_1):PAGE86_I352@PURE_QUANTA.SCONN288_DDR506112002KQ(CHIPS)':
 'VSS104': CDS_PINID='VSS104';
NODE_NAME     J15 242
 '@T6G_MB_LIB.T6G(SCH_1):PAGE86_I352@PURE_QUANTA.SCONN288_DDR506112002KQ(CHIPS)':
 'VSS105': CDS_PINID='VSS105';
NODE_NAME     J15 244
 '@T6G_MB_LIB.T6G(SCH_1):PAGE86_I352@PURE_QUANTA.SCONN288_DDR506112002KQ(CHIPS)':
 'VSS106': CDS_PINID='VSS106';
NODE_NAME     J15 246
 '@T6G_MB_LIB.T6G(SCH_1):PAGE86_I352@PURE_QUANTA.SCONN288_DDR506112002KQ(CHIPS)':
 'VSS107': CDS_PINID='VSS107';
NODE_NAME     J15 248
 '@T6G_MB_LIB.T6G(SCH_1):PAGE86_I352@PURE_QUANTA.SCONN288_DDR506112002KQ(CHIPS)':
 'VSS108': CDS_PINID='VSS108';
NODE_NAME     J15 251
 '@T6G_MB_LIB.T6G(SCH_1):PAGE86_I352@PURE_QUANTA.SCONN288_DDR506112002KQ(CHIPS)':
 'VSS109': CDS_PINID='VSS109';
NODE_NAME     J15 253
 '@T6G_MB_LIB.T6G(SCH_1):PAGE86_I352@PURE_QUANTA.SCONN288_DDR506112002KQ(CHIPS)':
 'VSS110': CDS_PINID='VSS110';
NODE_NAME     J15 255
 '@T6G_MB_LIB.T6G(SCH_1):PAGE86_I352@PURE_QUANTA.SCONN288_DDR506112002KQ(CHIPS)':
 'VSS111': CDS_PINID='VSS111';
NODE_NAME     J15 257
 '@T6G_MB_LIB.T6G(SCH_1):PAGE86_I352@PURE_QUANTA.SCONN288_DDR506112002KQ(CHIPS)':
 'VSS112': CDS_PINID='VSS112';
NODE_NAME     J15 259
 '@T6G_MB_LIB.T6G(SCH_1):PAGE86_I352@PURE_QUANTA.SCONN288_DDR506112002KQ(CHIPS)':
 'VSS113': CDS_PINID='VSS113';
NODE_NAME     J15 262
 '@T6G_MB_LIB.T6G(SCH_1):PAGE86_I352@PURE_QUANTA.SCONN288_DDR506112002KQ(CHIPS)':
 'VSS114': CDS_PINID='VSS114';
NODE_NAME     J15 264
 '@T6G_MB_LIB.T6G(SCH_1):PAGE86_I352@PURE_QUANTA.SCONN288_DDR506112002KQ(CHIPS)':
 'VSS115': CDS_PINID='VSS115';
NODE_NAME     J15 266
 '@T6G_MB_LIB.T6G(SCH_1):PAGE86_I352@PURE_QUANTA.SCONN288_DDR506112002KQ(CHIPS)':
 'VSS116': CDS_PINID='VSS116';
NODE_NAME     J15 268
 '@T6G_MB_LIB.T6G(SCH_1):PAGE86_I352@PURE_QUANTA.SCONN288_DDR506112002KQ(CHIPS)':
 'VSS117': CDS_PINID='VSS117';
NODE_NAME     J15 270
 '@T6G_MB_LIB.T6G(SCH_1):PAGE86_I352@PURE_QUANTA.SCONN288_DDR506112002KQ(CHIPS)':
 'VSS118': CDS_PINID='VSS118';
NODE_NAME     J15 273
 '@T6G_MB_LIB.T6G(SCH_1):PAGE86_I352@PURE_QUANTA.SCONN288_DDR506112002KQ(CHIPS)':
 'VSS119': CDS_PINID='VSS119';
NODE_NAME     J15 275
 '@T6G_MB_LIB.T6G(SCH_1):PAGE86_I352@PURE_QUANTA.SCONN288_DDR506112002KQ(CHIPS)':
 'VSS120': CDS_PINID='VSS120';
NODE_NAME     J15 277
 '@T6G_MB_LIB.T6G(SCH_1):PAGE86_I352@PURE_QUANTA.SCONN288_DDR506112002KQ(CHIPS)':
 'VSS121': CDS_PINID='VSS121';
NODE_NAME     J15 279
 '@T6G_MB_LIB.T6G(SCH_1):PAGE86_I352@PURE_QUANTA.SCONN288_DDR506112002KQ(CHIPS)':
 'VSS122': CDS_PINID='VSS122';
NODE_NAME     J15 281
 '@T6G_MB_LIB.T6G(SCH_1):PAGE86_I352@PURE_QUANTA.SCONN288_DDR506112002KQ(CHIPS)':
 'VSS123': CDS_PINID='VSS123';
NODE_NAME     J15 284
 '@T6G_MB_LIB.T6G(SCH_1):PAGE86_I352@PURE_QUANTA.SCONN288_DDR506112002KQ(CHIPS)':
 'VSS124': CDS_PINID='VSS124';
NODE_NAME     J15 286
 '@T6G_MB_LIB.T6G(SCH_1):PAGE86_I352@PURE_QUANTA.SCONN288_DDR506112002KQ(CHIPS)':
 'VSS125': CDS_PINID='VSS125';
NODE_NAME     J15 288
 '@T6G_MB_LIB.T6G(SCH_1):PAGE86_I352@PURE_QUANTA.SCONN288_DDR506112002KQ(CHIPS)':
 'VSS126': CDS_PINID='VSS126';
NODE_NAME     C92 2
 '@T6G_MB_LIB.T6G(SCH_1):PAGE86_I362@PURE_QUANTA.Q_CAP(CHIPS)':
 'B': CDS_PINID='B';
NODE_NAME     C143 2
 '@T6G_MB_LIB.T6G(SCH_1):PAGE86_I369@PURE_QUANTA.Q_CAP(CHIPS)':
 'B': CDS_PINID='B';
NODE_NAME     C145 2
 '@T6G_MB_LIB.T6G(SCH_1):PAGE86_I370@PURE_QUANTA.Q_CAP(CHIPS)':
 'B': CDS_PINID='B';
NODE_NAME     R762 2
 '@T6G_MB_LIB.T6G(SCH_1):PAGE87_I349@PURE_QUANTA.Q_RES(CHIPS)':
 'B': CDS_PINID='B';
NODE_NAME     J17 G1
 '@T6G_MB_LIB.T6G(SCH_1):PAGE87_I352@PURE_QUANTA.SCONN288_DDR506112002KQ(CHIPS)':
 'G1': CDS_PINID='G1';
NODE_NAME     J17 G2
 '@T6G_MB_LIB.T6G(SCH_1):PAGE87_I352@PURE_QUANTA.SCONN288_DDR506112002KQ(CHIPS)':
 'G2': CDS_PINID='G2';
NODE_NAME     J17 G3
 '@T6G_MB_LIB.T6G(SCH_1):PAGE87_I352@PURE_QUANTA.SCONN288_DDR506112002KQ(CHIPS)':
 'G3': CDS_PINID='G3';
NODE_NAME     J17 6
 '@T6G_MB_LIB.T6G(SCH_1):PAGE87_I352@PURE_QUANTA.SCONN288_DDR506112002KQ(CHIPS)':
 'VSS0': CDS_PINID='VSS0';
NODE_NAME     J17 8
 '@T6G_MB_LIB.T6G(SCH_1):PAGE87_I352@PURE_QUANTA.SCONN288_DDR506112002KQ(CHIPS)':
 'VSS1': CDS_PINID='VSS1';
NODE_NAME     J17 10
 '@T6G_MB_LIB.T6G(SCH_1):PAGE87_I352@PURE_QUANTA.SCONN288_DDR506112002KQ(CHIPS)':
 'VSS2': CDS_PINID='VSS2';
NODE_NAME     J17 13
 '@T6G_MB_LIB.T6G(SCH_1):PAGE87_I352@PURE_QUANTA.SCONN288_DDR506112002KQ(CHIPS)':
 'VSS3': CDS_PINID='VSS3';
NODE_NAME     J17 15
 '@T6G_MB_LIB.T6G(SCH_1):PAGE87_I352@PURE_QUANTA.SCONN288_DDR506112002KQ(CHIPS)':
 'VSS4': CDS_PINID='VSS4';
NODE_NAME     J17 17
 '@T6G_MB_LIB.T6G(SCH_1):PAGE87_I352@PURE_QUANTA.SCONN288_DDR506112002KQ(CHIPS)':
 'VSS5': CDS_PINID='VSS5';
NODE_NAME     J17 19
 '@T6G_MB_LIB.T6G(SCH_1):PAGE87_I352@PURE_QUANTA.SCONN288_DDR506112002KQ(CHIPS)':
 'VSS6': CDS_PINID='VSS6';
NODE_NAME     J17 21
 '@T6G_MB_LIB.T6G(SCH_1):PAGE87_I352@PURE_QUANTA.SCONN288_DDR506112002KQ(CHIPS)':
 'VSS7': CDS_PINID='VSS7';
NODE_NAME     J17 24
 '@T6G_MB_LIB.T6G(SCH_1):PAGE87_I352@PURE_QUANTA.SCONN288_DDR506112002KQ(CHIPS)':
 'VSS8': CDS_PINID='VSS8';
NODE_NAME     J17 26
 '@T6G_MB_LIB.T6G(SCH_1):PAGE87_I352@PURE_QUANTA.SCONN288_DDR506112002KQ(CHIPS)':
 'VSS9': CDS_PINID='VSS9';
NODE_NAME     J17 28
 '@T6G_MB_LIB.T6G(SCH_1):PAGE87_I352@PURE_QUANTA.SCONN288_DDR506112002KQ(CHIPS)':
 'VSS10': CDS_PINID='VSS10';
NODE_NAME     J17 30
 '@T6G_MB_LIB.T6G(SCH_1):PAGE87_I352@PURE_QUANTA.SCONN288_DDR506112002KQ(CHIPS)':
 'VSS11': CDS_PINID='VSS11';
NODE_NAME     J17 32
 '@T6G_MB_LIB.T6G(SCH_1):PAGE87_I352@PURE_QUANTA.SCONN288_DDR506112002KQ(CHIPS)':
 'VSS12': CDS_PINID='VSS12';
NODE_NAME     J17 35
 '@T6G_MB_LIB.T6G(SCH_1):PAGE87_I352@PURE_QUANTA.SCONN288_DDR506112002KQ(CHIPS)':
 'VSS13': CDS_PINID='VSS13';
NODE_NAME     J17 37
 '@T6G_MB_LIB.T6G(SCH_1):PAGE87_I352@PURE_QUANTA.SCONN288_DDR506112002KQ(CHIPS)':
 'VSS14': CDS_PINID='VSS14';
NODE_NAME     J17 39
 '@T6G_MB_LIB.T6G(SCH_1):PAGE87_I352@PURE_QUANTA.SCONN288_DDR506112002KQ(CHIPS)':
 'VSS15': CDS_PINID='VSS15';
NODE_NAME     J17 41
 '@T6G_MB_LIB.T6G(SCH_1):PAGE87_I352@PURE_QUANTA.SCONN288_DDR506112002KQ(CHIPS)':
 'VSS16': CDS_PINID='VSS16';
NODE_NAME     J17 43
 '@T6G_MB_LIB.T6G(SCH_1):PAGE87_I352@PURE_QUANTA.SCONN288_DDR506112002KQ(CHIPS)':
 'VSS17': CDS_PINID='VSS17';
NODE_NAME     J17 46
 '@T6G_MB_LIB.T6G(SCH_1):PAGE87_I352@PURE_QUANTA.SCONN288_DDR506112002KQ(CHIPS)':
 'VSS18': CDS_PINID='VSS18';
NODE_NAME     J17 48
 '@T6G_MB_LIB.T6G(SCH_1):PAGE87_I352@PURE_QUANTA.SCONN288_DDR506112002KQ(CHIPS)':
 'VSS19': CDS_PINID='VSS19';
NODE_NAME     J17 50
 '@T6G_MB_LIB.T6G(SCH_1):PAGE87_I352@PURE_QUANTA.SCONN288_DDR506112002KQ(CHIPS)':
 'VSS20': CDS_PINID='VSS20';
NODE_NAME     J17 52
 '@T6G_MB_LIB.T6G(SCH_1):PAGE87_I352@PURE_QUANTA.SCONN288_DDR506112002KQ(CHIPS)':
 'VSS21': CDS_PINID='VSS21';
NODE_NAME     J17 54
 '@T6G_MB_LIB.T6G(SCH_1):PAGE87_I352@PURE_QUANTA.SCONN288_DDR506112002KQ(CHIPS)':
 'VSS22': CDS_PINID='VSS22';
NODE_NAME     J17 57
 '@T6G_MB_LIB.T6G(SCH_1):PAGE87_I352@PURE_QUANTA.SCONN288_DDR506112002KQ(CHIPS)':
 'VSS23': CDS_PINID='VSS23';
NODE_NAME     J17 59
 '@T6G_MB_LIB.T6G(SCH_1):PAGE87_I352@PURE_QUANTA.SCONN288_DDR506112002KQ(CHIPS)':
 'VSS24': CDS_PINID='VSS24';
NODE_NAME     J17 61
 '@T6G_MB_LIB.T6G(SCH_1):PAGE87_I352@PURE_QUANTA.SCONN288_DDR506112002KQ(CHIPS)':
 'VSS25': CDS_PINID='VSS25';
NODE_NAME     J17 63
 '@T6G_MB_LIB.T6G(SCH_1):PAGE87_I352@PURE_QUANTA.SCONN288_DDR506112002KQ(CHIPS)':
 'VSS26': CDS_PINID='VSS26';
NODE_NAME     J17 65
 '@T6G_MB_LIB.T6G(SCH_1):PAGE87_I352@PURE_QUANTA.SCONN288_DDR506112002KQ(CHIPS)':
 'VSS27': CDS_PINID='VSS27';
NODE_NAME     J17 67
 '@T6G_MB_LIB.T6G(SCH_1):PAGE87_I352@PURE_QUANTA.SCONN288_DDR506112002KQ(CHIPS)':
 'VSS28': CDS_PINID='VSS28';
NODE_NAME     J17 69
 '@T6G_MB_LIB.T6G(SCH_1):PAGE87_I352@PURE_QUANTA.SCONN288_DDR506112002KQ(CHIPS)':
 'VSS29': CDS_PINID='VSS29';
NODE_NAME     J17 71
 '@T6G_MB_LIB.T6G(SCH_1):PAGE87_I352@PURE_QUANTA.SCONN288_DDR506112002KQ(CHIPS)':
 'VSS30': CDS_PINID='VSS30';
NODE_NAME     J17 73
 '@T6G_MB_LIB.T6G(SCH_1):PAGE87_I352@PURE_QUANTA.SCONN288_DDR506112002KQ(CHIPS)':
 'VSS31': CDS_PINID='VSS31';
NODE_NAME     J17 75
 '@T6G_MB_LIB.T6G(SCH_1):PAGE87_I352@PURE_QUANTA.SCONN288_DDR506112002KQ(CHIPS)':
 'VSS32': CDS_PINID='VSS32';
NODE_NAME     J17 77
 '@T6G_MB_LIB.T6G(SCH_1):PAGE87_I352@PURE_QUANTA.SCONN288_DDR506112002KQ(CHIPS)':
 'VSS33': CDS_PINID='VSS33';
NODE_NAME     J17 79
 '@T6G_MB_LIB.T6G(SCH_1):PAGE87_I352@PURE_QUANTA.SCONN288_DDR506112002KQ(CHIPS)':
 'VSS34': CDS_PINID='VSS34';
NODE_NAME     J17 81
 '@T6G_MB_LIB.T6G(SCH_1):PAGE87_I352@PURE_QUANTA.SCONN288_DDR506112002KQ(CHIPS)':
 'VSS35': CDS_PINID='VSS35';
NODE_NAME     J17 83
 '@T6G_MB_LIB.T6G(SCH_1):PAGE87_I352@PURE_QUANTA.SCONN288_DDR506112002KQ(CHIPS)':
 'VSS36': CDS_PINID='VSS36';
NODE_NAME     J17 85
 '@T6G_MB_LIB.T6G(SCH_1):PAGE87_I352@PURE_QUANTA.SCONN288_DDR506112002KQ(CHIPS)':
 'VSS37': CDS_PINID='VSS37';
NODE_NAME     J17 88
 '@T6G_MB_LIB.T6G(SCH_1):PAGE87_I352@PURE_QUANTA.SCONN288_DDR506112002KQ(CHIPS)':
 'VSS38': CDS_PINID='VSS38';
NODE_NAME     J17 90
 '@T6G_MB_LIB.T6G(SCH_1):PAGE87_I352@PURE_QUANTA.SCONN288_DDR506112002KQ(CHIPS)':
 'VSS39': CDS_PINID='VSS39';
NODE_NAME     J17 92
 '@T6G_MB_LIB.T6G(SCH_1):PAGE87_I352@PURE_QUANTA.SCONN288_DDR506112002KQ(CHIPS)':
 'VSS40': CDS_PINID='VSS40';
NODE_NAME     J17 95
 '@T6G_MB_LIB.T6G(SCH_1):PAGE87_I352@PURE_QUANTA.SCONN288_DDR506112002KQ(CHIPS)':
 'VSS41': CDS_PINID='VSS41';
NODE_NAME     J17 97
 '@T6G_MB_LIB.T6G(SCH_1):PAGE87_I352@PURE_QUANTA.SCONN288_DDR506112002KQ(CHIPS)':
 'VSS42': CDS_PINID='VSS42';
NODE_NAME     J17 99
 '@T6G_MB_LIB.T6G(SCH_1):PAGE87_I352@PURE_QUANTA.SCONN288_DDR506112002KQ(CHIPS)':
 'VSS43': CDS_PINID='VSS43';
NODE_NAME     J17 101
 '@T6G_MB_LIB.T6G(SCH_1):PAGE87_I352@PURE_QUANTA.SCONN288_DDR506112002KQ(CHIPS)':
 'VSS44': CDS_PINID='VSS44';
NODE_NAME     J17 103
 '@T6G_MB_LIB.T6G(SCH_1):PAGE87_I352@PURE_QUANTA.SCONN288_DDR506112002KQ(CHIPS)':
 'VSS45': CDS_PINID='VSS45';
NODE_NAME     J17 106
 '@T6G_MB_LIB.T6G(SCH_1):PAGE87_I352@PURE_QUANTA.SCONN288_DDR506112002KQ(CHIPS)':
 'VSS46': CDS_PINID='VSS46';
NODE_NAME     J17 108
 '@T6G_MB_LIB.T6G(SCH_1):PAGE87_I352@PURE_QUANTA.SCONN288_DDR506112002KQ(CHIPS)':
 'VSS47': CDS_PINID='VSS47';
NODE_NAME     J17 110
 '@T6G_MB_LIB.T6G(SCH_1):PAGE87_I352@PURE_QUANTA.SCONN288_DDR506112002KQ(CHIPS)':
 'VSS48': CDS_PINID='VSS48';
NODE_NAME     J17 112
 '@T6G_MB_LIB.T6G(SCH_1):PAGE87_I352@PURE_QUANTA.SCONN288_DDR506112002KQ(CHIPS)':
 'VSS49': CDS_PINID='VSS49';
NODE_NAME     J17 114
 '@T6G_MB_LIB.T6G(SCH_1):PAGE87_I352@PURE_QUANTA.SCONN288_DDR506112002KQ(CHIPS)':
 'VSS50': CDS_PINID='VSS50';
NODE_NAME     J17 117
 '@T6G_MB_LIB.T6G(SCH_1):PAGE87_I352@PURE_QUANTA.SCONN288_DDR506112002KQ(CHIPS)':
 'VSS51': CDS_PINID='VSS51';
NODE_NAME     J17 119
 '@T6G_MB_LIB.T6G(SCH_1):PAGE87_I352@PURE_QUANTA.SCONN288_DDR506112002KQ(CHIPS)':
 'VSS52': CDS_PINID='VSS52';
NODE_NAME     J17 121
 '@T6G_MB_LIB.T6G(SCH_1):PAGE87_I352@PURE_QUANTA.SCONN288_DDR506112002KQ(CHIPS)':
 'VSS53': CDS_PINID='VSS53';
NODE_NAME     J17 123
 '@T6G_MB_LIB.T6G(SCH_1):PAGE87_I352@PURE_QUANTA.SCONN288_DDR506112002KQ(CHIPS)':
 'VSS54': CDS_PINID='VSS54';
NODE_NAME     J17 125
 '@T6G_MB_LIB.T6G(SCH_1):PAGE87_I352@PURE_QUANTA.SCONN288_DDR506112002KQ(CHIPS)':
 'VSS55': CDS_PINID='VSS55';
NODE_NAME     J17 128
 '@T6G_MB_LIB.T6G(SCH_1):PAGE87_I352@PURE_QUANTA.SCONN288_DDR506112002KQ(CHIPS)':
 'VSS56': CDS_PINID='VSS56';
NODE_NAME     J17 130
 '@T6G_MB_LIB.T6G(SCH_1):PAGE87_I352@PURE_QUANTA.SCONN288_DDR506112002KQ(CHIPS)':
 'VSS57': CDS_PINID='VSS57';
NODE_NAME     J17 132
 '@T6G_MB_LIB.T6G(SCH_1):PAGE87_I352@PURE_QUANTA.SCONN288_DDR506112002KQ(CHIPS)':
 'VSS58': CDS_PINID='VSS58';
NODE_NAME     J17 134
 '@T6G_MB_LIB.T6G(SCH_1):PAGE87_I352@PURE_QUANTA.SCONN288_DDR506112002KQ(CHIPS)':
 'VSS59': CDS_PINID='VSS59';
NODE_NAME     J17 136
 '@T6G_MB_LIB.T6G(SCH_1):PAGE87_I352@PURE_QUANTA.SCONN288_DDR506112002KQ(CHIPS)':
 'VSS60': CDS_PINID='VSS60';
NODE_NAME     J17 139
 '@T6G_MB_LIB.T6G(SCH_1):PAGE87_I352@PURE_QUANTA.SCONN288_DDR506112002KQ(CHIPS)':
 'VSS61': CDS_PINID='VSS61';
NODE_NAME     J17 141
 '@T6G_MB_LIB.T6G(SCH_1):PAGE87_I352@PURE_QUANTA.SCONN288_DDR506112002KQ(CHIPS)':
 'VSS62': CDS_PINID='VSS62';
NODE_NAME     J17 143
 '@T6G_MB_LIB.T6G(SCH_1):PAGE87_I352@PURE_QUANTA.SCONN288_DDR506112002KQ(CHIPS)':
 'VSS63': CDS_PINID='VSS63';
NODE_NAME     J17 151
 '@T6G_MB_LIB.T6G(SCH_1):PAGE87_I352@PURE_QUANTA.SCONN288_DDR506112002KQ(CHIPS)':
 'VSS64': CDS_PINID='VSS64';
NODE_NAME     J17 153
 '@T6G_MB_LIB.T6G(SCH_1):PAGE87_I352@PURE_QUANTA.SCONN288_DDR506112002KQ(CHIPS)':
 'VSS65': CDS_PINID='VSS65';
NODE_NAME     J17 155
 '@T6G_MB_LIB.T6G(SCH_1):PAGE87_I352@PURE_QUANTA.SCONN288_DDR506112002KQ(CHIPS)':
 'VSS66': CDS_PINID='VSS66';
NODE_NAME     J17 158
 '@T6G_MB_LIB.T6G(SCH_1):PAGE87_I352@PURE_QUANTA.SCONN288_DDR506112002KQ(CHIPS)':
 'VSS67': CDS_PINID='VSS67';
NODE_NAME     J17 160
 '@T6G_MB_LIB.T6G(SCH_1):PAGE87_I352@PURE_QUANTA.SCONN288_DDR506112002KQ(CHIPS)':
 'VSS68': CDS_PINID='VSS68';
NODE_NAME     J17 162
 '@T6G_MB_LIB.T6G(SCH_1):PAGE87_I352@PURE_QUANTA.SCONN288_DDR506112002KQ(CHIPS)':
 'VSS69': CDS_PINID='VSS69';
NODE_NAME     J17 164
 '@T6G_MB_LIB.T6G(SCH_1):PAGE87_I352@PURE_QUANTA.SCONN288_DDR506112002KQ(CHIPS)':
 'VSS70': CDS_PINID='VSS70';
NODE_NAME     J17 166
 '@T6G_MB_LIB.T6G(SCH_1):PAGE87_I352@PURE_QUANTA.SCONN288_DDR506112002KQ(CHIPS)':
 'VSS71': CDS_PINID='VSS71';
NODE_NAME     J17 169
 '@T6G_MB_LIB.T6G(SCH_1):PAGE87_I352@PURE_QUANTA.SCONN288_DDR506112002KQ(CHIPS)':
 'VSS72': CDS_PINID='VSS72';
NODE_NAME     J17 171
 '@T6G_MB_LIB.T6G(SCH_1):PAGE87_I352@PURE_QUANTA.SCONN288_DDR506112002KQ(CHIPS)':
 'VSS73': CDS_PINID='VSS73';
NODE_NAME     J17 173
 '@T6G_MB_LIB.T6G(SCH_1):PAGE87_I352@PURE_QUANTA.SCONN288_DDR506112002KQ(CHIPS)':
 'VSS74': CDS_PINID='VSS74';
NODE_NAME     J17 175
 '@T6G_MB_LIB.T6G(SCH_1):PAGE87_I352@PURE_QUANTA.SCONN288_DDR506112002KQ(CHIPS)':
 'VSS75': CDS_PINID='VSS75';
NODE_NAME     J17 177
 '@T6G_MB_LIB.T6G(SCH_1):PAGE87_I352@PURE_QUANTA.SCONN288_DDR506112002KQ(CHIPS)':
 'VSS76': CDS_PINID='VSS76';
NODE_NAME     J17 180
 '@T6G_MB_LIB.T6G(SCH_1):PAGE87_I352@PURE_QUANTA.SCONN288_DDR506112002KQ(CHIPS)':
 'VSS77': CDS_PINID='VSS77';
NODE_NAME     J17 182
 '@T6G_MB_LIB.T6G(SCH_1):PAGE87_I352@PURE_QUANTA.SCONN288_DDR506112002KQ(CHIPS)':
 'VSS78': CDS_PINID='VSS78';
NODE_NAME     J17 184
 '@T6G_MB_LIB.T6G(SCH_1):PAGE87_I352@PURE_QUANTA.SCONN288_DDR506112002KQ(CHIPS)':
 'VSS79': CDS_PINID='VSS79';
NODE_NAME     J17 186
 '@T6G_MB_LIB.T6G(SCH_1):PAGE87_I352@PURE_QUANTA.SCONN288_DDR506112002KQ(CHIPS)':
 'VSS80': CDS_PINID='VSS80';
NODE_NAME     J17 188
 '@T6G_MB_LIB.T6G(SCH_1):PAGE87_I352@PURE_QUANTA.SCONN288_DDR506112002KQ(CHIPS)':
 'VSS81': CDS_PINID='VSS81';
NODE_NAME     J17 191
 '@T6G_MB_LIB.T6G(SCH_1):PAGE87_I352@PURE_QUANTA.SCONN288_DDR506112002KQ(CHIPS)':
 'VSS82': CDS_PINID='VSS82';
NODE_NAME     J17 193
 '@T6G_MB_LIB.T6G(SCH_1):PAGE87_I352@PURE_QUANTA.SCONN288_DDR506112002KQ(CHIPS)':
 'VSS83': CDS_PINID='VSS83';
NODE_NAME     J17 195
 '@T6G_MB_LIB.T6G(SCH_1):PAGE87_I352@PURE_QUANTA.SCONN288_DDR506112002KQ(CHIPS)':
 'VSS84': CDS_PINID='VSS84';
NODE_NAME     J17 197
 '@T6G_MB_LIB.T6G(SCH_1):PAGE87_I352@PURE_QUANTA.SCONN288_DDR506112002KQ(CHIPS)':
 'VSS85': CDS_PINID='VSS85';
NODE_NAME     J17 199
 '@T6G_MB_LIB.T6G(SCH_1):PAGE87_I352@PURE_QUANTA.SCONN288_DDR506112002KQ(CHIPS)':
 'VSS86': CDS_PINID='VSS86';
NODE_NAME     J17 202
 '@T6G_MB_LIB.T6G(SCH_1):PAGE87_I352@PURE_QUANTA.SCONN288_DDR506112002KQ(CHIPS)':
 'VSS87': CDS_PINID='VSS87';
NODE_NAME     J17 204
 '@T6G_MB_LIB.T6G(SCH_1):PAGE87_I352@PURE_QUANTA.SCONN288_DDR506112002KQ(CHIPS)':
 'VSS88': CDS_PINID='VSS88';
NODE_NAME     J17 206
 '@T6G_MB_LIB.T6G(SCH_1):PAGE87_I352@PURE_QUANTA.SCONN288_DDR506112002KQ(CHIPS)':
 'VSS89': CDS_PINID='VSS89';
NODE_NAME     J17 208
 '@T6G_MB_LIB.T6G(SCH_1):PAGE87_I352@PURE_QUANTA.SCONN288_DDR506112002KQ(CHIPS)':
 'VSS90': CDS_PINID='VSS90';
NODE_NAME     J17 210
 '@T6G_MB_LIB.T6G(SCH_1):PAGE87_I352@PURE_QUANTA.SCONN288_DDR506112002KQ(CHIPS)':
 'VSS91': CDS_PINID='VSS91';
NODE_NAME     J17 212
 '@T6G_MB_LIB.T6G(SCH_1):PAGE87_I352@PURE_QUANTA.SCONN288_DDR506112002KQ(CHIPS)':
 'VSS92': CDS_PINID='VSS92';
NODE_NAME     J17 214
 '@T6G_MB_LIB.T6G(SCH_1):PAGE87_I352@PURE_QUANTA.SCONN288_DDR506112002KQ(CHIPS)':
 'VSS93': CDS_PINID='VSS93';
NODE_NAME     J17 216
 '@T6G_MB_LIB.T6G(SCH_1):PAGE87_I352@PURE_QUANTA.SCONN288_DDR506112002KQ(CHIPS)':
 'VSS94': CDS_PINID='VSS94';
NODE_NAME     J17 219
 '@T6G_MB_LIB.T6G(SCH_1):PAGE87_I352@PURE_QUANTA.SCONN288_DDR506112002KQ(CHIPS)':
 'VSS95': CDS_PINID='VSS95';
NODE_NAME     J17 222
 '@T6G_MB_LIB.T6G(SCH_1):PAGE87_I352@PURE_QUANTA.SCONN288_DDR506112002KQ(CHIPS)':
 'VSS96': CDS_PINID='VSS96';
NODE_NAME     J17 224
 '@T6G_MB_LIB.T6G(SCH_1):PAGE87_I352@PURE_QUANTA.SCONN288_DDR506112002KQ(CHIPS)':
 'VSS97': CDS_PINID='VSS97';
NODE_NAME     J17 226
 '@T6G_MB_LIB.T6G(SCH_1):PAGE87_I352@PURE_QUANTA.SCONN288_DDR506112002KQ(CHIPS)':
 'VSS98': CDS_PINID='VSS98';
NODE_NAME     J17 228
 '@T6G_MB_LIB.T6G(SCH_1):PAGE87_I352@PURE_QUANTA.SCONN288_DDR506112002KQ(CHIPS)':
 'VSS99': CDS_PINID='VSS99';
NODE_NAME     J17 230
 '@T6G_MB_LIB.T6G(SCH_1):PAGE87_I352@PURE_QUANTA.SCONN288_DDR506112002KQ(CHIPS)':
 'VSS100': CDS_PINID='VSS100';
NODE_NAME     J17 233
 '@T6G_MB_LIB.T6G(SCH_1):PAGE87_I352@PURE_QUANTA.SCONN288_DDR506112002KQ(CHIPS)':
 'VSS101': CDS_PINID='VSS101';
NODE_NAME     J17 235
 '@T6G_MB_LIB.T6G(SCH_1):PAGE87_I352@PURE_QUANTA.SCONN288_DDR506112002KQ(CHIPS)':
 'VSS102': CDS_PINID='VSS102';
NODE_NAME     J17 237
 '@T6G_MB_LIB.T6G(SCH_1):PAGE87_I352@PURE_QUANTA.SCONN288_DDR506112002KQ(CHIPS)':
 'VSS103': CDS_PINID='VSS103';
NODE_NAME     J17 240
 '@T6G_MB_LIB.T6G(SCH_1):PAGE87_I352@PURE_QUANTA.SCONN288_DDR506112002KQ(CHIPS)':
 'VSS104': CDS_PINID='VSS104';
NODE_NAME     J17 242
 '@T6G_MB_LIB.T6G(SCH_1):PAGE87_I352@PURE_QUANTA.SCONN288_DDR506112002KQ(CHIPS)':
 'VSS105': CDS_PINID='VSS105';
NODE_NAME     J17 244
 '@T6G_MB_LIB.T6G(SCH_1):PAGE87_I352@PURE_QUANTA.SCONN288_DDR506112002KQ(CHIPS)':
 'VSS106': CDS_PINID='VSS106';
NODE_NAME     J17 246
 '@T6G_MB_LIB.T6G(SCH_1):PAGE87_I352@PURE_QUANTA.SCONN288_DDR506112002KQ(CHIPS)':
 'VSS107': CDS_PINID='VSS107';
NODE_NAME     J17 248
 '@T6G_MB_LIB.T6G(SCH_1):PAGE87_I352@PURE_QUANTA.SCONN288_DDR506112002KQ(CHIPS)':
 'VSS108': CDS_PINID='VSS108';
NODE_NAME     J17 251
 '@T6G_MB_LIB.T6G(SCH_1):PAGE87_I352@PURE_QUANTA.SCONN288_DDR506112002KQ(CHIPS)':
 'VSS109': CDS_PINID='VSS109';
NODE_NAME     J17 253
 '@T6G_MB_LIB.T6G(SCH_1):PAGE87_I352@PURE_QUANTA.SCONN288_DDR506112002KQ(CHIPS)':
 'VSS110': CDS_PINID='VSS110';
NODE_NAME     J17 255
 '@T6G_MB_LIB.T6G(SCH_1):PAGE87_I352@PURE_QUANTA.SCONN288_DDR506112002KQ(CHIPS)':
 'VSS111': CDS_PINID='VSS111';
NODE_NAME     J17 257
 '@T6G_MB_LIB.T6G(SCH_1):PAGE87_I352@PURE_QUANTA.SCONN288_DDR506112002KQ(CHIPS)':
 'VSS112': CDS_PINID='VSS112';
NODE_NAME     J17 259
 '@T6G_MB_LIB.T6G(SCH_1):PAGE87_I352@PURE_QUANTA.SCONN288_DDR506112002KQ(CHIPS)':
 'VSS113': CDS_PINID='VSS113';
NODE_NAME     J17 262
 '@T6G_MB_LIB.T6G(SCH_1):PAGE87_I352@PURE_QUANTA.SCONN288_DDR506112002KQ(CHIPS)':
 'VSS114': CDS_PINID='VSS114';
NODE_NAME     J17 264
 '@T6G_MB_LIB.T6G(SCH_1):PAGE87_I352@PURE_QUANTA.SCONN288_DDR506112002KQ(CHIPS)':
 'VSS115': CDS_PINID='VSS115';
NODE_NAME     J17 266
 '@T6G_MB_LIB.T6G(SCH_1):PAGE87_I352@PURE_QUANTA.SCONN288_DDR506112002KQ(CHIPS)':
 'VSS116': CDS_PINID='VSS116';
NODE_NAME     J17 268
 '@T6G_MB_LIB.T6G(SCH_1):PAGE87_I352@PURE_QUANTA.SCONN288_DDR506112002KQ(CHIPS)':
 'VSS117': CDS_PINID='VSS117';
NODE_NAME     J17 270
 '@T6G_MB_LIB.T6G(SCH_1):PAGE87_I352@PURE_QUANTA.SCONN288_DDR506112002KQ(CHIPS)':
 'VSS118': CDS_PINID='VSS118';
NODE_NAME     J17 273
 '@T6G_MB_LIB.T6G(SCH_1):PAGE87_I352@PURE_QUANTA.SCONN288_DDR506112002KQ(CHIPS)':
 'VSS119': CDS_PINID='VSS119';
NODE_NAME     J17 275
 '@T6G_MB_LIB.T6G(SCH_1):PAGE87_I352@PURE_QUANTA.SCONN288_DDR506112002KQ(CHIPS)':
 'VSS120': CDS_PINID='VSS120';
NODE_NAME     J17 277
 '@T6G_MB_LIB.T6G(SCH_1):PAGE87_I352@PURE_QUANTA.SCONN288_DDR506112002KQ(CHIPS)':
 'VSS121': CDS_PINID='VSS121';
NODE_NAME     J17 279
 '@T6G_MB_LIB.T6G(SCH_1):PAGE87_I352@PURE_QUANTA.SCONN288_DDR506112002KQ(CHIPS)':
 'VSS122': CDS_PINID='VSS122';
NODE_NAME     J17 281
 '@T6G_MB_LIB.T6G(SCH_1):PAGE87_I352@PURE_QUANTA.SCONN288_DDR506112002KQ(CHIPS)':
 'VSS123': CDS_PINID='VSS123';
NODE_NAME     J17 284
 '@T6G_MB_LIB.T6G(SCH_1):PAGE87_I352@PURE_QUANTA.SCONN288_DDR506112002KQ(CHIPS)':
 'VSS124': CDS_PINID='VSS124';
NODE_NAME     J17 286
 '@T6G_MB_LIB.T6G(SCH_1):PAGE87_I352@PURE_QUANTA.SCONN288_DDR506112002KQ(CHIPS)':
 'VSS125': CDS_PINID='VSS125';
NODE_NAME     J17 288
 '@T6G_MB_LIB.T6G(SCH_1):PAGE87_I352@PURE_QUANTA.SCONN288_DDR506112002KQ(CHIPS)':
 'VSS126': CDS_PINID='VSS126';
NODE_NAME     C96 2
 '@T6G_MB_LIB.T6G(SCH_1):PAGE87_I362@PURE_QUANTA.Q_CAP(CHIPS)':
 'B': CDS_PINID='B';
NODE_NAME     C146 2
 '@T6G_MB_LIB.T6G(SCH_1):PAGE87_I413@PURE_QUANTA.Q_CAP(CHIPS)':
 'B': CDS_PINID='B';
NODE_NAME     C147 2
 '@T6G_MB_LIB.T6G(SCH_1):PAGE87_I414@PURE_QUANTA.Q_CAP(CHIPS)':
 'B': CDS_PINID='B';
NODE_NAME     R763 2
 '@T6G_MB_LIB.T6G(SCH_1):PAGE88_I349@PURE_QUANTA.Q_RES(CHIPS)':
 'B': CDS_PINID='B';
NODE_NAME     J19 G1
 '@T6G_MB_LIB.T6G(SCH_1):PAGE88_I352@PURE_QUANTA.SCONN288_DDR506112002KQ(CHIPS)':
 'G1': CDS_PINID='G1';
NODE_NAME     J19 G2
 '@T6G_MB_LIB.T6G(SCH_1):PAGE88_I352@PURE_QUANTA.SCONN288_DDR506112002KQ(CHIPS)':
 'G2': CDS_PINID='G2';
NODE_NAME     J19 G3
 '@T6G_MB_LIB.T6G(SCH_1):PAGE88_I352@PURE_QUANTA.SCONN288_DDR506112002KQ(CHIPS)':
 'G3': CDS_PINID='G3';
NODE_NAME     J19 6
 '@T6G_MB_LIB.T6G(SCH_1):PAGE88_I352@PURE_QUANTA.SCONN288_DDR506112002KQ(CHIPS)':
 'VSS0': CDS_PINID='VSS0';
NODE_NAME     J19 8
 '@T6G_MB_LIB.T6G(SCH_1):PAGE88_I352@PURE_QUANTA.SCONN288_DDR506112002KQ(CHIPS)':
 'VSS1': CDS_PINID='VSS1';
NODE_NAME     J19 10
 '@T6G_MB_LIB.T6G(SCH_1):PAGE88_I352@PURE_QUANTA.SCONN288_DDR506112002KQ(CHIPS)':
 'VSS2': CDS_PINID='VSS2';
NODE_NAME     J19 13
 '@T6G_MB_LIB.T6G(SCH_1):PAGE88_I352@PURE_QUANTA.SCONN288_DDR506112002KQ(CHIPS)':
 'VSS3': CDS_PINID='VSS3';
NODE_NAME     J19 15
 '@T6G_MB_LIB.T6G(SCH_1):PAGE88_I352@PURE_QUANTA.SCONN288_DDR506112002KQ(CHIPS)':
 'VSS4': CDS_PINID='VSS4';
NODE_NAME     J19 17
 '@T6G_MB_LIB.T6G(SCH_1):PAGE88_I352@PURE_QUANTA.SCONN288_DDR506112002KQ(CHIPS)':
 'VSS5': CDS_PINID='VSS5';
NODE_NAME     J19 19
 '@T6G_MB_LIB.T6G(SCH_1):PAGE88_I352@PURE_QUANTA.SCONN288_DDR506112002KQ(CHIPS)':
 'VSS6': CDS_PINID='VSS6';
NODE_NAME     J19 21
 '@T6G_MB_LIB.T6G(SCH_1):PAGE88_I352@PURE_QUANTA.SCONN288_DDR506112002KQ(CHIPS)':
 'VSS7': CDS_PINID='VSS7';
NODE_NAME     J19 24
 '@T6G_MB_LIB.T6G(SCH_1):PAGE88_I352@PURE_QUANTA.SCONN288_DDR506112002KQ(CHIPS)':
 'VSS8': CDS_PINID='VSS8';
NODE_NAME     J19 26
 '@T6G_MB_LIB.T6G(SCH_1):PAGE88_I352@PURE_QUANTA.SCONN288_DDR506112002KQ(CHIPS)':
 'VSS9': CDS_PINID='VSS9';
NODE_NAME     J19 28
 '@T6G_MB_LIB.T6G(SCH_1):PAGE88_I352@PURE_QUANTA.SCONN288_DDR506112002KQ(CHIPS)':
 'VSS10': CDS_PINID='VSS10';
NODE_NAME     J19 30
 '@T6G_MB_LIB.T6G(SCH_1):PAGE88_I352@PURE_QUANTA.SCONN288_DDR506112002KQ(CHIPS)':
 'VSS11': CDS_PINID='VSS11';
NODE_NAME     J19 32
 '@T6G_MB_LIB.T6G(SCH_1):PAGE88_I352@PURE_QUANTA.SCONN288_DDR506112002KQ(CHIPS)':
 'VSS12': CDS_PINID='VSS12';
NODE_NAME     J19 35
 '@T6G_MB_LIB.T6G(SCH_1):PAGE88_I352@PURE_QUANTA.SCONN288_DDR506112002KQ(CHIPS)':
 'VSS13': CDS_PINID='VSS13';
NODE_NAME     J19 37
 '@T6G_MB_LIB.T6G(SCH_1):PAGE88_I352@PURE_QUANTA.SCONN288_DDR506112002KQ(CHIPS)':
 'VSS14': CDS_PINID='VSS14';
NODE_NAME     J19 39
 '@T6G_MB_LIB.T6G(SCH_1):PAGE88_I352@PURE_QUANTA.SCONN288_DDR506112002KQ(CHIPS)':
 'VSS15': CDS_PINID='VSS15';
NODE_NAME     J19 41
 '@T6G_MB_LIB.T6G(SCH_1):PAGE88_I352@PURE_QUANTA.SCONN288_DDR506112002KQ(CHIPS)':
 'VSS16': CDS_PINID='VSS16';
NODE_NAME     J19 43
 '@T6G_MB_LIB.T6G(SCH_1):PAGE88_I352@PURE_QUANTA.SCONN288_DDR506112002KQ(CHIPS)':
 'VSS17': CDS_PINID='VSS17';
NODE_NAME     J19 46
 '@T6G_MB_LIB.T6G(SCH_1):PAGE88_I352@PURE_QUANTA.SCONN288_DDR506112002KQ(CHIPS)':
 'VSS18': CDS_PINID='VSS18';
NODE_NAME     J19 48
 '@T6G_MB_LIB.T6G(SCH_1):PAGE88_I352@PURE_QUANTA.SCONN288_DDR506112002KQ(CHIPS)':
 'VSS19': CDS_PINID='VSS19';
NODE_NAME     J19 50
 '@T6G_MB_LIB.T6G(SCH_1):PAGE88_I352@PURE_QUANTA.SCONN288_DDR506112002KQ(CHIPS)':
 'VSS20': CDS_PINID='VSS20';
NODE_NAME     J19 52
 '@T6G_MB_LIB.T6G(SCH_1):PAGE88_I352@PURE_QUANTA.SCONN288_DDR506112002KQ(CHIPS)':
 'VSS21': CDS_PINID='VSS21';
NODE_NAME     J19 54
 '@T6G_MB_LIB.T6G(SCH_1):PAGE88_I352@PURE_QUANTA.SCONN288_DDR506112002KQ(CHIPS)':
 'VSS22': CDS_PINID='VSS22';
NODE_NAME     J19 57
 '@T6G_MB_LIB.T6G(SCH_1):PAGE88_I352@PURE_QUANTA.SCONN288_DDR506112002KQ(CHIPS)':
 'VSS23': CDS_PINID='VSS23';
NODE_NAME     J19 59
 '@T6G_MB_LIB.T6G(SCH_1):PAGE88_I352@PURE_QUANTA.SCONN288_DDR506112002KQ(CHIPS)':
 'VSS24': CDS_PINID='VSS24';
NODE_NAME     J19 61
 '@T6G_MB_LIB.T6G(SCH_1):PAGE88_I352@PURE_QUANTA.SCONN288_DDR506112002KQ(CHIPS)':
 'VSS25': CDS_PINID='VSS25';
NODE_NAME     J19 63
 '@T6G_MB_LIB.T6G(SCH_1):PAGE88_I352@PURE_QUANTA.SCONN288_DDR506112002KQ(CHIPS)':
 'VSS26': CDS_PINID='VSS26';
NODE_NAME     J19 65
 '@T6G_MB_LIB.T6G(SCH_1):PAGE88_I352@PURE_QUANTA.SCONN288_DDR506112002KQ(CHIPS)':
 'VSS27': CDS_PINID='VSS27';
NODE_NAME     J19 67
 '@T6G_MB_LIB.T6G(SCH_1):PAGE88_I352@PURE_QUANTA.SCONN288_DDR506112002KQ(CHIPS)':
 'VSS28': CDS_PINID='VSS28';
NODE_NAME     J19 69
 '@T6G_MB_LIB.T6G(SCH_1):PAGE88_I352@PURE_QUANTA.SCONN288_DDR506112002KQ(CHIPS)':
 'VSS29': CDS_PINID='VSS29';
NODE_NAME     J19 71
 '@T6G_MB_LIB.T6G(SCH_1):PAGE88_I352@PURE_QUANTA.SCONN288_DDR506112002KQ(CHIPS)':
 'VSS30': CDS_PINID='VSS30';
NODE_NAME     J19 73
 '@T6G_MB_LIB.T6G(SCH_1):PAGE88_I352@PURE_QUANTA.SCONN288_DDR506112002KQ(CHIPS)':
 'VSS31': CDS_PINID='VSS31';
NODE_NAME     J19 75
 '@T6G_MB_LIB.T6G(SCH_1):PAGE88_I352@PURE_QUANTA.SCONN288_DDR506112002KQ(CHIPS)':
 'VSS32': CDS_PINID='VSS32';
NODE_NAME     J19 77
 '@T6G_MB_LIB.T6G(SCH_1):PAGE88_I352@PURE_QUANTA.SCONN288_DDR506112002KQ(CHIPS)':
 'VSS33': CDS_PINID='VSS33';
NODE_NAME     J19 79
 '@T6G_MB_LIB.T6G(SCH_1):PAGE88_I352@PURE_QUANTA.SCONN288_DDR506112002KQ(CHIPS)':
 'VSS34': CDS_PINID='VSS34';
NODE_NAME     J19 81
 '@T6G_MB_LIB.T6G(SCH_1):PAGE88_I352@PURE_QUANTA.SCONN288_DDR506112002KQ(CHIPS)':
 'VSS35': CDS_PINID='VSS35';
NODE_NAME     J19 83
 '@T6G_MB_LIB.T6G(SCH_1):PAGE88_I352@PURE_QUANTA.SCONN288_DDR506112002KQ(CHIPS)':
 'VSS36': CDS_PINID='VSS36';
NODE_NAME     J19 85
 '@T6G_MB_LIB.T6G(SCH_1):PAGE88_I352@PURE_QUANTA.SCONN288_DDR506112002KQ(CHIPS)':
 'VSS37': CDS_PINID='VSS37';
NODE_NAME     J19 88
 '@T6G_MB_LIB.T6G(SCH_1):PAGE88_I352@PURE_QUANTA.SCONN288_DDR506112002KQ(CHIPS)':
 'VSS38': CDS_PINID='VSS38';
NODE_NAME     J19 90
 '@T6G_MB_LIB.T6G(SCH_1):PAGE88_I352@PURE_QUANTA.SCONN288_DDR506112002KQ(CHIPS)':
 'VSS39': CDS_PINID='VSS39';
NODE_NAME     J19 92
 '@T6G_MB_LIB.T6G(SCH_1):PAGE88_I352@PURE_QUANTA.SCONN288_DDR506112002KQ(CHIPS)':
 'VSS40': CDS_PINID='VSS40';
NODE_NAME     J19 95
 '@T6G_MB_LIB.T6G(SCH_1):PAGE88_I352@PURE_QUANTA.SCONN288_DDR506112002KQ(CHIPS)':
 'VSS41': CDS_PINID='VSS41';
NODE_NAME     J19 97
 '@T6G_MB_LIB.T6G(SCH_1):PAGE88_I352@PURE_QUANTA.SCONN288_DDR506112002KQ(CHIPS)':
 'VSS42': CDS_PINID='VSS42';
NODE_NAME     J19 99
 '@T6G_MB_LIB.T6G(SCH_1):PAGE88_I352@PURE_QUANTA.SCONN288_DDR506112002KQ(CHIPS)':
 'VSS43': CDS_PINID='VSS43';
NODE_NAME     J19 101
 '@T6G_MB_LIB.T6G(SCH_1):PAGE88_I352@PURE_QUANTA.SCONN288_DDR506112002KQ(CHIPS)':
 'VSS44': CDS_PINID='VSS44';
NODE_NAME     J19 103
 '@T6G_MB_LIB.T6G(SCH_1):PAGE88_I352@PURE_QUANTA.SCONN288_DDR506112002KQ(CHIPS)':
 'VSS45': CDS_PINID='VSS45';
NODE_NAME     J19 106
 '@T6G_MB_LIB.T6G(SCH_1):PAGE88_I352@PURE_QUANTA.SCONN288_DDR506112002KQ(CHIPS)':
 'VSS46': CDS_PINID='VSS46';
NODE_NAME     J19 108
 '@T6G_MB_LIB.T6G(SCH_1):PAGE88_I352@PURE_QUANTA.SCONN288_DDR506112002KQ(CHIPS)':
 'VSS47': CDS_PINID='VSS47';
NODE_NAME     J19 110
 '@T6G_MB_LIB.T6G(SCH_1):PAGE88_I352@PURE_QUANTA.SCONN288_DDR506112002KQ(CHIPS)':
 'VSS48': CDS_PINID='VSS48';
NODE_NAME     J19 112
 '@T6G_MB_LIB.T6G(SCH_1):PAGE88_I352@PURE_QUANTA.SCONN288_DDR506112002KQ(CHIPS)':
 'VSS49': CDS_PINID='VSS49';
NODE_NAME     J19 114
 '@T6G_MB_LIB.T6G(SCH_1):PAGE88_I352@PURE_QUANTA.SCONN288_DDR506112002KQ(CHIPS)':
 'VSS50': CDS_PINID='VSS50';
NODE_NAME     J19 117
 '@T6G_MB_LIB.T6G(SCH_1):PAGE88_I352@PURE_QUANTA.SCONN288_DDR506112002KQ(CHIPS)':
 'VSS51': CDS_PINID='VSS51';
NODE_NAME     J19 119
 '@T6G_MB_LIB.T6G(SCH_1):PAGE88_I352@PURE_QUANTA.SCONN288_DDR506112002KQ(CHIPS)':
 'VSS52': CDS_PINID='VSS52';
NODE_NAME     J19 121
 '@T6G_MB_LIB.T6G(SCH_1):PAGE88_I352@PURE_QUANTA.SCONN288_DDR506112002KQ(CHIPS)':
 'VSS53': CDS_PINID='VSS53';
NODE_NAME     J19 123
 '@T6G_MB_LIB.T6G(SCH_1):PAGE88_I352@PURE_QUANTA.SCONN288_DDR506112002KQ(CHIPS)':
 'VSS54': CDS_PINID='VSS54';
NODE_NAME     J19 125
 '@T6G_MB_LIB.T6G(SCH_1):PAGE88_I352@PURE_QUANTA.SCONN288_DDR506112002KQ(CHIPS)':
 'VSS55': CDS_PINID='VSS55';
NODE_NAME     J19 128
 '@T6G_MB_LIB.T6G(SCH_1):PAGE88_I352@PURE_QUANTA.SCONN288_DDR506112002KQ(CHIPS)':
 'VSS56': CDS_PINID='VSS56';
NODE_NAME     J19 130
 '@T6G_MB_LIB.T6G(SCH_1):PAGE88_I352@PURE_QUANTA.SCONN288_DDR506112002KQ(CHIPS)':
 'VSS57': CDS_PINID='VSS57';
NODE_NAME     J19 132
 '@T6G_MB_LIB.T6G(SCH_1):PAGE88_I352@PURE_QUANTA.SCONN288_DDR506112002KQ(CHIPS)':
 'VSS58': CDS_PINID='VSS58';
NODE_NAME     J19 134
 '@T6G_MB_LIB.T6G(SCH_1):PAGE88_I352@PURE_QUANTA.SCONN288_DDR506112002KQ(CHIPS)':
 'VSS59': CDS_PINID='VSS59';
NODE_NAME     J19 136
 '@T6G_MB_LIB.T6G(SCH_1):PAGE88_I352@PURE_QUANTA.SCONN288_DDR506112002KQ(CHIPS)':
 'VSS60': CDS_PINID='VSS60';
NODE_NAME     J19 139
 '@T6G_MB_LIB.T6G(SCH_1):PAGE88_I352@PURE_QUANTA.SCONN288_DDR506112002KQ(CHIPS)':
 'VSS61': CDS_PINID='VSS61';
NODE_NAME     J19 141
 '@T6G_MB_LIB.T6G(SCH_1):PAGE88_I352@PURE_QUANTA.SCONN288_DDR506112002KQ(CHIPS)':
 'VSS62': CDS_PINID='VSS62';
NODE_NAME     J19 143
 '@T6G_MB_LIB.T6G(SCH_1):PAGE88_I352@PURE_QUANTA.SCONN288_DDR506112002KQ(CHIPS)':
 'VSS63': CDS_PINID='VSS63';
NODE_NAME     J19 151
 '@T6G_MB_LIB.T6G(SCH_1):PAGE88_I352@PURE_QUANTA.SCONN288_DDR506112002KQ(CHIPS)':
 'VSS64': CDS_PINID='VSS64';
NODE_NAME     J19 153
 '@T6G_MB_LIB.T6G(SCH_1):PAGE88_I352@PURE_QUANTA.SCONN288_DDR506112002KQ(CHIPS)':
 'VSS65': CDS_PINID='VSS65';
NODE_NAME     J19 155
 '@T6G_MB_LIB.T6G(SCH_1):PAGE88_I352@PURE_QUANTA.SCONN288_DDR506112002KQ(CHIPS)':
 'VSS66': CDS_PINID='VSS66';
NODE_NAME     J19 158
 '@T6G_MB_LIB.T6G(SCH_1):PAGE88_I352@PURE_QUANTA.SCONN288_DDR506112002KQ(CHIPS)':
 'VSS67': CDS_PINID='VSS67';
NODE_NAME     J19 160
 '@T6G_MB_LIB.T6G(SCH_1):PAGE88_I352@PURE_QUANTA.SCONN288_DDR506112002KQ(CHIPS)':
 'VSS68': CDS_PINID='VSS68';
NODE_NAME     J19 162
 '@T6G_MB_LIB.T6G(SCH_1):PAGE88_I352@PURE_QUANTA.SCONN288_DDR506112002KQ(CHIPS)':
 'VSS69': CDS_PINID='VSS69';
NODE_NAME     J19 164
 '@T6G_MB_LIB.T6G(SCH_1):PAGE88_I352@PURE_QUANTA.SCONN288_DDR506112002KQ(CHIPS)':
 'VSS70': CDS_PINID='VSS70';
NODE_NAME     J19 166
 '@T6G_MB_LIB.T6G(SCH_1):PAGE88_I352@PURE_QUANTA.SCONN288_DDR506112002KQ(CHIPS)':
 'VSS71': CDS_PINID='VSS71';
NODE_NAME     J19 169
 '@T6G_MB_LIB.T6G(SCH_1):PAGE88_I352@PURE_QUANTA.SCONN288_DDR506112002KQ(CHIPS)':
 'VSS72': CDS_PINID='VSS72';
NODE_NAME     J19 171
 '@T6G_MB_LIB.T6G(SCH_1):PAGE88_I352@PURE_QUANTA.SCONN288_DDR506112002KQ(CHIPS)':
 'VSS73': CDS_PINID='VSS73';
NODE_NAME     J19 173
 '@T6G_MB_LIB.T6G(SCH_1):PAGE88_I352@PURE_QUANTA.SCONN288_DDR506112002KQ(CHIPS)':
 'VSS74': CDS_PINID='VSS74';
NODE_NAME     J19 175
 '@T6G_MB_LIB.T6G(SCH_1):PAGE88_I352@PURE_QUANTA.SCONN288_DDR506112002KQ(CHIPS)':
 'VSS75': CDS_PINID='VSS75';
NODE_NAME     J19 177
 '@T6G_MB_LIB.T6G(SCH_1):PAGE88_I352@PURE_QUANTA.SCONN288_DDR506112002KQ(CHIPS)':
 'VSS76': CDS_PINID='VSS76';
NODE_NAME     J19 180
 '@T6G_MB_LIB.T6G(SCH_1):PAGE88_I352@PURE_QUANTA.SCONN288_DDR506112002KQ(CHIPS)':
 'VSS77': CDS_PINID='VSS77';
NODE_NAME     J19 182
 '@T6G_MB_LIB.T6G(SCH_1):PAGE88_I352@PURE_QUANTA.SCONN288_DDR506112002KQ(CHIPS)':
 'VSS78': CDS_PINID='VSS78';
NODE_NAME     J19 184
 '@T6G_MB_LIB.T6G(SCH_1):PAGE88_I352@PURE_QUANTA.SCONN288_DDR506112002KQ(CHIPS)':
 'VSS79': CDS_PINID='VSS79';
NODE_NAME     J19 186
 '@T6G_MB_LIB.T6G(SCH_1):PAGE88_I352@PURE_QUANTA.SCONN288_DDR506112002KQ(CHIPS)':
 'VSS80': CDS_PINID='VSS80';
NODE_NAME     J19 188
 '@T6G_MB_LIB.T6G(SCH_1):PAGE88_I352@PURE_QUANTA.SCONN288_DDR506112002KQ(CHIPS)':
 'VSS81': CDS_PINID='VSS81';
NODE_NAME     J19 191
 '@T6G_MB_LIB.T6G(SCH_1):PAGE88_I352@PURE_QUANTA.SCONN288_DDR506112002KQ(CHIPS)':
 'VSS82': CDS_PINID='VSS82';
NODE_NAME     J19 193
 '@T6G_MB_LIB.T6G(SCH_1):PAGE88_I352@PURE_QUANTA.SCONN288_DDR506112002KQ(CHIPS)':
 'VSS83': CDS_PINID='VSS83';
NODE_NAME     J19 195
 '@T6G_MB_LIB.T6G(SCH_1):PAGE88_I352@PURE_QUANTA.SCONN288_DDR506112002KQ(CHIPS)':
 'VSS84': CDS_PINID='VSS84';
NODE_NAME     J19 197
 '@T6G_MB_LIB.T6G(SCH_1):PAGE88_I352@PURE_QUANTA.SCONN288_DDR506112002KQ(CHIPS)':
 'VSS85': CDS_PINID='VSS85';
NODE_NAME     J19 199
 '@T6G_MB_LIB.T6G(SCH_1):PAGE88_I352@PURE_QUANTA.SCONN288_DDR506112002KQ(CHIPS)':
 'VSS86': CDS_PINID='VSS86';
NODE_NAME     J19 202
 '@T6G_MB_LIB.T6G(SCH_1):PAGE88_I352@PURE_QUANTA.SCONN288_DDR506112002KQ(CHIPS)':
 'VSS87': CDS_PINID='VSS87';
NODE_NAME     J19 204
 '@T6G_MB_LIB.T6G(SCH_1):PAGE88_I352@PURE_QUANTA.SCONN288_DDR506112002KQ(CHIPS)':
 'VSS88': CDS_PINID='VSS88';
NODE_NAME     J19 206
 '@T6G_MB_LIB.T6G(SCH_1):PAGE88_I352@PURE_QUANTA.SCONN288_DDR506112002KQ(CHIPS)':
 'VSS89': CDS_PINID='VSS89';
NODE_NAME     J19 208
 '@T6G_MB_LIB.T6G(SCH_1):PAGE88_I352@PURE_QUANTA.SCONN288_DDR506112002KQ(CHIPS)':
 'VSS90': CDS_PINID='VSS90';
NODE_NAME     J19 210
 '@T6G_MB_LIB.T6G(SCH_1):PAGE88_I352@PURE_QUANTA.SCONN288_DDR506112002KQ(CHIPS)':
 'VSS91': CDS_PINID='VSS91';
NODE_NAME     J19 212
 '@T6G_MB_LIB.T6G(SCH_1):PAGE88_I352@PURE_QUANTA.SCONN288_DDR506112002KQ(CHIPS)':
 'VSS92': CDS_PINID='VSS92';
NODE_NAME     J19 214
 '@T6G_MB_LIB.T6G(SCH_1):PAGE88_I352@PURE_QUANTA.SCONN288_DDR506112002KQ(CHIPS)':
 'VSS93': CDS_PINID='VSS93';
NODE_NAME     J19 216
 '@T6G_MB_LIB.T6G(SCH_1):PAGE88_I352@PURE_QUANTA.SCONN288_DDR506112002KQ(CHIPS)':
 'VSS94': CDS_PINID='VSS94';
NODE_NAME     J19 219
 '@T6G_MB_LIB.T6G(SCH_1):PAGE88_I352@PURE_QUANTA.SCONN288_DDR506112002KQ(CHIPS)':
 'VSS95': CDS_PINID='VSS95';
NODE_NAME     J19 222
 '@T6G_MB_LIB.T6G(SCH_1):PAGE88_I352@PURE_QUANTA.SCONN288_DDR506112002KQ(CHIPS)':
 'VSS96': CDS_PINID='VSS96';
NODE_NAME     J19 224
 '@T6G_MB_LIB.T6G(SCH_1):PAGE88_I352@PURE_QUANTA.SCONN288_DDR506112002KQ(CHIPS)':
 'VSS97': CDS_PINID='VSS97';
NODE_NAME     J19 226
 '@T6G_MB_LIB.T6G(SCH_1):PAGE88_I352@PURE_QUANTA.SCONN288_DDR506112002KQ(CHIPS)':
 'VSS98': CDS_PINID='VSS98';
NODE_NAME     J19 228
 '@T6G_MB_LIB.T6G(SCH_1):PAGE88_I352@PURE_QUANTA.SCONN288_DDR506112002KQ(CHIPS)':
 'VSS99': CDS_PINID='VSS99';
NODE_NAME     J19 230
 '@T6G_MB_LIB.T6G(SCH_1):PAGE88_I352@PURE_QUANTA.SCONN288_DDR506112002KQ(CHIPS)':
 'VSS100': CDS_PINID='VSS100';
NODE_NAME     J19 233
 '@T6G_MB_LIB.T6G(SCH_1):PAGE88_I352@PURE_QUANTA.SCONN288_DDR506112002KQ(CHIPS)':
 'VSS101': CDS_PINID='VSS101';
NODE_NAME     J19 235
 '@T6G_MB_LIB.T6G(SCH_1):PAGE88_I352@PURE_QUANTA.SCONN288_DDR506112002KQ(CHIPS)':
 'VSS102': CDS_PINID='VSS102';
NODE_NAME     J19 237
 '@T6G_MB_LIB.T6G(SCH_1):PAGE88_I352@PURE_QUANTA.SCONN288_DDR506112002KQ(CHIPS)':
 'VSS103': CDS_PINID='VSS103';
NODE_NAME     J19 240
 '@T6G_MB_LIB.T6G(SCH_1):PAGE88_I352@PURE_QUANTA.SCONN288_DDR506112002KQ(CHIPS)':
 'VSS104': CDS_PINID='VSS104';
NODE_NAME     J19 242
 '@T6G_MB_LIB.T6G(SCH_1):PAGE88_I352@PURE_QUANTA.SCONN288_DDR506112002KQ(CHIPS)':
 'VSS105': CDS_PINID='VSS105';
NODE_NAME     J19 244
 '@T6G_MB_LIB.T6G(SCH_1):PAGE88_I352@PURE_QUANTA.SCONN288_DDR506112002KQ(CHIPS)':
 'VSS106': CDS_PINID='VSS106';
NODE_NAME     J19 246
 '@T6G_MB_LIB.T6G(SCH_1):PAGE88_I352@PURE_QUANTA.SCONN288_DDR506112002KQ(CHIPS)':
 'VSS107': CDS_PINID='VSS107';
NODE_NAME     J19 248
 '@T6G_MB_LIB.T6G(SCH_1):PAGE88_I352@PURE_QUANTA.SCONN288_DDR506112002KQ(CHIPS)':
 'VSS108': CDS_PINID='VSS108';
NODE_NAME     J19 251
 '@T6G_MB_LIB.T6G(SCH_1):PAGE88_I352@PURE_QUANTA.SCONN288_DDR506112002KQ(CHIPS)':
 'VSS109': CDS_PINID='VSS109';
NODE_NAME     J19 253
 '@T6G_MB_LIB.T6G(SCH_1):PAGE88_I352@PURE_QUANTA.SCONN288_DDR506112002KQ(CHIPS)':
 'VSS110': CDS_PINID='VSS110';
NODE_NAME     J19 255
 '@T6G_MB_LIB.T6G(SCH_1):PAGE88_I352@PURE_QUANTA.SCONN288_DDR506112002KQ(CHIPS)':
 'VSS111': CDS_PINID='VSS111';
NODE_NAME     J19 257
 '@T6G_MB_LIB.T6G(SCH_1):PAGE88_I352@PURE_QUANTA.SCONN288_DDR506112002KQ(CHIPS)':
 'VSS112': CDS_PINID='VSS112';
NODE_NAME     J19 259
 '@T6G_MB_LIB.T6G(SCH_1):PAGE88_I352@PURE_QUANTA.SCONN288_DDR506112002KQ(CHIPS)':
 'VSS113': CDS_PINID='VSS113';
NODE_NAME     J19 262
 '@T6G_MB_LIB.T6G(SCH_1):PAGE88_I352@PURE_QUANTA.SCONN288_DDR506112002KQ(CHIPS)':
 'VSS114': CDS_PINID='VSS114';
NODE_NAME     J19 264
 '@T6G_MB_LIB.T6G(SCH_1):PAGE88_I352@PURE_QUANTA.SCONN288_DDR506112002KQ(CHIPS)':
 'VSS115': CDS_PINID='VSS115';
NODE_NAME     J19 266
 '@T6G_MB_LIB.T6G(SCH_1):PAGE88_I352@PURE_QUANTA.SCONN288_DDR506112002KQ(CHIPS)':
 'VSS116': CDS_PINID='VSS116';
NODE_NAME     J19 268
 '@T6G_MB_LIB.T6G(SCH_1):PAGE88_I352@PURE_QUANTA.SCONN288_DDR506112002KQ(CHIPS)':
 'VSS117': CDS_PINID='VSS117';
NODE_NAME     J19 270
 '@T6G_MB_LIB.T6G(SCH_1):PAGE88_I352@PURE_QUANTA.SCONN288_DDR506112002KQ(CHIPS)':
 'VSS118': CDS_PINID='VSS118';
NODE_NAME     J19 273
 '@T6G_MB_LIB.T6G(SCH_1):PAGE88_I352@PURE_QUANTA.SCONN288_DDR506112002KQ(CHIPS)':
 'VSS119': CDS_PINID='VSS119';
NODE_NAME     J19 275
 '@T6G_MB_LIB.T6G(SCH_1):PAGE88_I352@PURE_QUANTA.SCONN288_DDR506112002KQ(CHIPS)':
 'VSS120': CDS_PINID='VSS120';
NODE_NAME     J19 277
 '@T6G_MB_LIB.T6G(SCH_1):PAGE88_I352@PURE_QUANTA.SCONN288_DDR506112002KQ(CHIPS)':
 'VSS121': CDS_PINID='VSS121';
NODE_NAME     J19 279
 '@T6G_MB_LIB.T6G(SCH_1):PAGE88_I352@PURE_QUANTA.SCONN288_DDR506112002KQ(CHIPS)':
 'VSS122': CDS_PINID='VSS122';
NODE_NAME     J19 281
 '@T6G_MB_LIB.T6G(SCH_1):PAGE88_I352@PURE_QUANTA.SCONN288_DDR506112002KQ(CHIPS)':
 'VSS123': CDS_PINID='VSS123';
NODE_NAME     J19 284
 '@T6G_MB_LIB.T6G(SCH_1):PAGE88_I352@PURE_QUANTA.SCONN288_DDR506112002KQ(CHIPS)':
 'VSS124': CDS_PINID='VSS124';
NODE_NAME     J19 286
 '@T6G_MB_LIB.T6G(SCH_1):PAGE88_I352@PURE_QUANTA.SCONN288_DDR506112002KQ(CHIPS)':
 'VSS125': CDS_PINID='VSS125';
NODE_NAME     J19 288
 '@T6G_MB_LIB.T6G(SCH_1):PAGE88_I352@PURE_QUANTA.SCONN288_DDR506112002KQ(CHIPS)':
 'VSS126': CDS_PINID='VSS126';
NODE_NAME     C100 2
 '@T6G_MB_LIB.T6G(SCH_1):PAGE88_I362@PURE_QUANTA.Q_CAP(CHIPS)':
 'B': CDS_PINID='B';
NODE_NAME     C149 2
 '@T6G_MB_LIB.T6G(SCH_1):PAGE88_I417@PURE_QUANTA.Q_CAP(CHIPS)':
 'B': CDS_PINID='B';
NODE_NAME     C150 2
 '@T6G_MB_LIB.T6G(SCH_1):PAGE88_I418@PURE_QUANTA.Q_CAP(CHIPS)':
 'B': CDS_PINID='B';
NODE_NAME     R5 2
 '@T6G_MB_LIB.T6G(SCH_1):PAGE89_I331@PURE_QUANTA.Q_RES(CHIPS)':
 'B':XNET_PINS='2',
 CDS_PINID='B';
NODE_NAME     J21 G1
 '@T6G_MB_LIB.T6G(SCH_1):PAGE89_I350@PURE_QUANTA.SCONN288_DDR506112002KQ(CHIPS)':
 'G1': CDS_PINID='G1';
NODE_NAME     J21 G2
 '@T6G_MB_LIB.T6G(SCH_1):PAGE89_I350@PURE_QUANTA.SCONN288_DDR506112002KQ(CHIPS)':
 'G2': CDS_PINID='G2';
NODE_NAME     J21 G3
 '@T6G_MB_LIB.T6G(SCH_1):PAGE89_I350@PURE_QUANTA.SCONN288_DDR506112002KQ(CHIPS)':
 'G3': CDS_PINID='G3';
NODE_NAME     J21 6
 '@T6G_MB_LIB.T6G(SCH_1):PAGE89_I350@PURE_QUANTA.SCONN288_DDR506112002KQ(CHIPS)':
 'VSS0': CDS_PINID='VSS0';
NODE_NAME     J21 8
 '@T6G_MB_LIB.T6G(SCH_1):PAGE89_I350@PURE_QUANTA.SCONN288_DDR506112002KQ(CHIPS)':
 'VSS1': CDS_PINID='VSS1';
NODE_NAME     J21 10
 '@T6G_MB_LIB.T6G(SCH_1):PAGE89_I350@PURE_QUANTA.SCONN288_DDR506112002KQ(CHIPS)':
 'VSS2': CDS_PINID='VSS2';
NODE_NAME     J21 13
 '@T6G_MB_LIB.T6G(SCH_1):PAGE89_I350@PURE_QUANTA.SCONN288_DDR506112002KQ(CHIPS)':
 'VSS3': CDS_PINID='VSS3';
NODE_NAME     J21 15
 '@T6G_MB_LIB.T6G(SCH_1):PAGE89_I350@PURE_QUANTA.SCONN288_DDR506112002KQ(CHIPS)':
 'VSS4': CDS_PINID='VSS4';
NODE_NAME     J21 17
 '@T6G_MB_LIB.T6G(SCH_1):PAGE89_I350@PURE_QUANTA.SCONN288_DDR506112002KQ(CHIPS)':
 'VSS5': CDS_PINID='VSS5';
NODE_NAME     J21 19
 '@T6G_MB_LIB.T6G(SCH_1):PAGE89_I350@PURE_QUANTA.SCONN288_DDR506112002KQ(CHIPS)':
 'VSS6': CDS_PINID='VSS6';
NODE_NAME     J21 21
 '@T6G_MB_LIB.T6G(SCH_1):PAGE89_I350@PURE_QUANTA.SCONN288_DDR506112002KQ(CHIPS)':
 'VSS7': CDS_PINID='VSS7';
NODE_NAME     J21 24
 '@T6G_MB_LIB.T6G(SCH_1):PAGE89_I350@PURE_QUANTA.SCONN288_DDR506112002KQ(CHIPS)':
 'VSS8': CDS_PINID='VSS8';
NODE_NAME     J21 26
 '@T6G_MB_LIB.T6G(SCH_1):PAGE89_I350@PURE_QUANTA.SCONN288_DDR506112002KQ(CHIPS)':
 'VSS9': CDS_PINID='VSS9';
NODE_NAME     J21 28
 '@T6G_MB_LIB.T6G(SCH_1):PAGE89_I350@PURE_QUANTA.SCONN288_DDR506112002KQ(CHIPS)':
 'VSS10': CDS_PINID='VSS10';
NODE_NAME     J21 30
 '@T6G_MB_LIB.T6G(SCH_1):PAGE89_I350@PURE_QUANTA.SCONN288_DDR506112002KQ(CHIPS)':
 'VSS11': CDS_PINID='VSS11';
NODE_NAME     J21 32
 '@T6G_MB_LIB.T6G(SCH_1):PAGE89_I350@PURE_QUANTA.SCONN288_DDR506112002KQ(CHIPS)':
 'VSS12': CDS_PINID='VSS12';
NODE_NAME     J21 35
 '@T6G_MB_LIB.T6G(SCH_1):PAGE89_I350@PURE_QUANTA.SCONN288_DDR506112002KQ(CHIPS)':
 'VSS13': CDS_PINID='VSS13';
NODE_NAME     J21 37
 '@T6G_MB_LIB.T6G(SCH_1):PAGE89_I350@PURE_QUANTA.SCONN288_DDR506112002KQ(CHIPS)':
 'VSS14': CDS_PINID='VSS14';
NODE_NAME     J21 39
 '@T6G_MB_LIB.T6G(SCH_1):PAGE89_I350@PURE_QUANTA.SCONN288_DDR506112002KQ(CHIPS)':
 'VSS15': CDS_PINID='VSS15';
NODE_NAME     J21 41
 '@T6G_MB_LIB.T6G(SCH_1):PAGE89_I350@PURE_QUANTA.SCONN288_DDR506112002KQ(CHIPS)':
 'VSS16': CDS_PINID='VSS16';
NODE_NAME     J21 43
 '@T6G_MB_LIB.T6G(SCH_1):PAGE89_I350@PURE_QUANTA.SCONN288_DDR506112002KQ(CHIPS)':
 'VSS17': CDS_PINID='VSS17';
NODE_NAME     J21 46
 '@T6G_MB_LIB.T6G(SCH_1):PAGE89_I350@PURE_QUANTA.SCONN288_DDR506112002KQ(CHIPS)':
 'VSS18': CDS_PINID='VSS18';
NODE_NAME     J21 48
 '@T6G_MB_LIB.T6G(SCH_1):PAGE89_I350@PURE_QUANTA.SCONN288_DDR506112002KQ(CHIPS)':
 'VSS19': CDS_PINID='VSS19';
NODE_NAME     J21 50
 '@T6G_MB_LIB.T6G(SCH_1):PAGE89_I350@PURE_QUANTA.SCONN288_DDR506112002KQ(CHIPS)':
 'VSS20': CDS_PINID='VSS20';
NODE_NAME     J21 52
 '@T6G_MB_LIB.T6G(SCH_1):PAGE89_I350@PURE_QUANTA.SCONN288_DDR506112002KQ(CHIPS)':
 'VSS21': CDS_PINID='VSS21';
NODE_NAME     J21 54
 '@T6G_MB_LIB.T6G(SCH_1):PAGE89_I350@PURE_QUANTA.SCONN288_DDR506112002KQ(CHIPS)':
 'VSS22': CDS_PINID='VSS22';
NODE_NAME     J21 57
 '@T6G_MB_LIB.T6G(SCH_1):PAGE89_I350@PURE_QUANTA.SCONN288_DDR506112002KQ(CHIPS)':
 'VSS23': CDS_PINID='VSS23';
NODE_NAME     J21 59
 '@T6G_MB_LIB.T6G(SCH_1):PAGE89_I350@PURE_QUANTA.SCONN288_DDR506112002KQ(CHIPS)':
 'VSS24': CDS_PINID='VSS24';
NODE_NAME     J21 61
 '@T6G_MB_LIB.T6G(SCH_1):PAGE89_I350@PURE_QUANTA.SCONN288_DDR506112002KQ(CHIPS)':
 'VSS25': CDS_PINID='VSS25';
NODE_NAME     J21 63
 '@T6G_MB_LIB.T6G(SCH_1):PAGE89_I350@PURE_QUANTA.SCONN288_DDR506112002KQ(CHIPS)':
 'VSS26': CDS_PINID='VSS26';
NODE_NAME     J21 65
 '@T6G_MB_LIB.T6G(SCH_1):PAGE89_I350@PURE_QUANTA.SCONN288_DDR506112002KQ(CHIPS)':
 'VSS27': CDS_PINID='VSS27';
NODE_NAME     J21 67
 '@T6G_MB_LIB.T6G(SCH_1):PAGE89_I350@PURE_QUANTA.SCONN288_DDR506112002KQ(CHIPS)':
 'VSS28': CDS_PINID='VSS28';
NODE_NAME     J21 69
 '@T6G_MB_LIB.T6G(SCH_1):PAGE89_I350@PURE_QUANTA.SCONN288_DDR506112002KQ(CHIPS)':
 'VSS29': CDS_PINID='VSS29';
NODE_NAME     J21 71
 '@T6G_MB_LIB.T6G(SCH_1):PAGE89_I350@PURE_QUANTA.SCONN288_DDR506112002KQ(CHIPS)':
 'VSS30': CDS_PINID='VSS30';
NODE_NAME     J21 73
 '@T6G_MB_LIB.T6G(SCH_1):PAGE89_I350@PURE_QUANTA.SCONN288_DDR506112002KQ(CHIPS)':
 'VSS31': CDS_PINID='VSS31';
NODE_NAME     J21 75
 '@T6G_MB_LIB.T6G(SCH_1):PAGE89_I350@PURE_QUANTA.SCONN288_DDR506112002KQ(CHIPS)':
 'VSS32': CDS_PINID='VSS32';
NODE_NAME     J21 77
 '@T6G_MB_LIB.T6G(SCH_1):PAGE89_I350@PURE_QUANTA.SCONN288_DDR506112002KQ(CHIPS)':
 'VSS33': CDS_PINID='VSS33';
NODE_NAME     J21 79
 '@T6G_MB_LIB.T6G(SCH_1):PAGE89_I350@PURE_QUANTA.SCONN288_DDR506112002KQ(CHIPS)':
 'VSS34': CDS_PINID='VSS34';
NODE_NAME     J21 81
 '@T6G_MB_LIB.T6G(SCH_1):PAGE89_I350@PURE_QUANTA.SCONN288_DDR506112002KQ(CHIPS)':
 'VSS35': CDS_PINID='VSS35';
NODE_NAME     J21 83
 '@T6G_MB_LIB.T6G(SCH_1):PAGE89_I350@PURE_QUANTA.SCONN288_DDR506112002KQ(CHIPS)':
 'VSS36': CDS_PINID='VSS36';
NODE_NAME     J21 85
 '@T6G_MB_LIB.T6G(SCH_1):PAGE89_I350@PURE_QUANTA.SCONN288_DDR506112002KQ(CHIPS)':
 'VSS37': CDS_PINID='VSS37';
NODE_NAME     J21 88
 '@T6G_MB_LIB.T6G(SCH_1):PAGE89_I350@PURE_QUANTA.SCONN288_DDR506112002KQ(CHIPS)':
 'VSS38': CDS_PINID='VSS38';
NODE_NAME     J21 90
 '@T6G_MB_LIB.T6G(SCH_1):PAGE89_I350@PURE_QUANTA.SCONN288_DDR506112002KQ(CHIPS)':
 'VSS39': CDS_PINID='VSS39';
NODE_NAME     J21 92
 '@T6G_MB_LIB.T6G(SCH_1):PAGE89_I350@PURE_QUANTA.SCONN288_DDR506112002KQ(CHIPS)':
 'VSS40': CDS_PINID='VSS40';
NODE_NAME     J21 95
 '@T6G_MB_LIB.T6G(SCH_1):PAGE89_I350@PURE_QUANTA.SCONN288_DDR506112002KQ(CHIPS)':
 'VSS41': CDS_PINID='VSS41';
NODE_NAME     J21 97
 '@T6G_MB_LIB.T6G(SCH_1):PAGE89_I350@PURE_QUANTA.SCONN288_DDR506112002KQ(CHIPS)':
 'VSS42': CDS_PINID='VSS42';
NODE_NAME     J21 99
 '@T6G_MB_LIB.T6G(SCH_1):PAGE89_I350@PURE_QUANTA.SCONN288_DDR506112002KQ(CHIPS)':
 'VSS43': CDS_PINID='VSS43';
NODE_NAME     J21 101
 '@T6G_MB_LIB.T6G(SCH_1):PAGE89_I350@PURE_QUANTA.SCONN288_DDR506112002KQ(CHIPS)':
 'VSS44': CDS_PINID='VSS44';
NODE_NAME     J21 103
 '@T6G_MB_LIB.T6G(SCH_1):PAGE89_I350@PURE_QUANTA.SCONN288_DDR506112002KQ(CHIPS)':
 'VSS45': CDS_PINID='VSS45';
NODE_NAME     J21 106
 '@T6G_MB_LIB.T6G(SCH_1):PAGE89_I350@PURE_QUANTA.SCONN288_DDR506112002KQ(CHIPS)':
 'VSS46': CDS_PINID='VSS46';
NODE_NAME     J21 108
 '@T6G_MB_LIB.T6G(SCH_1):PAGE89_I350@PURE_QUANTA.SCONN288_DDR506112002KQ(CHIPS)':
 'VSS47': CDS_PINID='VSS47';
NODE_NAME     J21 110
 '@T6G_MB_LIB.T6G(SCH_1):PAGE89_I350@PURE_QUANTA.SCONN288_DDR506112002KQ(CHIPS)':
 'VSS48': CDS_PINID='VSS48';
NODE_NAME     J21 112
 '@T6G_MB_LIB.T6G(SCH_1):PAGE89_I350@PURE_QUANTA.SCONN288_DDR506112002KQ(CHIPS)':
 'VSS49': CDS_PINID='VSS49';
NODE_NAME     J21 114
 '@T6G_MB_LIB.T6G(SCH_1):PAGE89_I350@PURE_QUANTA.SCONN288_DDR506112002KQ(CHIPS)':
 'VSS50': CDS_PINID='VSS50';
NODE_NAME     J21 117
 '@T6G_MB_LIB.T6G(SCH_1):PAGE89_I350@PURE_QUANTA.SCONN288_DDR506112002KQ(CHIPS)':
 'VSS51': CDS_PINID='VSS51';
NODE_NAME     J21 119
 '@T6G_MB_LIB.T6G(SCH_1):PAGE89_I350@PURE_QUANTA.SCONN288_DDR506112002KQ(CHIPS)':
 'VSS52': CDS_PINID='VSS52';
NODE_NAME     J21 121
 '@T6G_MB_LIB.T6G(SCH_1):PAGE89_I350@PURE_QUANTA.SCONN288_DDR506112002KQ(CHIPS)':
 'VSS53': CDS_PINID='VSS53';
NODE_NAME     J21 123
 '@T6G_MB_LIB.T6G(SCH_1):PAGE89_I350@PURE_QUANTA.SCONN288_DDR506112002KQ(CHIPS)':
 'VSS54': CDS_PINID='VSS54';
NODE_NAME     J21 125
 '@T6G_MB_LIB.T6G(SCH_1):PAGE89_I350@PURE_QUANTA.SCONN288_DDR506112002KQ(CHIPS)':
 'VSS55': CDS_PINID='VSS55';
NODE_NAME     J21 128
 '@T6G_MB_LIB.T6G(SCH_1):PAGE89_I350@PURE_QUANTA.SCONN288_DDR506112002KQ(CHIPS)':
 'VSS56': CDS_PINID='VSS56';
NODE_NAME     J21 130
 '@T6G_MB_LIB.T6G(SCH_1):PAGE89_I350@PURE_QUANTA.SCONN288_DDR506112002KQ(CHIPS)':
 'VSS57': CDS_PINID='VSS57';
NODE_NAME     J21 132
 '@T6G_MB_LIB.T6G(SCH_1):PAGE89_I350@PURE_QUANTA.SCONN288_DDR506112002KQ(CHIPS)':
 'VSS58': CDS_PINID='VSS58';
NODE_NAME     J21 134
 '@T6G_MB_LIB.T6G(SCH_1):PAGE89_I350@PURE_QUANTA.SCONN288_DDR506112002KQ(CHIPS)':
 'VSS59': CDS_PINID='VSS59';
NODE_NAME     J21 136
 '@T6G_MB_LIB.T6G(SCH_1):PAGE89_I350@PURE_QUANTA.SCONN288_DDR506112002KQ(CHIPS)':
 'VSS60': CDS_PINID='VSS60';
NODE_NAME     J21 139
 '@T6G_MB_LIB.T6G(SCH_1):PAGE89_I350@PURE_QUANTA.SCONN288_DDR506112002KQ(CHIPS)':
 'VSS61': CDS_PINID='VSS61';
NODE_NAME     J21 141
 '@T6G_MB_LIB.T6G(SCH_1):PAGE89_I350@PURE_QUANTA.SCONN288_DDR506112002KQ(CHIPS)':
 'VSS62': CDS_PINID='VSS62';
NODE_NAME     J21 143
 '@T6G_MB_LIB.T6G(SCH_1):PAGE89_I350@PURE_QUANTA.SCONN288_DDR506112002KQ(CHIPS)':
 'VSS63': CDS_PINID='VSS63';
NODE_NAME     J21 151
 '@T6G_MB_LIB.T6G(SCH_1):PAGE89_I350@PURE_QUANTA.SCONN288_DDR506112002KQ(CHIPS)':
 'VSS64': CDS_PINID='VSS64';
NODE_NAME     J21 153
 '@T6G_MB_LIB.T6G(SCH_1):PAGE89_I350@PURE_QUANTA.SCONN288_DDR506112002KQ(CHIPS)':
 'VSS65': CDS_PINID='VSS65';
NODE_NAME     J21 155
 '@T6G_MB_LIB.T6G(SCH_1):PAGE89_I350@PURE_QUANTA.SCONN288_DDR506112002KQ(CHIPS)':
 'VSS66': CDS_PINID='VSS66';
NODE_NAME     J21 158
 '@T6G_MB_LIB.T6G(SCH_1):PAGE89_I350@PURE_QUANTA.SCONN288_DDR506112002KQ(CHIPS)':
 'VSS67': CDS_PINID='VSS67';
NODE_NAME     J21 160
 '@T6G_MB_LIB.T6G(SCH_1):PAGE89_I350@PURE_QUANTA.SCONN288_DDR506112002KQ(CHIPS)':
 'VSS68': CDS_PINID='VSS68';
NODE_NAME     J21 162
 '@T6G_MB_LIB.T6G(SCH_1):PAGE89_I350@PURE_QUANTA.SCONN288_DDR506112002KQ(CHIPS)':
 'VSS69': CDS_PINID='VSS69';
NODE_NAME     J21 164
 '@T6G_MB_LIB.T6G(SCH_1):PAGE89_I350@PURE_QUANTA.SCONN288_DDR506112002KQ(CHIPS)':
 'VSS70': CDS_PINID='VSS70';
NODE_NAME     J21 166
 '@T6G_MB_LIB.T6G(SCH_1):PAGE89_I350@PURE_QUANTA.SCONN288_DDR506112002KQ(CHIPS)':
 'VSS71': CDS_PINID='VSS71';
NODE_NAME     J21 169
 '@T6G_MB_LIB.T6G(SCH_1):PAGE89_I350@PURE_QUANTA.SCONN288_DDR506112002KQ(CHIPS)':
 'VSS72': CDS_PINID='VSS72';
NODE_NAME     J21 171
 '@T6G_MB_LIB.T6G(SCH_1):PAGE89_I350@PURE_QUANTA.SCONN288_DDR506112002KQ(CHIPS)':
 'VSS73': CDS_PINID='VSS73';
NODE_NAME     J21 173
 '@T6G_MB_LIB.T6G(SCH_1):PAGE89_I350@PURE_QUANTA.SCONN288_DDR506112002KQ(CHIPS)':
 'VSS74': CDS_PINID='VSS74';
NODE_NAME     J21 175
 '@T6G_MB_LIB.T6G(SCH_1):PAGE89_I350@PURE_QUANTA.SCONN288_DDR506112002KQ(CHIPS)':
 'VSS75': CDS_PINID='VSS75';
NODE_NAME     J21 177
 '@T6G_MB_LIB.T6G(SCH_1):PAGE89_I350@PURE_QUANTA.SCONN288_DDR506112002KQ(CHIPS)':
 'VSS76': CDS_PINID='VSS76';
NODE_NAME     J21 180
 '@T6G_MB_LIB.T6G(SCH_1):PAGE89_I350@PURE_QUANTA.SCONN288_DDR506112002KQ(CHIPS)':
 'VSS77': CDS_PINID='VSS77';
NODE_NAME     J21 182
 '@T6G_MB_LIB.T6G(SCH_1):PAGE89_I350@PURE_QUANTA.SCONN288_DDR506112002KQ(CHIPS)':
 'VSS78': CDS_PINID='VSS78';
NODE_NAME     J21 184
 '@T6G_MB_LIB.T6G(SCH_1):PAGE89_I350@PURE_QUANTA.SCONN288_DDR506112002KQ(CHIPS)':
 'VSS79': CDS_PINID='VSS79';
NODE_NAME     J21 186
 '@T6G_MB_LIB.T6G(SCH_1):PAGE89_I350@PURE_QUANTA.SCONN288_DDR506112002KQ(CHIPS)':
 'VSS80': CDS_PINID='VSS80';
NODE_NAME     J21 188
 '@T6G_MB_LIB.T6G(SCH_1):PAGE89_I350@PURE_QUANTA.SCONN288_DDR506112002KQ(CHIPS)':
 'VSS81': CDS_PINID='VSS81';
NODE_NAME     J21 191
 '@T6G_MB_LIB.T6G(SCH_1):PAGE89_I350@PURE_QUANTA.SCONN288_DDR506112002KQ(CHIPS)':
 'VSS82': CDS_PINID='VSS82';
NODE_NAME     J21 193
 '@T6G_MB_LIB.T6G(SCH_1):PAGE89_I350@PURE_QUANTA.SCONN288_DDR506112002KQ(CHIPS)':
 'VSS83': CDS_PINID='VSS83';
NODE_NAME     J21 195
 '@T6G_MB_LIB.T6G(SCH_1):PAGE89_I350@PURE_QUANTA.SCONN288_DDR506112002KQ(CHIPS)':
 'VSS84': CDS_PINID='VSS84';
NODE_NAME     J21 197
 '@T6G_MB_LIB.T6G(SCH_1):PAGE89_I350@PURE_QUANTA.SCONN288_DDR506112002KQ(CHIPS)':
 'VSS85': CDS_PINID='VSS85';
NODE_NAME     J21 199
 '@T6G_MB_LIB.T6G(SCH_1):PAGE89_I350@PURE_QUANTA.SCONN288_DDR506112002KQ(CHIPS)':
 'VSS86': CDS_PINID='VSS86';
NODE_NAME     J21 202
 '@T6G_MB_LIB.T6G(SCH_1):PAGE89_I350@PURE_QUANTA.SCONN288_DDR506112002KQ(CHIPS)':
 'VSS87': CDS_PINID='VSS87';
NODE_NAME     J21 204
 '@T6G_MB_LIB.T6G(SCH_1):PAGE89_I350@PURE_QUANTA.SCONN288_DDR506112002KQ(CHIPS)':
 'VSS88': CDS_PINID='VSS88';
NODE_NAME     J21 206
 '@T6G_MB_LIB.T6G(SCH_1):PAGE89_I350@PURE_QUANTA.SCONN288_DDR506112002KQ(CHIPS)':
 'VSS89': CDS_PINID='VSS89';
NODE_NAME     J21 208
 '@T6G_MB_LIB.T6G(SCH_1):PAGE89_I350@PURE_QUANTA.SCONN288_DDR506112002KQ(CHIPS)':
 'VSS90': CDS_PINID='VSS90';
NODE_NAME     J21 210
 '@T6G_MB_LIB.T6G(SCH_1):PAGE89_I350@PURE_QUANTA.SCONN288_DDR506112002KQ(CHIPS)':
 'VSS91': CDS_PINID='VSS91';
NODE_NAME     J21 212
 '@T6G_MB_LIB.T6G(SCH_1):PAGE89_I350@PURE_QUANTA.SCONN288_DDR506112002KQ(CHIPS)':
 'VSS92': CDS_PINID='VSS92';
NODE_NAME     J21 214
 '@T6G_MB_LIB.T6G(SCH_1):PAGE89_I350@PURE_QUANTA.SCONN288_DDR506112002KQ(CHIPS)':
 'VSS93': CDS_PINID='VSS93';
NODE_NAME     J21 216
 '@T6G_MB_LIB.T6G(SCH_1):PAGE89_I350@PURE_QUANTA.SCONN288_DDR506112002KQ(CHIPS)':
 'VSS94': CDS_PINID='VSS94';
NODE_NAME     J21 219
 '@T6G_MB_LIB.T6G(SCH_1):PAGE89_I350@PURE_QUANTA.SCONN288_DDR506112002KQ(CHIPS)':
 'VSS95': CDS_PINID='VSS95';
NODE_NAME     J21 222
 '@T6G_MB_LIB.T6G(SCH_1):PAGE89_I350@PURE_QUANTA.SCONN288_DDR506112002KQ(CHIPS)':
 'VSS96': CDS_PINID='VSS96';
NODE_NAME     J21 224
 '@T6G_MB_LIB.T6G(SCH_1):PAGE89_I350@PURE_QUANTA.SCONN288_DDR506112002KQ(CHIPS)':
 'VSS97': CDS_PINID='VSS97';
NODE_NAME     J21 226
 '@T6G_MB_LIB.T6G(SCH_1):PAGE89_I350@PURE_QUANTA.SCONN288_DDR506112002KQ(CHIPS)':
 'VSS98': CDS_PINID='VSS98';
NODE_NAME     J21 228
 '@T6G_MB_LIB.T6G(SCH_1):PAGE89_I350@PURE_QUANTA.SCONN288_DDR506112002KQ(CHIPS)':
 'VSS99': CDS_PINID='VSS99';
NODE_NAME     J21 230
 '@T6G_MB_LIB.T6G(SCH_1):PAGE89_I350@PURE_QUANTA.SCONN288_DDR506112002KQ(CHIPS)':
 'VSS100': CDS_PINID='VSS100';
NODE_NAME     J21 233
 '@T6G_MB_LIB.T6G(SCH_1):PAGE89_I350@PURE_QUANTA.SCONN288_DDR506112002KQ(CHIPS)':
 'VSS101': CDS_PINID='VSS101';
NODE_NAME     J21 235
 '@T6G_MB_LIB.T6G(SCH_1):PAGE89_I350@PURE_QUANTA.SCONN288_DDR506112002KQ(CHIPS)':
 'VSS102': CDS_PINID='VSS102';
NODE_NAME     J21 237
 '@T6G_MB_LIB.T6G(SCH_1):PAGE89_I350@PURE_QUANTA.SCONN288_DDR506112002KQ(CHIPS)':
 'VSS103': CDS_PINID='VSS103';
NODE_NAME     J21 240
 '@T6G_MB_LIB.T6G(SCH_1):PAGE89_I350@PURE_QUANTA.SCONN288_DDR506112002KQ(CHIPS)':
 'VSS104': CDS_PINID='VSS104';
NODE_NAME     J21 242
 '@T6G_MB_LIB.T6G(SCH_1):PAGE89_I350@PURE_QUANTA.SCONN288_DDR506112002KQ(CHIPS)':
 'VSS105': CDS_PINID='VSS105';
NODE_NAME     J21 244
 '@T6G_MB_LIB.T6G(SCH_1):PAGE89_I350@PURE_QUANTA.SCONN288_DDR506112002KQ(CHIPS)':
 'VSS106': CDS_PINID='VSS106';
NODE_NAME     J21 246
 '@T6G_MB_LIB.T6G(SCH_1):PAGE89_I350@PURE_QUANTA.SCONN288_DDR506112002KQ(CHIPS)':
 'VSS107': CDS_PINID='VSS107';
NODE_NAME     J21 248
 '@T6G_MB_LIB.T6G(SCH_1):PAGE89_I350@PURE_QUANTA.SCONN288_DDR506112002KQ(CHIPS)':
 'VSS108': CDS_PINID='VSS108';
NODE_NAME     J21 251
 '@T6G_MB_LIB.T6G(SCH_1):PAGE89_I350@PURE_QUANTA.SCONN288_DDR506112002KQ(CHIPS)':
 'VSS109': CDS_PINID='VSS109';
NODE_NAME     J21 253
 '@T6G_MB_LIB.T6G(SCH_1):PAGE89_I350@PURE_QUANTA.SCONN288_DDR506112002KQ(CHIPS)':
 'VSS110': CDS_PINID='VSS110';
NODE_NAME     J21 255
 '@T6G_MB_LIB.T6G(SCH_1):PAGE89_I350@PURE_QUANTA.SCONN288_DDR506112002KQ(CHIPS)':
 'VSS111': CDS_PINID='VSS111';
NODE_NAME     J21 257
 '@T6G_MB_LIB.T6G(SCH_1):PAGE89_I350@PURE_QUANTA.SCONN288_DDR506112002KQ(CHIPS)':
 'VSS112': CDS_PINID='VSS112';
NODE_NAME     J21 259
 '@T6G_MB_LIB.T6G(SCH_1):PAGE89_I350@PURE_QUANTA.SCONN288_DDR506112002KQ(CHIPS)':
 'VSS113': CDS_PINID='VSS113';
NODE_NAME     J21 262
 '@T6G_MB_LIB.T6G(SCH_1):PAGE89_I350@PURE_QUANTA.SCONN288_DDR506112002KQ(CHIPS)':
 'VSS114': CDS_PINID='VSS114';
NODE_NAME     J21 264
 '@T6G_MB_LIB.T6G(SCH_1):PAGE89_I350@PURE_QUANTA.SCONN288_DDR506112002KQ(CHIPS)':
 'VSS115': CDS_PINID='VSS115';
NODE_NAME     J21 266
 '@T6G_MB_LIB.T6G(SCH_1):PAGE89_I350@PURE_QUANTA.SCONN288_DDR506112002KQ(CHIPS)':
 'VSS116': CDS_PINID='VSS116';
NODE_NAME     J21 268
 '@T6G_MB_LIB.T6G(SCH_1):PAGE89_I350@PURE_QUANTA.SCONN288_DDR506112002KQ(CHIPS)':
 'VSS117': CDS_PINID='VSS117';
NODE_NAME     J21 270
 '@T6G_MB_LIB.T6G(SCH_1):PAGE89_I350@PURE_QUANTA.SCONN288_DDR506112002KQ(CHIPS)':
 'VSS118': CDS_PINID='VSS118';
NODE_NAME     J21 273
 '@T6G_MB_LIB.T6G(SCH_1):PAGE89_I350@PURE_QUANTA.SCONN288_DDR506112002KQ(CHIPS)':
 'VSS119': CDS_PINID='VSS119';
NODE_NAME     J21 275
 '@T6G_MB_LIB.T6G(SCH_1):PAGE89_I350@PURE_QUANTA.SCONN288_DDR506112002KQ(CHIPS)':
 'VSS120': CDS_PINID='VSS120';
NODE_NAME     J21 277
 '@T6G_MB_LIB.T6G(SCH_1):PAGE89_I350@PURE_QUANTA.SCONN288_DDR506112002KQ(CHIPS)':
 'VSS121': CDS_PINID='VSS121';
NODE_NAME     J21 279
 '@T6G_MB_LIB.T6G(SCH_1):PAGE89_I350@PURE_QUANTA.SCONN288_DDR506112002KQ(CHIPS)':
 'VSS122': CDS_PINID='VSS122';
NODE_NAME     J21 281
 '@T6G_MB_LIB.T6G(SCH_1):PAGE89_I350@PURE_QUANTA.SCONN288_DDR506112002KQ(CHIPS)':
 'VSS123': CDS_PINID='VSS123';
NODE_NAME     J21 284
 '@T6G_MB_LIB.T6G(SCH_1):PAGE89_I350@PURE_QUANTA.SCONN288_DDR506112002KQ(CHIPS)':
 'VSS124': CDS_PINID='VSS124';
NODE_NAME     J21 286
 '@T6G_MB_LIB.T6G(SCH_1):PAGE89_I350@PURE_QUANTA.SCONN288_DDR506112002KQ(CHIPS)':
 'VSS125': CDS_PINID='VSS125';
NODE_NAME     J21 288
 '@T6G_MB_LIB.T6G(SCH_1):PAGE89_I350@PURE_QUANTA.SCONN288_DDR506112002KQ(CHIPS)':
 'VSS126': CDS_PINID='VSS126';
NODE_NAME     C104 2
 '@T6G_MB_LIB.T6G(SCH_1):PAGE89_I360@PURE_QUANTA.Q_CAP(CHIPS)':
 'B': CDS_PINID='B';
NODE_NAME     C151 2
 '@T6G_MB_LIB.T6G(SCH_1):PAGE89_I412@PURE_QUANTA.Q_CAP(CHIPS)':
 'B': CDS_PINID='B';
NODE_NAME     C153 2
 '@T6G_MB_LIB.T6G(SCH_1):PAGE89_I413@PURE_QUANTA.Q_CAP(CHIPS)':
 'B': CDS_PINID='B';
NODE_NAME     R764 2
 '@T6G_MB_LIB.T6G(SCH_1):PAGE90_I349@PURE_QUANTA.Q_RES(CHIPS)':
 'B': CDS_PINID='B';
NODE_NAME     J23 G1
 '@T6G_MB_LIB.T6G(SCH_1):PAGE90_I352@PURE_QUANTA.SCONN288_DDR506112002KQ(CHIPS)':
 'G1': CDS_PINID='G1';
NODE_NAME     J23 G2
 '@T6G_MB_LIB.T6G(SCH_1):PAGE90_I352@PURE_QUANTA.SCONN288_DDR506112002KQ(CHIPS)':
 'G2': CDS_PINID='G2';
NODE_NAME     J23 G3
 '@T6G_MB_LIB.T6G(SCH_1):PAGE90_I352@PURE_QUANTA.SCONN288_DDR506112002KQ(CHIPS)':
 'G3': CDS_PINID='G3';
NODE_NAME     J23 6
 '@T6G_MB_LIB.T6G(SCH_1):PAGE90_I352@PURE_QUANTA.SCONN288_DDR506112002KQ(CHIPS)':
 'VSS0': CDS_PINID='VSS0';
NODE_NAME     J23 8
 '@T6G_MB_LIB.T6G(SCH_1):PAGE90_I352@PURE_QUANTA.SCONN288_DDR506112002KQ(CHIPS)':
 'VSS1': CDS_PINID='VSS1';
NODE_NAME     J23 10
 '@T6G_MB_LIB.T6G(SCH_1):PAGE90_I352@PURE_QUANTA.SCONN288_DDR506112002KQ(CHIPS)':
 'VSS2': CDS_PINID='VSS2';
NODE_NAME     J23 13
 '@T6G_MB_LIB.T6G(SCH_1):PAGE90_I352@PURE_QUANTA.SCONN288_DDR506112002KQ(CHIPS)':
 'VSS3': CDS_PINID='VSS3';
NODE_NAME     J23 15
 '@T6G_MB_LIB.T6G(SCH_1):PAGE90_I352@PURE_QUANTA.SCONN288_DDR506112002KQ(CHIPS)':
 'VSS4': CDS_PINID='VSS4';
NODE_NAME     J23 17
 '@T6G_MB_LIB.T6G(SCH_1):PAGE90_I352@PURE_QUANTA.SCONN288_DDR506112002KQ(CHIPS)':
 'VSS5': CDS_PINID='VSS5';
NODE_NAME     J23 19
 '@T6G_MB_LIB.T6G(SCH_1):PAGE90_I352@PURE_QUANTA.SCONN288_DDR506112002KQ(CHIPS)':
 'VSS6': CDS_PINID='VSS6';
NODE_NAME     J23 21
 '@T6G_MB_LIB.T6G(SCH_1):PAGE90_I352@PURE_QUANTA.SCONN288_DDR506112002KQ(CHIPS)':
 'VSS7': CDS_PINID='VSS7';
NODE_NAME     J23 24
 '@T6G_MB_LIB.T6G(SCH_1):PAGE90_I352@PURE_QUANTA.SCONN288_DDR506112002KQ(CHIPS)':
 'VSS8': CDS_PINID='VSS8';
NODE_NAME     J23 26
 '@T6G_MB_LIB.T6G(SCH_1):PAGE90_I352@PURE_QUANTA.SCONN288_DDR506112002KQ(CHIPS)':
 'VSS9': CDS_PINID='VSS9';
NODE_NAME     J23 28
 '@T6G_MB_LIB.T6G(SCH_1):PAGE90_I352@PURE_QUANTA.SCONN288_DDR506112002KQ(CHIPS)':
 'VSS10': CDS_PINID='VSS10';
NODE_NAME     J23 30
 '@T6G_MB_LIB.T6G(SCH_1):PAGE90_I352@PURE_QUANTA.SCONN288_DDR506112002KQ(CHIPS)':
 'VSS11': CDS_PINID='VSS11';
NODE_NAME     J23 32
 '@T6G_MB_LIB.T6G(SCH_1):PAGE90_I352@PURE_QUANTA.SCONN288_DDR506112002KQ(CHIPS)':
 'VSS12': CDS_PINID='VSS12';
NODE_NAME     J23 35
 '@T6G_MB_LIB.T6G(SCH_1):PAGE90_I352@PURE_QUANTA.SCONN288_DDR506112002KQ(CHIPS)':
 'VSS13': CDS_PINID='VSS13';
NODE_NAME     J23 37
 '@T6G_MB_LIB.T6G(SCH_1):PAGE90_I352@PURE_QUANTA.SCONN288_DDR506112002KQ(CHIPS)':
 'VSS14': CDS_PINID='VSS14';
NODE_NAME     J23 39
 '@T6G_MB_LIB.T6G(SCH_1):PAGE90_I352@PURE_QUANTA.SCONN288_DDR506112002KQ(CHIPS)':
 'VSS15': CDS_PINID='VSS15';
NODE_NAME     J23 41
 '@T6G_MB_LIB.T6G(SCH_1):PAGE90_I352@PURE_QUANTA.SCONN288_DDR506112002KQ(CHIPS)':
 'VSS16': CDS_PINID='VSS16';
NODE_NAME     J23 43
 '@T6G_MB_LIB.T6G(SCH_1):PAGE90_I352@PURE_QUANTA.SCONN288_DDR506112002KQ(CHIPS)':
 'VSS17': CDS_PINID='VSS17';
NODE_NAME     J23 46
 '@T6G_MB_LIB.T6G(SCH_1):PAGE90_I352@PURE_QUANTA.SCONN288_DDR506112002KQ(CHIPS)':
 'VSS18': CDS_PINID='VSS18';
NODE_NAME     J23 48
 '@T6G_MB_LIB.T6G(SCH_1):PAGE90_I352@PURE_QUANTA.SCONN288_DDR506112002KQ(CHIPS)':
 'VSS19': CDS_PINID='VSS19';
NODE_NAME     J23 50
 '@T6G_MB_LIB.T6G(SCH_1):PAGE90_I352@PURE_QUANTA.SCONN288_DDR506112002KQ(CHIPS)':
 'VSS20': CDS_PINID='VSS20';
NODE_NAME     J23 52
 '@T6G_MB_LIB.T6G(SCH_1):PAGE90_I352@PURE_QUANTA.SCONN288_DDR506112002KQ(CHIPS)':
 'VSS21': CDS_PINID='VSS21';
NODE_NAME     J23 54
 '@T6G_MB_LIB.T6G(SCH_1):PAGE90_I352@PURE_QUANTA.SCONN288_DDR506112002KQ(CHIPS)':
 'VSS22': CDS_PINID='VSS22';
NODE_NAME     J23 57
 '@T6G_MB_LIB.T6G(SCH_1):PAGE90_I352@PURE_QUANTA.SCONN288_DDR506112002KQ(CHIPS)':
 'VSS23': CDS_PINID='VSS23';
NODE_NAME     J23 59
 '@T6G_MB_LIB.T6G(SCH_1):PAGE90_I352@PURE_QUANTA.SCONN288_DDR506112002KQ(CHIPS)':
 'VSS24': CDS_PINID='VSS24';
NODE_NAME     J23 61
 '@T6G_MB_LIB.T6G(SCH_1):PAGE90_I352@PURE_QUANTA.SCONN288_DDR506112002KQ(CHIPS)':
 'VSS25': CDS_PINID='VSS25';
NODE_NAME     J23 63
 '@T6G_MB_LIB.T6G(SCH_1):PAGE90_I352@PURE_QUANTA.SCONN288_DDR506112002KQ(CHIPS)':
 'VSS26': CDS_PINID='VSS26';
NODE_NAME     J23 65
 '@T6G_MB_LIB.T6G(SCH_1):PAGE90_I352@PURE_QUANTA.SCONN288_DDR506112002KQ(CHIPS)':
 'VSS27': CDS_PINID='VSS27';
NODE_NAME     J23 67
 '@T6G_MB_LIB.T6G(SCH_1):PAGE90_I352@PURE_QUANTA.SCONN288_DDR506112002KQ(CHIPS)':
 'VSS28': CDS_PINID='VSS28';
NODE_NAME     J23 69
 '@T6G_MB_LIB.T6G(SCH_1):PAGE90_I352@PURE_QUANTA.SCONN288_DDR506112002KQ(CHIPS)':
 'VSS29': CDS_PINID='VSS29';
NODE_NAME     J23 71
 '@T6G_MB_LIB.T6G(SCH_1):PAGE90_I352@PURE_QUANTA.SCONN288_DDR506112002KQ(CHIPS)':
 'VSS30': CDS_PINID='VSS30';
NODE_NAME     J23 73
 '@T6G_MB_LIB.T6G(SCH_1):PAGE90_I352@PURE_QUANTA.SCONN288_DDR506112002KQ(CHIPS)':
 'VSS31': CDS_PINID='VSS31';
NODE_NAME     J23 75
 '@T6G_MB_LIB.T6G(SCH_1):PAGE90_I352@PURE_QUANTA.SCONN288_DDR506112002KQ(CHIPS)':
 'VSS32': CDS_PINID='VSS32';
NODE_NAME     J23 77
 '@T6G_MB_LIB.T6G(SCH_1):PAGE90_I352@PURE_QUANTA.SCONN288_DDR506112002KQ(CHIPS)':
 'VSS33': CDS_PINID='VSS33';
NODE_NAME     J23 79
 '@T6G_MB_LIB.T6G(SCH_1):PAGE90_I352@PURE_QUANTA.SCONN288_DDR506112002KQ(CHIPS)':
 'VSS34': CDS_PINID='VSS34';
NODE_NAME     J23 81
 '@T6G_MB_LIB.T6G(SCH_1):PAGE90_I352@PURE_QUANTA.SCONN288_DDR506112002KQ(CHIPS)':
 'VSS35': CDS_PINID='VSS35';
NODE_NAME     J23 83
 '@T6G_MB_LIB.T6G(SCH_1):PAGE90_I352@PURE_QUANTA.SCONN288_DDR506112002KQ(CHIPS)':
 'VSS36': CDS_PINID='VSS36';
NODE_NAME     J23 85
 '@T6G_MB_LIB.T6G(SCH_1):PAGE90_I352@PURE_QUANTA.SCONN288_DDR506112002KQ(CHIPS)':
 'VSS37': CDS_PINID='VSS37';
NODE_NAME     J23 88
 '@T6G_MB_LIB.T6G(SCH_1):PAGE90_I352@PURE_QUANTA.SCONN288_DDR506112002KQ(CHIPS)':
 'VSS38': CDS_PINID='VSS38';
NODE_NAME     J23 90
 '@T6G_MB_LIB.T6G(SCH_1):PAGE90_I352@PURE_QUANTA.SCONN288_DDR506112002KQ(CHIPS)':
 'VSS39': CDS_PINID='VSS39';
NODE_NAME     J23 92
 '@T6G_MB_LIB.T6G(SCH_1):PAGE90_I352@PURE_QUANTA.SCONN288_DDR506112002KQ(CHIPS)':
 'VSS40': CDS_PINID='VSS40';
NODE_NAME     J23 95
 '@T6G_MB_LIB.T6G(SCH_1):PAGE90_I352@PURE_QUANTA.SCONN288_DDR506112002KQ(CHIPS)':
 'VSS41': CDS_PINID='VSS41';
NODE_NAME     J23 97
 '@T6G_MB_LIB.T6G(SCH_1):PAGE90_I352@PURE_QUANTA.SCONN288_DDR506112002KQ(CHIPS)':
 'VSS42': CDS_PINID='VSS42';
NODE_NAME     J23 99
 '@T6G_MB_LIB.T6G(SCH_1):PAGE90_I352@PURE_QUANTA.SCONN288_DDR506112002KQ(CHIPS)':
 'VSS43': CDS_PINID='VSS43';
NODE_NAME     J23 101
 '@T6G_MB_LIB.T6G(SCH_1):PAGE90_I352@PURE_QUANTA.SCONN288_DDR506112002KQ(CHIPS)':
 'VSS44': CDS_PINID='VSS44';
NODE_NAME     J23 103
 '@T6G_MB_LIB.T6G(SCH_1):PAGE90_I352@PURE_QUANTA.SCONN288_DDR506112002KQ(CHIPS)':
 'VSS45': CDS_PINID='VSS45';
NODE_NAME     J23 106
 '@T6G_MB_LIB.T6G(SCH_1):PAGE90_I352@PURE_QUANTA.SCONN288_DDR506112002KQ(CHIPS)':
 'VSS46': CDS_PINID='VSS46';
NODE_NAME     J23 108
 '@T6G_MB_LIB.T6G(SCH_1):PAGE90_I352@PURE_QUANTA.SCONN288_DDR506112002KQ(CHIPS)':
 'VSS47': CDS_PINID='VSS47';
NODE_NAME     J23 110
 '@T6G_MB_LIB.T6G(SCH_1):PAGE90_I352@PURE_QUANTA.SCONN288_DDR506112002KQ(CHIPS)':
 'VSS48': CDS_PINID='VSS48';
NODE_NAME     J23 112
 '@T6G_MB_LIB.T6G(SCH_1):PAGE90_I352@PURE_QUANTA.SCONN288_DDR506112002KQ(CHIPS)':
 'VSS49': CDS_PINID='VSS49';
NODE_NAME     J23 114
 '@T6G_MB_LIB.T6G(SCH_1):PAGE90_I352@PURE_QUANTA.SCONN288_DDR506112002KQ(CHIPS)':
 'VSS50': CDS_PINID='VSS50';
NODE_NAME     J23 117
 '@T6G_MB_LIB.T6G(SCH_1):PAGE90_I352@PURE_QUANTA.SCONN288_DDR506112002KQ(CHIPS)':
 'VSS51': CDS_PINID='VSS51';
NODE_NAME     J23 119
 '@T6G_MB_LIB.T6G(SCH_1):PAGE90_I352@PURE_QUANTA.SCONN288_DDR506112002KQ(CHIPS)':
 'VSS52': CDS_PINID='VSS52';
NODE_NAME     J23 121
 '@T6G_MB_LIB.T6G(SCH_1):PAGE90_I352@PURE_QUANTA.SCONN288_DDR506112002KQ(CHIPS)':
 'VSS53': CDS_PINID='VSS53';
NODE_NAME     J23 123
 '@T6G_MB_LIB.T6G(SCH_1):PAGE90_I352@PURE_QUANTA.SCONN288_DDR506112002KQ(CHIPS)':
 'VSS54': CDS_PINID='VSS54';
NODE_NAME     J23 125
 '@T6G_MB_LIB.T6G(SCH_1):PAGE90_I352@PURE_QUANTA.SCONN288_DDR506112002KQ(CHIPS)':
 'VSS55': CDS_PINID='VSS55';
NODE_NAME     J23 128
 '@T6G_MB_LIB.T6G(SCH_1):PAGE90_I352@PURE_QUANTA.SCONN288_DDR506112002KQ(CHIPS)':
 'VSS56': CDS_PINID='VSS56';
NODE_NAME     J23 130
 '@T6G_MB_LIB.T6G(SCH_1):PAGE90_I352@PURE_QUANTA.SCONN288_DDR506112002KQ(CHIPS)':
 'VSS57': CDS_PINID='VSS57';
NODE_NAME     J23 132
 '@T6G_MB_LIB.T6G(SCH_1):PAGE90_I352@PURE_QUANTA.SCONN288_DDR506112002KQ(CHIPS)':
 'VSS58': CDS_PINID='VSS58';
NODE_NAME     J23 134
 '@T6G_MB_LIB.T6G(SCH_1):PAGE90_I352@PURE_QUANTA.SCONN288_DDR506112002KQ(CHIPS)':
 'VSS59': CDS_PINID='VSS59';
NODE_NAME     J23 136
 '@T6G_MB_LIB.T6G(SCH_1):PAGE90_I352@PURE_QUANTA.SCONN288_DDR506112002KQ(CHIPS)':
 'VSS60': CDS_PINID='VSS60';
NODE_NAME     J23 139
 '@T6G_MB_LIB.T6G(SCH_1):PAGE90_I352@PURE_QUANTA.SCONN288_DDR506112002KQ(CHIPS)':
 'VSS61': CDS_PINID='VSS61';
NODE_NAME     J23 141
 '@T6G_MB_LIB.T6G(SCH_1):PAGE90_I352@PURE_QUANTA.SCONN288_DDR506112002KQ(CHIPS)':
 'VSS62': CDS_PINID='VSS62';
NODE_NAME     J23 143
 '@T6G_MB_LIB.T6G(SCH_1):PAGE90_I352@PURE_QUANTA.SCONN288_DDR506112002KQ(CHIPS)':
 'VSS63': CDS_PINID='VSS63';
NODE_NAME     J23 151
 '@T6G_MB_LIB.T6G(SCH_1):PAGE90_I352@PURE_QUANTA.SCONN288_DDR506112002KQ(CHIPS)':
 'VSS64': CDS_PINID='VSS64';
NODE_NAME     J23 153
 '@T6G_MB_LIB.T6G(SCH_1):PAGE90_I352@PURE_QUANTA.SCONN288_DDR506112002KQ(CHIPS)':
 'VSS65': CDS_PINID='VSS65';
NODE_NAME     J23 155
 '@T6G_MB_LIB.T6G(SCH_1):PAGE90_I352@PURE_QUANTA.SCONN288_DDR506112002KQ(CHIPS)':
 'VSS66': CDS_PINID='VSS66';
NODE_NAME     J23 158
 '@T6G_MB_LIB.T6G(SCH_1):PAGE90_I352@PURE_QUANTA.SCONN288_DDR506112002KQ(CHIPS)':
 'VSS67': CDS_PINID='VSS67';
NODE_NAME     J23 160
 '@T6G_MB_LIB.T6G(SCH_1):PAGE90_I352@PURE_QUANTA.SCONN288_DDR506112002KQ(CHIPS)':
 'VSS68': CDS_PINID='VSS68';
NODE_NAME     J23 162
 '@T6G_MB_LIB.T6G(SCH_1):PAGE90_I352@PURE_QUANTA.SCONN288_DDR506112002KQ(CHIPS)':
 'VSS69': CDS_PINID='VSS69';
NODE_NAME     J23 164
 '@T6G_MB_LIB.T6G(SCH_1):PAGE90_I352@PURE_QUANTA.SCONN288_DDR506112002KQ(CHIPS)':
 'VSS70': CDS_PINID='VSS70';
NODE_NAME     J23 166
 '@T6G_MB_LIB.T6G(SCH_1):PAGE90_I352@PURE_QUANTA.SCONN288_DDR506112002KQ(CHIPS)':
 'VSS71': CDS_PINID='VSS71';
NODE_NAME     J23 169
 '@T6G_MB_LIB.T6G(SCH_1):PAGE90_I352@PURE_QUANTA.SCONN288_DDR506112002KQ(CHIPS)':
 'VSS72': CDS_PINID='VSS72';
NODE_NAME     J23 171
 '@T6G_MB_LIB.T6G(SCH_1):PAGE90_I352@PURE_QUANTA.SCONN288_DDR506112002KQ(CHIPS)':
 'VSS73': CDS_PINID='VSS73';
NODE_NAME     J23 173
 '@T6G_MB_LIB.T6G(SCH_1):PAGE90_I352@PURE_QUANTA.SCONN288_DDR506112002KQ(CHIPS)':
 'VSS74': CDS_PINID='VSS74';
NODE_NAME     J23 175
 '@T6G_MB_LIB.T6G(SCH_1):PAGE90_I352@PURE_QUANTA.SCONN288_DDR506112002KQ(CHIPS)':
 'VSS75': CDS_PINID='VSS75';
NODE_NAME     J23 177
 '@T6G_MB_LIB.T6G(SCH_1):PAGE90_I352@PURE_QUANTA.SCONN288_DDR506112002KQ(CHIPS)':
 'VSS76': CDS_PINID='VSS76';
NODE_NAME     J23 180
 '@T6G_MB_LIB.T6G(SCH_1):PAGE90_I352@PURE_QUANTA.SCONN288_DDR506112002KQ(CHIPS)':
 'VSS77': CDS_PINID='VSS77';
NODE_NAME     J23 182
 '@T6G_MB_LIB.T6G(SCH_1):PAGE90_I352@PURE_QUANTA.SCONN288_DDR506112002KQ(CHIPS)':
 'VSS78': CDS_PINID='VSS78';
NODE_NAME     J23 184
 '@T6G_MB_LIB.T6G(SCH_1):PAGE90_I352@PURE_QUANTA.SCONN288_DDR506112002KQ(CHIPS)':
 'VSS79': CDS_PINID='VSS79';
NODE_NAME     J23 186
 '@T6G_MB_LIB.T6G(SCH_1):PAGE90_I352@PURE_QUANTA.SCONN288_DDR506112002KQ(CHIPS)':
 'VSS80': CDS_PINID='VSS80';
NODE_NAME     J23 188
 '@T6G_MB_LIB.T6G(SCH_1):PAGE90_I352@PURE_QUANTA.SCONN288_DDR506112002KQ(CHIPS)':
 'VSS81': CDS_PINID='VSS81';
NODE_NAME     J23 191
 '@T6G_MB_LIB.T6G(SCH_1):PAGE90_I352@PURE_QUANTA.SCONN288_DDR506112002KQ(CHIPS)':
 'VSS82': CDS_PINID='VSS82';
NODE_NAME     J23 193
 '@T6G_MB_LIB.T6G(SCH_1):PAGE90_I352@PURE_QUANTA.SCONN288_DDR506112002KQ(CHIPS)':
 'VSS83': CDS_PINID='VSS83';
NODE_NAME     J23 195
 '@T6G_MB_LIB.T6G(SCH_1):PAGE90_I352@PURE_QUANTA.SCONN288_DDR506112002KQ(CHIPS)':
 'VSS84': CDS_PINID='VSS84';
NODE_NAME     J23 197
 '@T6G_MB_LIB.T6G(SCH_1):PAGE90_I352@PURE_QUANTA.SCONN288_DDR506112002KQ(CHIPS)':
 'VSS85': CDS_PINID='VSS85';
NODE_NAME     J23 199
 '@T6G_MB_LIB.T6G(SCH_1):PAGE90_I352@PURE_QUANTA.SCONN288_DDR506112002KQ(CHIPS)':
 'VSS86': CDS_PINID='VSS86';
NODE_NAME     J23 202
 '@T6G_MB_LIB.T6G(SCH_1):PAGE90_I352@PURE_QUANTA.SCONN288_DDR506112002KQ(CHIPS)':
 'VSS87': CDS_PINID='VSS87';
NODE_NAME     J23 204
 '@T6G_MB_LIB.T6G(SCH_1):PAGE90_I352@PURE_QUANTA.SCONN288_DDR506112002KQ(CHIPS)':
 'VSS88': CDS_PINID='VSS88';
NODE_NAME     J23 206
 '@T6G_MB_LIB.T6G(SCH_1):PAGE90_I352@PURE_QUANTA.SCONN288_DDR506112002KQ(CHIPS)':
 'VSS89': CDS_PINID='VSS89';
NODE_NAME     J23 208
 '@T6G_MB_LIB.T6G(SCH_1):PAGE90_I352@PURE_QUANTA.SCONN288_DDR506112002KQ(CHIPS)':
 'VSS90': CDS_PINID='VSS90';
NODE_NAME     J23 210
 '@T6G_MB_LIB.T6G(SCH_1):PAGE90_I352@PURE_QUANTA.SCONN288_DDR506112002KQ(CHIPS)':
 'VSS91': CDS_PINID='VSS91';
NODE_NAME     J23 212
 '@T6G_MB_LIB.T6G(SCH_1):PAGE90_I352@PURE_QUANTA.SCONN288_DDR506112002KQ(CHIPS)':
 'VSS92': CDS_PINID='VSS92';
NODE_NAME     J23 214
 '@T6G_MB_LIB.T6G(SCH_1):PAGE90_I352@PURE_QUANTA.SCONN288_DDR506112002KQ(CHIPS)':
 'VSS93': CDS_PINID='VSS93';
NODE_NAME     J23 216
 '@T6G_MB_LIB.T6G(SCH_1):PAGE90_I352@PURE_QUANTA.SCONN288_DDR506112002KQ(CHIPS)':
 'VSS94': CDS_PINID='VSS94';
NODE_NAME     J23 219
 '@T6G_MB_LIB.T6G(SCH_1):PAGE90_I352@PURE_QUANTA.SCONN288_DDR506112002KQ(CHIPS)':
 'VSS95': CDS_PINID='VSS95';
NODE_NAME     J23 222
 '@T6G_MB_LIB.T6G(SCH_1):PAGE90_I352@PURE_QUANTA.SCONN288_DDR506112002KQ(CHIPS)':
 'VSS96': CDS_PINID='VSS96';
NODE_NAME     J23 224
 '@T6G_MB_LIB.T6G(SCH_1):PAGE90_I352@PURE_QUANTA.SCONN288_DDR506112002KQ(CHIPS)':
 'VSS97': CDS_PINID='VSS97';
NODE_NAME     J23 226
 '@T6G_MB_LIB.T6G(SCH_1):PAGE90_I352@PURE_QUANTA.SCONN288_DDR506112002KQ(CHIPS)':
 'VSS98': CDS_PINID='VSS98';
NODE_NAME     J23 228
 '@T6G_MB_LIB.T6G(SCH_1):PAGE90_I352@PURE_QUANTA.SCONN288_DDR506112002KQ(CHIPS)':
 'VSS99': CDS_PINID='VSS99';
NODE_NAME     J23 230
 '@T6G_MB_LIB.T6G(SCH_1):PAGE90_I352@PURE_QUANTA.SCONN288_DDR506112002KQ(CHIPS)':
 'VSS100': CDS_PINID='VSS100';
NODE_NAME     J23 233
 '@T6G_MB_LIB.T6G(SCH_1):PAGE90_I352@PURE_QUANTA.SCONN288_DDR506112002KQ(CHIPS)':
 'VSS101': CDS_PINID='VSS101';
NODE_NAME     J23 235
 '@T6G_MB_LIB.T6G(SCH_1):PAGE90_I352@PURE_QUANTA.SCONN288_DDR506112002KQ(CHIPS)':
 'VSS102': CDS_PINID='VSS102';
NODE_NAME     J23 237
 '@T6G_MB_LIB.T6G(SCH_1):PAGE90_I352@PURE_QUANTA.SCONN288_DDR506112002KQ(CHIPS)':
 'VSS103': CDS_PINID='VSS103';
NODE_NAME     J23 240
 '@T6G_MB_LIB.T6G(SCH_1):PAGE90_I352@PURE_QUANTA.SCONN288_DDR506112002KQ(CHIPS)':
 'VSS104': CDS_PINID='VSS104';
NODE_NAME     J23 242
 '@T6G_MB_LIB.T6G(SCH_1):PAGE90_I352@PURE_QUANTA.SCONN288_DDR506112002KQ(CHIPS)':
 'VSS105': CDS_PINID='VSS105';
NODE_NAME     J23 244
 '@T6G_MB_LIB.T6G(SCH_1):PAGE90_I352@PURE_QUANTA.SCONN288_DDR506112002KQ(CHIPS)':
 'VSS106': CDS_PINID='VSS106';
NODE_NAME     J23 246
 '@T6G_MB_LIB.T6G(SCH_1):PAGE90_I352@PURE_QUANTA.SCONN288_DDR506112002KQ(CHIPS)':
 'VSS107': CDS_PINID='VSS107';
NODE_NAME     J23 248
 '@T6G_MB_LIB.T6G(SCH_1):PAGE90_I352@PURE_QUANTA.SCONN288_DDR506112002KQ(CHIPS)':
 'VSS108': CDS_PINID='VSS108';
NODE_NAME     J23 251
 '@T6G_MB_LIB.T6G(SCH_1):PAGE90_I352@PURE_QUANTA.SCONN288_DDR506112002KQ(CHIPS)':
 'VSS109': CDS_PINID='VSS109';
NODE_NAME     J23 253
 '@T6G_MB_LIB.T6G(SCH_1):PAGE90_I352@PURE_QUANTA.SCONN288_DDR506112002KQ(CHIPS)':
 'VSS110': CDS_PINID='VSS110';
NODE_NAME     J23 255
 '@T6G_MB_LIB.T6G(SCH_1):PAGE90_I352@PURE_QUANTA.SCONN288_DDR506112002KQ(CHIPS)':
 'VSS111': CDS_PINID='VSS111';
NODE_NAME     J23 257
 '@T6G_MB_LIB.T6G(SCH_1):PAGE90_I352@PURE_QUANTA.SCONN288_DDR506112002KQ(CHIPS)':
 'VSS112': CDS_PINID='VSS112';
NODE_NAME     J23 259
 '@T6G_MB_LIB.T6G(SCH_1):PAGE90_I352@PURE_QUANTA.SCONN288_DDR506112002KQ(CHIPS)':
 'VSS113': CDS_PINID='VSS113';
NODE_NAME     J23 262
 '@T6G_MB_LIB.T6G(SCH_1):PAGE90_I352@PURE_QUANTA.SCONN288_DDR506112002KQ(CHIPS)':
 'VSS114': CDS_PINID='VSS114';
NODE_NAME     J23 264
 '@T6G_MB_LIB.T6G(SCH_1):PAGE90_I352@PURE_QUANTA.SCONN288_DDR506112002KQ(CHIPS)':
 'VSS115': CDS_PINID='VSS115';
NODE_NAME     J23 266
 '@T6G_MB_LIB.T6G(SCH_1):PAGE90_I352@PURE_QUANTA.SCONN288_DDR506112002KQ(CHIPS)':
 'VSS116': CDS_PINID='VSS116';
NODE_NAME     J23 268
 '@T6G_MB_LIB.T6G(SCH_1):PAGE90_I352@PURE_QUANTA.SCONN288_DDR506112002KQ(CHIPS)':
 'VSS117': CDS_PINID='VSS117';
NODE_NAME     J23 270
 '@T6G_MB_LIB.T6G(SCH_1):PAGE90_I352@PURE_QUANTA.SCONN288_DDR506112002KQ(CHIPS)':
 'VSS118': CDS_PINID='VSS118';
NODE_NAME     J23 273
 '@T6G_MB_LIB.T6G(SCH_1):PAGE90_I352@PURE_QUANTA.SCONN288_DDR506112002KQ(CHIPS)':
 'VSS119': CDS_PINID='VSS119';
NODE_NAME     J23 275
 '@T6G_MB_LIB.T6G(SCH_1):PAGE90_I352@PURE_QUANTA.SCONN288_DDR506112002KQ(CHIPS)':
 'VSS120': CDS_PINID='VSS120';
NODE_NAME     J23 277
 '@T6G_MB_LIB.T6G(SCH_1):PAGE90_I352@PURE_QUANTA.SCONN288_DDR506112002KQ(CHIPS)':
 'VSS121': CDS_PINID='VSS121';
NODE_NAME     J23 279
 '@T6G_MB_LIB.T6G(SCH_1):PAGE90_I352@PURE_QUANTA.SCONN288_DDR506112002KQ(CHIPS)':
 'VSS122': CDS_PINID='VSS122';
NODE_NAME     J23 281
 '@T6G_MB_LIB.T6G(SCH_1):PAGE90_I352@PURE_QUANTA.SCONN288_DDR506112002KQ(CHIPS)':
 'VSS123': CDS_PINID='VSS123';
NODE_NAME     J23 284
 '@T6G_MB_LIB.T6G(SCH_1):PAGE90_I352@PURE_QUANTA.SCONN288_DDR506112002KQ(CHIPS)':
 'VSS124': CDS_PINID='VSS124';
NODE_NAME     J23 286
 '@T6G_MB_LIB.T6G(SCH_1):PAGE90_I352@PURE_QUANTA.SCONN288_DDR506112002KQ(CHIPS)':
 'VSS125': CDS_PINID='VSS125';
NODE_NAME     J23 288
 '@T6G_MB_LIB.T6G(SCH_1):PAGE90_I352@PURE_QUANTA.SCONN288_DDR506112002KQ(CHIPS)':
 'VSS126': CDS_PINID='VSS126';
NODE_NAME     C108 2
 '@T6G_MB_LIB.T6G(SCH_1):PAGE90_I361@PURE_QUANTA.Q_CAP(CHIPS)':
 'B': CDS_PINID='B';
NODE_NAME     C154 2
 '@T6G_MB_LIB.T6G(SCH_1):PAGE90_I414@PURE_QUANTA.Q_CAP(CHIPS)':
 'B': CDS_PINID='B';
NODE_NAME     C155 2
 '@T6G_MB_LIB.T6G(SCH_1):PAGE90_I415@PURE_QUANTA.Q_CAP(CHIPS)':
 'B': CDS_PINID='B';
NODE_NAME     R35 2
 '@T6G_MB_LIB.T6G(SCH_1):PAGE91_I129@PURE_QUANTA.Q_RES(CHIPS)':
 'B':XNET_PINS='2',
 CDS_PINID='B';
NODE_NAME     J16 G1
 '@T6G_MB_LIB.T6G(SCH_1):PAGE91_I177@PURE_QUANTA.SCONN288_DDR506112002KQ(CHIPS)':
 'G1': CDS_PINID='G1';
NODE_NAME     J16 G2
 '@T6G_MB_LIB.T6G(SCH_1):PAGE91_I177@PURE_QUANTA.SCONN288_DDR506112002KQ(CHIPS)':
 'G2': CDS_PINID='G2';
NODE_NAME     J16 G3
 '@T6G_MB_LIB.T6G(SCH_1):PAGE91_I177@PURE_QUANTA.SCONN288_DDR506112002KQ(CHIPS)':
 'G3': CDS_PINID='G3';
NODE_NAME     J16 6
 '@T6G_MB_LIB.T6G(SCH_1):PAGE91_I177@PURE_QUANTA.SCONN288_DDR506112002KQ(CHIPS)':
 'VSS0': CDS_PINID='VSS0';
NODE_NAME     J16 8
 '@T6G_MB_LIB.T6G(SCH_1):PAGE91_I177@PURE_QUANTA.SCONN288_DDR506112002KQ(CHIPS)':
 'VSS1': CDS_PINID='VSS1';
NODE_NAME     J16 10
 '@T6G_MB_LIB.T6G(SCH_1):PAGE91_I177@PURE_QUANTA.SCONN288_DDR506112002KQ(CHIPS)':
 'VSS2': CDS_PINID='VSS2';
NODE_NAME     J16 13
 '@T6G_MB_LIB.T6G(SCH_1):PAGE91_I177@PURE_QUANTA.SCONN288_DDR506112002KQ(CHIPS)':
 'VSS3': CDS_PINID='VSS3';
NODE_NAME     J16 15
 '@T6G_MB_LIB.T6G(SCH_1):PAGE91_I177@PURE_QUANTA.SCONN288_DDR506112002KQ(CHIPS)':
 'VSS4': CDS_PINID='VSS4';
NODE_NAME     J16 17
 '@T6G_MB_LIB.T6G(SCH_1):PAGE91_I177@PURE_QUANTA.SCONN288_DDR506112002KQ(CHIPS)':
 'VSS5': CDS_PINID='VSS5';
NODE_NAME     J16 19
 '@T6G_MB_LIB.T6G(SCH_1):PAGE91_I177@PURE_QUANTA.SCONN288_DDR506112002KQ(CHIPS)':
 'VSS6': CDS_PINID='VSS6';
NODE_NAME     J16 21
 '@T6G_MB_LIB.T6G(SCH_1):PAGE91_I177@PURE_QUANTA.SCONN288_DDR506112002KQ(CHIPS)':
 'VSS7': CDS_PINID='VSS7';
NODE_NAME     J16 24
 '@T6G_MB_LIB.T6G(SCH_1):PAGE91_I177@PURE_QUANTA.SCONN288_DDR506112002KQ(CHIPS)':
 'VSS8': CDS_PINID='VSS8';
NODE_NAME     J16 26
 '@T6G_MB_LIB.T6G(SCH_1):PAGE91_I177@PURE_QUANTA.SCONN288_DDR506112002KQ(CHIPS)':
 'VSS9': CDS_PINID='VSS9';
NODE_NAME     J16 28
 '@T6G_MB_LIB.T6G(SCH_1):PAGE91_I177@PURE_QUANTA.SCONN288_DDR506112002KQ(CHIPS)':
 'VSS10': CDS_PINID='VSS10';
NODE_NAME     J16 30
 '@T6G_MB_LIB.T6G(SCH_1):PAGE91_I177@PURE_QUANTA.SCONN288_DDR506112002KQ(CHIPS)':
 'VSS11': CDS_PINID='VSS11';
NODE_NAME     J16 32
 '@T6G_MB_LIB.T6G(SCH_1):PAGE91_I177@PURE_QUANTA.SCONN288_DDR506112002KQ(CHIPS)':
 'VSS12': CDS_PINID='VSS12';
NODE_NAME     J16 35
 '@T6G_MB_LIB.T6G(SCH_1):PAGE91_I177@PURE_QUANTA.SCONN288_DDR506112002KQ(CHIPS)':
 'VSS13': CDS_PINID='VSS13';
NODE_NAME     J16 37
 '@T6G_MB_LIB.T6G(SCH_1):PAGE91_I177@PURE_QUANTA.SCONN288_DDR506112002KQ(CHIPS)':
 'VSS14': CDS_PINID='VSS14';
NODE_NAME     J16 39
 '@T6G_MB_LIB.T6G(SCH_1):PAGE91_I177@PURE_QUANTA.SCONN288_DDR506112002KQ(CHIPS)':
 'VSS15': CDS_PINID='VSS15';
NODE_NAME     J16 41
 '@T6G_MB_LIB.T6G(SCH_1):PAGE91_I177@PURE_QUANTA.SCONN288_DDR506112002KQ(CHIPS)':
 'VSS16': CDS_PINID='VSS16';
NODE_NAME     J16 43
 '@T6G_MB_LIB.T6G(SCH_1):PAGE91_I177@PURE_QUANTA.SCONN288_DDR506112002KQ(CHIPS)':
 'VSS17': CDS_PINID='VSS17';
NODE_NAME     J16 46
 '@T6G_MB_LIB.T6G(SCH_1):PAGE91_I177@PURE_QUANTA.SCONN288_DDR506112002KQ(CHIPS)':
 'VSS18': CDS_PINID='VSS18';
NODE_NAME     J16 48
 '@T6G_MB_LIB.T6G(SCH_1):PAGE91_I177@PURE_QUANTA.SCONN288_DDR506112002KQ(CHIPS)':
 'VSS19': CDS_PINID='VSS19';
NODE_NAME     J16 50
 '@T6G_MB_LIB.T6G(SCH_1):PAGE91_I177@PURE_QUANTA.SCONN288_DDR506112002KQ(CHIPS)':
 'VSS20': CDS_PINID='VSS20';
NODE_NAME     J16 52
 '@T6G_MB_LIB.T6G(SCH_1):PAGE91_I177@PURE_QUANTA.SCONN288_DDR506112002KQ(CHIPS)':
 'VSS21': CDS_PINID='VSS21';
NODE_NAME     J16 54
 '@T6G_MB_LIB.T6G(SCH_1):PAGE91_I177@PURE_QUANTA.SCONN288_DDR506112002KQ(CHIPS)':
 'VSS22': CDS_PINID='VSS22';
NODE_NAME     J16 57
 '@T6G_MB_LIB.T6G(SCH_1):PAGE91_I177@PURE_QUANTA.SCONN288_DDR506112002KQ(CHIPS)':
 'VSS23': CDS_PINID='VSS23';
NODE_NAME     J16 59
 '@T6G_MB_LIB.T6G(SCH_1):PAGE91_I177@PURE_QUANTA.SCONN288_DDR506112002KQ(CHIPS)':
 'VSS24': CDS_PINID='VSS24';
NODE_NAME     J16 61
 '@T6G_MB_LIB.T6G(SCH_1):PAGE91_I177@PURE_QUANTA.SCONN288_DDR506112002KQ(CHIPS)':
 'VSS25': CDS_PINID='VSS25';
NODE_NAME     J16 63
 '@T6G_MB_LIB.T6G(SCH_1):PAGE91_I177@PURE_QUANTA.SCONN288_DDR506112002KQ(CHIPS)':
 'VSS26': CDS_PINID='VSS26';
NODE_NAME     J16 65
 '@T6G_MB_LIB.T6G(SCH_1):PAGE91_I177@PURE_QUANTA.SCONN288_DDR506112002KQ(CHIPS)':
 'VSS27': CDS_PINID='VSS27';
NODE_NAME     J16 67
 '@T6G_MB_LIB.T6G(SCH_1):PAGE91_I177@PURE_QUANTA.SCONN288_DDR506112002KQ(CHIPS)':
 'VSS28': CDS_PINID='VSS28';
NODE_NAME     J16 69
 '@T6G_MB_LIB.T6G(SCH_1):PAGE91_I177@PURE_QUANTA.SCONN288_DDR506112002KQ(CHIPS)':
 'VSS29': CDS_PINID='VSS29';
NODE_NAME     J16 71
 '@T6G_MB_LIB.T6G(SCH_1):PAGE91_I177@PURE_QUANTA.SCONN288_DDR506112002KQ(CHIPS)':
 'VSS30': CDS_PINID='VSS30';
NODE_NAME     J16 73
 '@T6G_MB_LIB.T6G(SCH_1):PAGE91_I177@PURE_QUANTA.SCONN288_DDR506112002KQ(CHIPS)':
 'VSS31': CDS_PINID='VSS31';
NODE_NAME     J16 75
 '@T6G_MB_LIB.T6G(SCH_1):PAGE91_I177@PURE_QUANTA.SCONN288_DDR506112002KQ(CHIPS)':
 'VSS32': CDS_PINID='VSS32';
NODE_NAME     J16 77
 '@T6G_MB_LIB.T6G(SCH_1):PAGE91_I177@PURE_QUANTA.SCONN288_DDR506112002KQ(CHIPS)':
 'VSS33': CDS_PINID='VSS33';
NODE_NAME     J16 79
 '@T6G_MB_LIB.T6G(SCH_1):PAGE91_I177@PURE_QUANTA.SCONN288_DDR506112002KQ(CHIPS)':
 'VSS34': CDS_PINID='VSS34';
NODE_NAME     J16 81
 '@T6G_MB_LIB.T6G(SCH_1):PAGE91_I177@PURE_QUANTA.SCONN288_DDR506112002KQ(CHIPS)':
 'VSS35': CDS_PINID='VSS35';
NODE_NAME     J16 83
 '@T6G_MB_LIB.T6G(SCH_1):PAGE91_I177@PURE_QUANTA.SCONN288_DDR506112002KQ(CHIPS)':
 'VSS36': CDS_PINID='VSS36';
NODE_NAME     J16 85
 '@T6G_MB_LIB.T6G(SCH_1):PAGE91_I177@PURE_QUANTA.SCONN288_DDR506112002KQ(CHIPS)':
 'VSS37': CDS_PINID='VSS37';
NODE_NAME     J16 88
 '@T6G_MB_LIB.T6G(SCH_1):PAGE91_I177@PURE_QUANTA.SCONN288_DDR506112002KQ(CHIPS)':
 'VSS38': CDS_PINID='VSS38';
NODE_NAME     J16 90
 '@T6G_MB_LIB.T6G(SCH_1):PAGE91_I177@PURE_QUANTA.SCONN288_DDR506112002KQ(CHIPS)':
 'VSS39': CDS_PINID='VSS39';
NODE_NAME     J16 92
 '@T6G_MB_LIB.T6G(SCH_1):PAGE91_I177@PURE_QUANTA.SCONN288_DDR506112002KQ(CHIPS)':
 'VSS40': CDS_PINID='VSS40';
NODE_NAME     J16 95
 '@T6G_MB_LIB.T6G(SCH_1):PAGE91_I177@PURE_QUANTA.SCONN288_DDR506112002KQ(CHIPS)':
 'VSS41': CDS_PINID='VSS41';
NODE_NAME     J16 97
 '@T6G_MB_LIB.T6G(SCH_1):PAGE91_I177@PURE_QUANTA.SCONN288_DDR506112002KQ(CHIPS)':
 'VSS42': CDS_PINID='VSS42';
NODE_NAME     J16 99
 '@T6G_MB_LIB.T6G(SCH_1):PAGE91_I177@PURE_QUANTA.SCONN288_DDR506112002KQ(CHIPS)':
 'VSS43': CDS_PINID='VSS43';
NODE_NAME     J16 101
 '@T6G_MB_LIB.T6G(SCH_1):PAGE91_I177@PURE_QUANTA.SCONN288_DDR506112002KQ(CHIPS)':
 'VSS44': CDS_PINID='VSS44';
NODE_NAME     J16 103
 '@T6G_MB_LIB.T6G(SCH_1):PAGE91_I177@PURE_QUANTA.SCONN288_DDR506112002KQ(CHIPS)':
 'VSS45': CDS_PINID='VSS45';
NODE_NAME     J16 106
 '@T6G_MB_LIB.T6G(SCH_1):PAGE91_I177@PURE_QUANTA.SCONN288_DDR506112002KQ(CHIPS)':
 'VSS46': CDS_PINID='VSS46';
NODE_NAME     J16 108
 '@T6G_MB_LIB.T6G(SCH_1):PAGE91_I177@PURE_QUANTA.SCONN288_DDR506112002KQ(CHIPS)':
 'VSS47': CDS_PINID='VSS47';
NODE_NAME     J16 110
 '@T6G_MB_LIB.T6G(SCH_1):PAGE91_I177@PURE_QUANTA.SCONN288_DDR506112002KQ(CHIPS)':
 'VSS48': CDS_PINID='VSS48';
NODE_NAME     J16 112
 '@T6G_MB_LIB.T6G(SCH_1):PAGE91_I177@PURE_QUANTA.SCONN288_DDR506112002KQ(CHIPS)':
 'VSS49': CDS_PINID='VSS49';
NODE_NAME     J16 114
 '@T6G_MB_LIB.T6G(SCH_1):PAGE91_I177@PURE_QUANTA.SCONN288_DDR506112002KQ(CHIPS)':
 'VSS50': CDS_PINID='VSS50';
NODE_NAME     J16 117
 '@T6G_MB_LIB.T6G(SCH_1):PAGE91_I177@PURE_QUANTA.SCONN288_DDR506112002KQ(CHIPS)':
 'VSS51': CDS_PINID='VSS51';
NODE_NAME     J16 119
 '@T6G_MB_LIB.T6G(SCH_1):PAGE91_I177@PURE_QUANTA.SCONN288_DDR506112002KQ(CHIPS)':
 'VSS52': CDS_PINID='VSS52';
NODE_NAME     J16 121
 '@T6G_MB_LIB.T6G(SCH_1):PAGE91_I177@PURE_QUANTA.SCONN288_DDR506112002KQ(CHIPS)':
 'VSS53': CDS_PINID='VSS53';
NODE_NAME     J16 123
 '@T6G_MB_LIB.T6G(SCH_1):PAGE91_I177@PURE_QUANTA.SCONN288_DDR506112002KQ(CHIPS)':
 'VSS54': CDS_PINID='VSS54';
NODE_NAME     J16 125
 '@T6G_MB_LIB.T6G(SCH_1):PAGE91_I177@PURE_QUANTA.SCONN288_DDR506112002KQ(CHIPS)':
 'VSS55': CDS_PINID='VSS55';
NODE_NAME     J16 128
 '@T6G_MB_LIB.T6G(SCH_1):PAGE91_I177@PURE_QUANTA.SCONN288_DDR506112002KQ(CHIPS)':
 'VSS56': CDS_PINID='VSS56';
NODE_NAME     J16 130
 '@T6G_MB_LIB.T6G(SCH_1):PAGE91_I177@PURE_QUANTA.SCONN288_DDR506112002KQ(CHIPS)':
 'VSS57': CDS_PINID='VSS57';
NODE_NAME     J16 132
 '@T6G_MB_LIB.T6G(SCH_1):PAGE91_I177@PURE_QUANTA.SCONN288_DDR506112002KQ(CHIPS)':
 'VSS58': CDS_PINID='VSS58';
NODE_NAME     J16 134
 '@T6G_MB_LIB.T6G(SCH_1):PAGE91_I177@PURE_QUANTA.SCONN288_DDR506112002KQ(CHIPS)':
 'VSS59': CDS_PINID='VSS59';
NODE_NAME     J16 136
 '@T6G_MB_LIB.T6G(SCH_1):PAGE91_I177@PURE_QUANTA.SCONN288_DDR506112002KQ(CHIPS)':
 'VSS60': CDS_PINID='VSS60';
NODE_NAME     J16 139
 '@T6G_MB_LIB.T6G(SCH_1):PAGE91_I177@PURE_QUANTA.SCONN288_DDR506112002KQ(CHIPS)':
 'VSS61': CDS_PINID='VSS61';
NODE_NAME     J16 141
 '@T6G_MB_LIB.T6G(SCH_1):PAGE91_I177@PURE_QUANTA.SCONN288_DDR506112002KQ(CHIPS)':
 'VSS62': CDS_PINID='VSS62';
NODE_NAME     J16 143
 '@T6G_MB_LIB.T6G(SCH_1):PAGE91_I177@PURE_QUANTA.SCONN288_DDR506112002KQ(CHIPS)':
 'VSS63': CDS_PINID='VSS63';
NODE_NAME     J16 151
 '@T6G_MB_LIB.T6G(SCH_1):PAGE91_I177@PURE_QUANTA.SCONN288_DDR506112002KQ(CHIPS)':
 'VSS64': CDS_PINID='VSS64';
NODE_NAME     J16 153
 '@T6G_MB_LIB.T6G(SCH_1):PAGE91_I177@PURE_QUANTA.SCONN288_DDR506112002KQ(CHIPS)':
 'VSS65': CDS_PINID='VSS65';
NODE_NAME     J16 155
 '@T6G_MB_LIB.T6G(SCH_1):PAGE91_I177@PURE_QUANTA.SCONN288_DDR506112002KQ(CHIPS)':
 'VSS66': CDS_PINID='VSS66';
NODE_NAME     J16 158
 '@T6G_MB_LIB.T6G(SCH_1):PAGE91_I177@PURE_QUANTA.SCONN288_DDR506112002KQ(CHIPS)':
 'VSS67': CDS_PINID='VSS67';
NODE_NAME     J16 160
 '@T6G_MB_LIB.T6G(SCH_1):PAGE91_I177@PURE_QUANTA.SCONN288_DDR506112002KQ(CHIPS)':
 'VSS68': CDS_PINID='VSS68';
NODE_NAME     J16 162
 '@T6G_MB_LIB.T6G(SCH_1):PAGE91_I177@PURE_QUANTA.SCONN288_DDR506112002KQ(CHIPS)':
 'VSS69': CDS_PINID='VSS69';
NODE_NAME     J16 164
 '@T6G_MB_LIB.T6G(SCH_1):PAGE91_I177@PURE_QUANTA.SCONN288_DDR506112002KQ(CHIPS)':
 'VSS70': CDS_PINID='VSS70';
NODE_NAME     J16 166
 '@T6G_MB_LIB.T6G(SCH_1):PAGE91_I177@PURE_QUANTA.SCONN288_DDR506112002KQ(CHIPS)':
 'VSS71': CDS_PINID='VSS71';
NODE_NAME     J16 169
 '@T6G_MB_LIB.T6G(SCH_1):PAGE91_I177@PURE_QUANTA.SCONN288_DDR506112002KQ(CHIPS)':
 'VSS72': CDS_PINID='VSS72';
NODE_NAME     J16 171
 '@T6G_MB_LIB.T6G(SCH_1):PAGE91_I177@PURE_QUANTA.SCONN288_DDR506112002KQ(CHIPS)':
 'VSS73': CDS_PINID='VSS73';
NODE_NAME     J16 173
 '@T6G_MB_LIB.T6G(SCH_1):PAGE91_I177@PURE_QUANTA.SCONN288_DDR506112002KQ(CHIPS)':
 'VSS74': CDS_PINID='VSS74';
NODE_NAME     J16 175
 '@T6G_MB_LIB.T6G(SCH_1):PAGE91_I177@PURE_QUANTA.SCONN288_DDR506112002KQ(CHIPS)':
 'VSS75': CDS_PINID='VSS75';
NODE_NAME     J16 177
 '@T6G_MB_LIB.T6G(SCH_1):PAGE91_I177@PURE_QUANTA.SCONN288_DDR506112002KQ(CHIPS)':
 'VSS76': CDS_PINID='VSS76';
NODE_NAME     J16 180
 '@T6G_MB_LIB.T6G(SCH_1):PAGE91_I177@PURE_QUANTA.SCONN288_DDR506112002KQ(CHIPS)':
 'VSS77': CDS_PINID='VSS77';
NODE_NAME     J16 182
 '@T6G_MB_LIB.T6G(SCH_1):PAGE91_I177@PURE_QUANTA.SCONN288_DDR506112002KQ(CHIPS)':
 'VSS78': CDS_PINID='VSS78';
NODE_NAME     J16 184
 '@T6G_MB_LIB.T6G(SCH_1):PAGE91_I177@PURE_QUANTA.SCONN288_DDR506112002KQ(CHIPS)':
 'VSS79': CDS_PINID='VSS79';
NODE_NAME     J16 186
 '@T6G_MB_LIB.T6G(SCH_1):PAGE91_I177@PURE_QUANTA.SCONN288_DDR506112002KQ(CHIPS)':
 'VSS80': CDS_PINID='VSS80';
NODE_NAME     J16 188
 '@T6G_MB_LIB.T6G(SCH_1):PAGE91_I177@PURE_QUANTA.SCONN288_DDR506112002KQ(CHIPS)':
 'VSS81': CDS_PINID='VSS81';
NODE_NAME     J16 191
 '@T6G_MB_LIB.T6G(SCH_1):PAGE91_I177@PURE_QUANTA.SCONN288_DDR506112002KQ(CHIPS)':
 'VSS82': CDS_PINID='VSS82';
NODE_NAME     J16 193
 '@T6G_MB_LIB.T6G(SCH_1):PAGE91_I177@PURE_QUANTA.SCONN288_DDR506112002KQ(CHIPS)':
 'VSS83': CDS_PINID='VSS83';
NODE_NAME     J16 195
 '@T6G_MB_LIB.T6G(SCH_1):PAGE91_I177@PURE_QUANTA.SCONN288_DDR506112002KQ(CHIPS)':
 'VSS84': CDS_PINID='VSS84';
NODE_NAME     J16 197
 '@T6G_MB_LIB.T6G(SCH_1):PAGE91_I177@PURE_QUANTA.SCONN288_DDR506112002KQ(CHIPS)':
 'VSS85': CDS_PINID='VSS85';
NODE_NAME     J16 199
 '@T6G_MB_LIB.T6G(SCH_1):PAGE91_I177@PURE_QUANTA.SCONN288_DDR506112002KQ(CHIPS)':
 'VSS86': CDS_PINID='VSS86';
NODE_NAME     J16 202
 '@T6G_MB_LIB.T6G(SCH_1):PAGE91_I177@PURE_QUANTA.SCONN288_DDR506112002KQ(CHIPS)':
 'VSS87': CDS_PINID='VSS87';
NODE_NAME     J16 204
 '@T6G_MB_LIB.T6G(SCH_1):PAGE91_I177@PURE_QUANTA.SCONN288_DDR506112002KQ(CHIPS)':
 'VSS88': CDS_PINID='VSS88';
NODE_NAME     J16 206
 '@T6G_MB_LIB.T6G(SCH_1):PAGE91_I177@PURE_QUANTA.SCONN288_DDR506112002KQ(CHIPS)':
 'VSS89': CDS_PINID='VSS89';
NODE_NAME     J16 208
 '@T6G_MB_LIB.T6G(SCH_1):PAGE91_I177@PURE_QUANTA.SCONN288_DDR506112002KQ(CHIPS)':
 'VSS90': CDS_PINID='VSS90';
NODE_NAME     J16 210
 '@T6G_MB_LIB.T6G(SCH_1):PAGE91_I177@PURE_QUANTA.SCONN288_DDR506112002KQ(CHIPS)':
 'VSS91': CDS_PINID='VSS91';
NODE_NAME     J16 212
 '@T6G_MB_LIB.T6G(SCH_1):PAGE91_I177@PURE_QUANTA.SCONN288_DDR506112002KQ(CHIPS)':
 'VSS92': CDS_PINID='VSS92';
NODE_NAME     J16 214
 '@T6G_MB_LIB.T6G(SCH_1):PAGE91_I177@PURE_QUANTA.SCONN288_DDR506112002KQ(CHIPS)':
 'VSS93': CDS_PINID='VSS93';
NODE_NAME     J16 216
 '@T6G_MB_LIB.T6G(SCH_1):PAGE91_I177@PURE_QUANTA.SCONN288_DDR506112002KQ(CHIPS)':
 'VSS94': CDS_PINID='VSS94';
NODE_NAME     J16 219
 '@T6G_MB_LIB.T6G(SCH_1):PAGE91_I177@PURE_QUANTA.SCONN288_DDR506112002KQ(CHIPS)':
 'VSS95': CDS_PINID='VSS95';
NODE_NAME     J16 222
 '@T6G_MB_LIB.T6G(SCH_1):PAGE91_I177@PURE_QUANTA.SCONN288_DDR506112002KQ(CHIPS)':
 'VSS96': CDS_PINID='VSS96';
NODE_NAME     J16 224
 '@T6G_MB_LIB.T6G(SCH_1):PAGE91_I177@PURE_QUANTA.SCONN288_DDR506112002KQ(CHIPS)':
 'VSS97': CDS_PINID='VSS97';
NODE_NAME     J16 226
 '@T6G_MB_LIB.T6G(SCH_1):PAGE91_I177@PURE_QUANTA.SCONN288_DDR506112002KQ(CHIPS)':
 'VSS98': CDS_PINID='VSS98';
NODE_NAME     J16 228
 '@T6G_MB_LIB.T6G(SCH_1):PAGE91_I177@PURE_QUANTA.SCONN288_DDR506112002KQ(CHIPS)':
 'VSS99': CDS_PINID='VSS99';
NODE_NAME     J16 230
 '@T6G_MB_LIB.T6G(SCH_1):PAGE91_I177@PURE_QUANTA.SCONN288_DDR506112002KQ(CHIPS)':
 'VSS100': CDS_PINID='VSS100';
NODE_NAME     J16 233
 '@T6G_MB_LIB.T6G(SCH_1):PAGE91_I177@PURE_QUANTA.SCONN288_DDR506112002KQ(CHIPS)':
 'VSS101': CDS_PINID='VSS101';
NODE_NAME     J16 235
 '@T6G_MB_LIB.T6G(SCH_1):PAGE91_I177@PURE_QUANTA.SCONN288_DDR506112002KQ(CHIPS)':
 'VSS102': CDS_PINID='VSS102';
NODE_NAME     J16 237
 '@T6G_MB_LIB.T6G(SCH_1):PAGE91_I177@PURE_QUANTA.SCONN288_DDR506112002KQ(CHIPS)':
 'VSS103': CDS_PINID='VSS103';
NODE_NAME     J16 240
 '@T6G_MB_LIB.T6G(SCH_1):PAGE91_I177@PURE_QUANTA.SCONN288_DDR506112002KQ(CHIPS)':
 'VSS104': CDS_PINID='VSS104';
NODE_NAME     J16 242
 '@T6G_MB_LIB.T6G(SCH_1):PAGE91_I177@PURE_QUANTA.SCONN288_DDR506112002KQ(CHIPS)':
 'VSS105': CDS_PINID='VSS105';
NODE_NAME     J16 244
 '@T6G_MB_LIB.T6G(SCH_1):PAGE91_I177@PURE_QUANTA.SCONN288_DDR506112002KQ(CHIPS)':
 'VSS106': CDS_PINID='VSS106';
NODE_NAME     J16 246
 '@T6G_MB_LIB.T6G(SCH_1):PAGE91_I177@PURE_QUANTA.SCONN288_DDR506112002KQ(CHIPS)':
 'VSS107': CDS_PINID='VSS107';
NODE_NAME     J16 248
 '@T6G_MB_LIB.T6G(SCH_1):PAGE91_I177@PURE_QUANTA.SCONN288_DDR506112002KQ(CHIPS)':
 'VSS108': CDS_PINID='VSS108';
NODE_NAME     J16 251
 '@T6G_MB_LIB.T6G(SCH_1):PAGE91_I177@PURE_QUANTA.SCONN288_DDR506112002KQ(CHIPS)':
 'VSS109': CDS_PINID='VSS109';
NODE_NAME     J16 253
 '@T6G_MB_LIB.T6G(SCH_1):PAGE91_I177@PURE_QUANTA.SCONN288_DDR506112002KQ(CHIPS)':
 'VSS110': CDS_PINID='VSS110';
NODE_NAME     J16 255
 '@T6G_MB_LIB.T6G(SCH_1):PAGE91_I177@PURE_QUANTA.SCONN288_DDR506112002KQ(CHIPS)':
 'VSS111': CDS_PINID='VSS111';
NODE_NAME     J16 257
 '@T6G_MB_LIB.T6G(SCH_1):PAGE91_I177@PURE_QUANTA.SCONN288_DDR506112002KQ(CHIPS)':
 'VSS112': CDS_PINID='VSS112';
NODE_NAME     J16 259
 '@T6G_MB_LIB.T6G(SCH_1):PAGE91_I177@PURE_QUANTA.SCONN288_DDR506112002KQ(CHIPS)':
 'VSS113': CDS_PINID='VSS113';
NODE_NAME     J16 262
 '@T6G_MB_LIB.T6G(SCH_1):PAGE91_I177@PURE_QUANTA.SCONN288_DDR506112002KQ(CHIPS)':
 'VSS114': CDS_PINID='VSS114';
NODE_NAME     J16 264
 '@T6G_MB_LIB.T6G(SCH_1):PAGE91_I177@PURE_QUANTA.SCONN288_DDR506112002KQ(CHIPS)':
 'VSS115': CDS_PINID='VSS115';
NODE_NAME     J16 266
 '@T6G_MB_LIB.T6G(SCH_1):PAGE91_I177@PURE_QUANTA.SCONN288_DDR506112002KQ(CHIPS)':
 'VSS116': CDS_PINID='VSS116';
NODE_NAME     J16 268
 '@T6G_MB_LIB.T6G(SCH_1):PAGE91_I177@PURE_QUANTA.SCONN288_DDR506112002KQ(CHIPS)':
 'VSS117': CDS_PINID='VSS117';
NODE_NAME     J16 270
 '@T6G_MB_LIB.T6G(SCH_1):PAGE91_I177@PURE_QUANTA.SCONN288_DDR506112002KQ(CHIPS)':
 'VSS118': CDS_PINID='VSS118';
NODE_NAME     J16 273
 '@T6G_MB_LIB.T6G(SCH_1):PAGE91_I177@PURE_QUANTA.SCONN288_DDR506112002KQ(CHIPS)':
 'VSS119': CDS_PINID='VSS119';
NODE_NAME     J16 275
 '@T6G_MB_LIB.T6G(SCH_1):PAGE91_I177@PURE_QUANTA.SCONN288_DDR506112002KQ(CHIPS)':
 'VSS120': CDS_PINID='VSS120';
NODE_NAME     J16 277
 '@T6G_MB_LIB.T6G(SCH_1):PAGE91_I177@PURE_QUANTA.SCONN288_DDR506112002KQ(CHIPS)':
 'VSS121': CDS_PINID='VSS121';
NODE_NAME     J16 279
 '@T6G_MB_LIB.T6G(SCH_1):PAGE91_I177@PURE_QUANTA.SCONN288_DDR506112002KQ(CHIPS)':
 'VSS122': CDS_PINID='VSS122';
NODE_NAME     J16 281
 '@T6G_MB_LIB.T6G(SCH_1):PAGE91_I177@PURE_QUANTA.SCONN288_DDR506112002KQ(CHIPS)':
 'VSS123': CDS_PINID='VSS123';
NODE_NAME     J16 284
 '@T6G_MB_LIB.T6G(SCH_1):PAGE91_I177@PURE_QUANTA.SCONN288_DDR506112002KQ(CHIPS)':
 'VSS124': CDS_PINID='VSS124';
NODE_NAME     J16 286
 '@T6G_MB_LIB.T6G(SCH_1):PAGE91_I177@PURE_QUANTA.SCONN288_DDR506112002KQ(CHIPS)':
 'VSS125': CDS_PINID='VSS125';
NODE_NAME     J16 288
 '@T6G_MB_LIB.T6G(SCH_1):PAGE91_I177@PURE_QUANTA.SCONN288_DDR506112002KQ(CHIPS)':
 'VSS126': CDS_PINID='VSS126';
NODE_NAME     C112 2
 '@T6G_MB_LIB.T6G(SCH_1):PAGE91_I183@PURE_QUANTA.Q_CAP(CHIPS)':
 'B': CDS_PINID='B';
NODE_NAME     C157 2
 '@T6G_MB_LIB.T6G(SCH_1):PAGE91_I238@PURE_QUANTA.Q_CAP(CHIPS)':
 'B': CDS_PINID='B';
NODE_NAME     C158 2
 '@T6G_MB_LIB.T6G(SCH_1):PAGE91_I239@PURE_QUANTA.Q_CAP(CHIPS)':
 'B': CDS_PINID='B';
NODE_NAME     R765 2
 '@T6G_MB_LIB.T6G(SCH_1):PAGE92_I129@PURE_QUANTA.Q_RES(CHIPS)':
 'B': CDS_PINID='B';
NODE_NAME     J69 G1
 '@T6G_MB_LIB.T6G(SCH_1):PAGE92_I177@PURE_QUANTA.SCONN288_DDR506112002KQ(CHIPS)':
 'G1': CDS_PINID='G1';
NODE_NAME     J69 G2
 '@T6G_MB_LIB.T6G(SCH_1):PAGE92_I177@PURE_QUANTA.SCONN288_DDR506112002KQ(CHIPS)':
 'G2': CDS_PINID='G2';
NODE_NAME     J69 G3
 '@T6G_MB_LIB.T6G(SCH_1):PAGE92_I177@PURE_QUANTA.SCONN288_DDR506112002KQ(CHIPS)':
 'G3': CDS_PINID='G3';
NODE_NAME     J69 6
 '@T6G_MB_LIB.T6G(SCH_1):PAGE92_I177@PURE_QUANTA.SCONN288_DDR506112002KQ(CHIPS)':
 'VSS0': CDS_PINID='VSS0';
NODE_NAME     J69 8
 '@T6G_MB_LIB.T6G(SCH_1):PAGE92_I177@PURE_QUANTA.SCONN288_DDR506112002KQ(CHIPS)':
 'VSS1': CDS_PINID='VSS1';
NODE_NAME     J69 10
 '@T6G_MB_LIB.T6G(SCH_1):PAGE92_I177@PURE_QUANTA.SCONN288_DDR506112002KQ(CHIPS)':
 'VSS2': CDS_PINID='VSS2';
NODE_NAME     J69 13
 '@T6G_MB_LIB.T6G(SCH_1):PAGE92_I177@PURE_QUANTA.SCONN288_DDR506112002KQ(CHIPS)':
 'VSS3': CDS_PINID='VSS3';
NODE_NAME     J69 15
 '@T6G_MB_LIB.T6G(SCH_1):PAGE92_I177@PURE_QUANTA.SCONN288_DDR506112002KQ(CHIPS)':
 'VSS4': CDS_PINID='VSS4';
NODE_NAME     J69 17
 '@T6G_MB_LIB.T6G(SCH_1):PAGE92_I177@PURE_QUANTA.SCONN288_DDR506112002KQ(CHIPS)':
 'VSS5': CDS_PINID='VSS5';
NODE_NAME     J69 19
 '@T6G_MB_LIB.T6G(SCH_1):PAGE92_I177@PURE_QUANTA.SCONN288_DDR506112002KQ(CHIPS)':
 'VSS6': CDS_PINID='VSS6';
NODE_NAME     J69 21
 '@T6G_MB_LIB.T6G(SCH_1):PAGE92_I177@PURE_QUANTA.SCONN288_DDR506112002KQ(CHIPS)':
 'VSS7': CDS_PINID='VSS7';
NODE_NAME     J69 24
 '@T6G_MB_LIB.T6G(SCH_1):PAGE92_I177@PURE_QUANTA.SCONN288_DDR506112002KQ(CHIPS)':
 'VSS8': CDS_PINID='VSS8';
NODE_NAME     J69 26
 '@T6G_MB_LIB.T6G(SCH_1):PAGE92_I177@PURE_QUANTA.SCONN288_DDR506112002KQ(CHIPS)':
 'VSS9': CDS_PINID='VSS9';
NODE_NAME     J69 28
 '@T6G_MB_LIB.T6G(SCH_1):PAGE92_I177@PURE_QUANTA.SCONN288_DDR506112002KQ(CHIPS)':
 'VSS10': CDS_PINID='VSS10';
NODE_NAME     J69 30
 '@T6G_MB_LIB.T6G(SCH_1):PAGE92_I177@PURE_QUANTA.SCONN288_DDR506112002KQ(CHIPS)':
 'VSS11': CDS_PINID='VSS11';
NODE_NAME     J69 32
 '@T6G_MB_LIB.T6G(SCH_1):PAGE92_I177@PURE_QUANTA.SCONN288_DDR506112002KQ(CHIPS)':
 'VSS12': CDS_PINID='VSS12';
NODE_NAME     J69 35
 '@T6G_MB_LIB.T6G(SCH_1):PAGE92_I177@PURE_QUANTA.SCONN288_DDR506112002KQ(CHIPS)':
 'VSS13': CDS_PINID='VSS13';
NODE_NAME     J69 37
 '@T6G_MB_LIB.T6G(SCH_1):PAGE92_I177@PURE_QUANTA.SCONN288_DDR506112002KQ(CHIPS)':
 'VSS14': CDS_PINID='VSS14';
NODE_NAME     J69 39
 '@T6G_MB_LIB.T6G(SCH_1):PAGE92_I177@PURE_QUANTA.SCONN288_DDR506112002KQ(CHIPS)':
 'VSS15': CDS_PINID='VSS15';
NODE_NAME     J69 41
 '@T6G_MB_LIB.T6G(SCH_1):PAGE92_I177@PURE_QUANTA.SCONN288_DDR506112002KQ(CHIPS)':
 'VSS16': CDS_PINID='VSS16';
NODE_NAME     J69 43
 '@T6G_MB_LIB.T6G(SCH_1):PAGE92_I177@PURE_QUANTA.SCONN288_DDR506112002KQ(CHIPS)':
 'VSS17': CDS_PINID='VSS17';
NODE_NAME     J69 46
 '@T6G_MB_LIB.T6G(SCH_1):PAGE92_I177@PURE_QUANTA.SCONN288_DDR506112002KQ(CHIPS)':
 'VSS18': CDS_PINID='VSS18';
NODE_NAME     J69 48
 '@T6G_MB_LIB.T6G(SCH_1):PAGE92_I177@PURE_QUANTA.SCONN288_DDR506112002KQ(CHIPS)':
 'VSS19': CDS_PINID='VSS19';
NODE_NAME     J69 50
 '@T6G_MB_LIB.T6G(SCH_1):PAGE92_I177@PURE_QUANTA.SCONN288_DDR506112002KQ(CHIPS)':
 'VSS20': CDS_PINID='VSS20';
NODE_NAME     J69 52
 '@T6G_MB_LIB.T6G(SCH_1):PAGE92_I177@PURE_QUANTA.SCONN288_DDR506112002KQ(CHIPS)':
 'VSS21': CDS_PINID='VSS21';
NODE_NAME     J69 54
 '@T6G_MB_LIB.T6G(SCH_1):PAGE92_I177@PURE_QUANTA.SCONN288_DDR506112002KQ(CHIPS)':
 'VSS22': CDS_PINID='VSS22';
NODE_NAME     J69 57
 '@T6G_MB_LIB.T6G(SCH_1):PAGE92_I177@PURE_QUANTA.SCONN288_DDR506112002KQ(CHIPS)':
 'VSS23': CDS_PINID='VSS23';
NODE_NAME     J69 59
 '@T6G_MB_LIB.T6G(SCH_1):PAGE92_I177@PURE_QUANTA.SCONN288_DDR506112002KQ(CHIPS)':
 'VSS24': CDS_PINID='VSS24';
NODE_NAME     J69 61
 '@T6G_MB_LIB.T6G(SCH_1):PAGE92_I177@PURE_QUANTA.SCONN288_DDR506112002KQ(CHIPS)':
 'VSS25': CDS_PINID='VSS25';
NODE_NAME     J69 63
 '@T6G_MB_LIB.T6G(SCH_1):PAGE92_I177@PURE_QUANTA.SCONN288_DDR506112002KQ(CHIPS)':
 'VSS26': CDS_PINID='VSS26';
NODE_NAME     J69 65
 '@T6G_MB_LIB.T6G(SCH_1):PAGE92_I177@PURE_QUANTA.SCONN288_DDR506112002KQ(CHIPS)':
 'VSS27': CDS_PINID='VSS27';
NODE_NAME     J69 67
 '@T6G_MB_LIB.T6G(SCH_1):PAGE92_I177@PURE_QUANTA.SCONN288_DDR506112002KQ(CHIPS)':
 'VSS28': CDS_PINID='VSS28';
NODE_NAME     J69 69
 '@T6G_MB_LIB.T6G(SCH_1):PAGE92_I177@PURE_QUANTA.SCONN288_DDR506112002KQ(CHIPS)':
 'VSS29': CDS_PINID='VSS29';
NODE_NAME     J69 71
 '@T6G_MB_LIB.T6G(SCH_1):PAGE92_I177@PURE_QUANTA.SCONN288_DDR506112002KQ(CHIPS)':
 'VSS30': CDS_PINID='VSS30';
NODE_NAME     J69 73
 '@T6G_MB_LIB.T6G(SCH_1):PAGE92_I177@PURE_QUANTA.SCONN288_DDR506112002KQ(CHIPS)':
 'VSS31': CDS_PINID='VSS31';
NODE_NAME     J69 75
 '@T6G_MB_LIB.T6G(SCH_1):PAGE92_I177@PURE_QUANTA.SCONN288_DDR506112002KQ(CHIPS)':
 'VSS32': CDS_PINID='VSS32';
NODE_NAME     J69 77
 '@T6G_MB_LIB.T6G(SCH_1):PAGE92_I177@PURE_QUANTA.SCONN288_DDR506112002KQ(CHIPS)':
 'VSS33': CDS_PINID='VSS33';
NODE_NAME     J69 79
 '@T6G_MB_LIB.T6G(SCH_1):PAGE92_I177@PURE_QUANTA.SCONN288_DDR506112002KQ(CHIPS)':
 'VSS34': CDS_PINID='VSS34';
NODE_NAME     J69 81
 '@T6G_MB_LIB.T6G(SCH_1):PAGE92_I177@PURE_QUANTA.SCONN288_DDR506112002KQ(CHIPS)':
 'VSS35': CDS_PINID='VSS35';
NODE_NAME     J69 83
 '@T6G_MB_LIB.T6G(SCH_1):PAGE92_I177@PURE_QUANTA.SCONN288_DDR506112002KQ(CHIPS)':
 'VSS36': CDS_PINID='VSS36';
NODE_NAME     J69 85
 '@T6G_MB_LIB.T6G(SCH_1):PAGE92_I177@PURE_QUANTA.SCONN288_DDR506112002KQ(CHIPS)':
 'VSS37': CDS_PINID='VSS37';
NODE_NAME     J69 88
 '@T6G_MB_LIB.T6G(SCH_1):PAGE92_I177@PURE_QUANTA.SCONN288_DDR506112002KQ(CHIPS)':
 'VSS38': CDS_PINID='VSS38';
NODE_NAME     J69 90
 '@T6G_MB_LIB.T6G(SCH_1):PAGE92_I177@PURE_QUANTA.SCONN288_DDR506112002KQ(CHIPS)':
 'VSS39': CDS_PINID='VSS39';
NODE_NAME     J69 92
 '@T6G_MB_LIB.T6G(SCH_1):PAGE92_I177@PURE_QUANTA.SCONN288_DDR506112002KQ(CHIPS)':
 'VSS40': CDS_PINID='VSS40';
NODE_NAME     J69 95
 '@T6G_MB_LIB.T6G(SCH_1):PAGE92_I177@PURE_QUANTA.SCONN288_DDR506112002KQ(CHIPS)':
 'VSS41': CDS_PINID='VSS41';
NODE_NAME     J69 97
 '@T6G_MB_LIB.T6G(SCH_1):PAGE92_I177@PURE_QUANTA.SCONN288_DDR506112002KQ(CHIPS)':
 'VSS42': CDS_PINID='VSS42';
NODE_NAME     J69 99
 '@T6G_MB_LIB.T6G(SCH_1):PAGE92_I177@PURE_QUANTA.SCONN288_DDR506112002KQ(CHIPS)':
 'VSS43': CDS_PINID='VSS43';
NODE_NAME     J69 101
 '@T6G_MB_LIB.T6G(SCH_1):PAGE92_I177@PURE_QUANTA.SCONN288_DDR506112002KQ(CHIPS)':
 'VSS44': CDS_PINID='VSS44';
NODE_NAME     J69 103
 '@T6G_MB_LIB.T6G(SCH_1):PAGE92_I177@PURE_QUANTA.SCONN288_DDR506112002KQ(CHIPS)':
 'VSS45': CDS_PINID='VSS45';
NODE_NAME     J69 106
 '@T6G_MB_LIB.T6G(SCH_1):PAGE92_I177@PURE_QUANTA.SCONN288_DDR506112002KQ(CHIPS)':
 'VSS46': CDS_PINID='VSS46';
NODE_NAME     J69 108
 '@T6G_MB_LIB.T6G(SCH_1):PAGE92_I177@PURE_QUANTA.SCONN288_DDR506112002KQ(CHIPS)':
 'VSS47': CDS_PINID='VSS47';
NODE_NAME     J69 110
 '@T6G_MB_LIB.T6G(SCH_1):PAGE92_I177@PURE_QUANTA.SCONN288_DDR506112002KQ(CHIPS)':
 'VSS48': CDS_PINID='VSS48';
NODE_NAME     J69 112
 '@T6G_MB_LIB.T6G(SCH_1):PAGE92_I177@PURE_QUANTA.SCONN288_DDR506112002KQ(CHIPS)':
 'VSS49': CDS_PINID='VSS49';
NODE_NAME     J69 114
 '@T6G_MB_LIB.T6G(SCH_1):PAGE92_I177@PURE_QUANTA.SCONN288_DDR506112002KQ(CHIPS)':
 'VSS50': CDS_PINID='VSS50';
NODE_NAME     J69 117
 '@T6G_MB_LIB.T6G(SCH_1):PAGE92_I177@PURE_QUANTA.SCONN288_DDR506112002KQ(CHIPS)':
 'VSS51': CDS_PINID='VSS51';
NODE_NAME     J69 119
 '@T6G_MB_LIB.T6G(SCH_1):PAGE92_I177@PURE_QUANTA.SCONN288_DDR506112002KQ(CHIPS)':
 'VSS52': CDS_PINID='VSS52';
NODE_NAME     J69 121
 '@T6G_MB_LIB.T6G(SCH_1):PAGE92_I177@PURE_QUANTA.SCONN288_DDR506112002KQ(CHIPS)':
 'VSS53': CDS_PINID='VSS53';
NODE_NAME     J69 123
 '@T6G_MB_LIB.T6G(SCH_1):PAGE92_I177@PURE_QUANTA.SCONN288_DDR506112002KQ(CHIPS)':
 'VSS54': CDS_PINID='VSS54';
NODE_NAME     J69 125
 '@T6G_MB_LIB.T6G(SCH_1):PAGE92_I177@PURE_QUANTA.SCONN288_DDR506112002KQ(CHIPS)':
 'VSS55': CDS_PINID='VSS55';
NODE_NAME     J69 128
 '@T6G_MB_LIB.T6G(SCH_1):PAGE92_I177@PURE_QUANTA.SCONN288_DDR506112002KQ(CHIPS)':
 'VSS56': CDS_PINID='VSS56';
NODE_NAME     J69 130
 '@T6G_MB_LIB.T6G(SCH_1):PAGE92_I177@PURE_QUANTA.SCONN288_DDR506112002KQ(CHIPS)':
 'VSS57': CDS_PINID='VSS57';
NODE_NAME     J69 132
 '@T6G_MB_LIB.T6G(SCH_1):PAGE92_I177@PURE_QUANTA.SCONN288_DDR506112002KQ(CHIPS)':
 'VSS58': CDS_PINID='VSS58';
NODE_NAME     J69 134
 '@T6G_MB_LIB.T6G(SCH_1):PAGE92_I177@PURE_QUANTA.SCONN288_DDR506112002KQ(CHIPS)':
 'VSS59': CDS_PINID='VSS59';
NODE_NAME     J69 136
 '@T6G_MB_LIB.T6G(SCH_1):PAGE92_I177@PURE_QUANTA.SCONN288_DDR506112002KQ(CHIPS)':
 'VSS60': CDS_PINID='VSS60';
NODE_NAME     J69 139
 '@T6G_MB_LIB.T6G(SCH_1):PAGE92_I177@PURE_QUANTA.SCONN288_DDR506112002KQ(CHIPS)':
 'VSS61': CDS_PINID='VSS61';
NODE_NAME     J69 141
 '@T6G_MB_LIB.T6G(SCH_1):PAGE92_I177@PURE_QUANTA.SCONN288_DDR506112002KQ(CHIPS)':
 'VSS62': CDS_PINID='VSS62';
NODE_NAME     J69 143
 '@T6G_MB_LIB.T6G(SCH_1):PAGE92_I177@PURE_QUANTA.SCONN288_DDR506112002KQ(CHIPS)':
 'VSS63': CDS_PINID='VSS63';
NODE_NAME     J69 151
 '@T6G_MB_LIB.T6G(SCH_1):PAGE92_I177@PURE_QUANTA.SCONN288_DDR506112002KQ(CHIPS)':
 'VSS64': CDS_PINID='VSS64';
NODE_NAME     J69 153
 '@T6G_MB_LIB.T6G(SCH_1):PAGE92_I177@PURE_QUANTA.SCONN288_DDR506112002KQ(CHIPS)':
 'VSS65': CDS_PINID='VSS65';
NODE_NAME     J69 155
 '@T6G_MB_LIB.T6G(SCH_1):PAGE92_I177@PURE_QUANTA.SCONN288_DDR506112002KQ(CHIPS)':
 'VSS66': CDS_PINID='VSS66';
NODE_NAME     J69 158
 '@T6G_MB_LIB.T6G(SCH_1):PAGE92_I177@PURE_QUANTA.SCONN288_DDR506112002KQ(CHIPS)':
 'VSS67': CDS_PINID='VSS67';
NODE_NAME     J69 160
 '@T6G_MB_LIB.T6G(SCH_1):PAGE92_I177@PURE_QUANTA.SCONN288_DDR506112002KQ(CHIPS)':
 'VSS68': CDS_PINID='VSS68';
NODE_NAME     J69 162
 '@T6G_MB_LIB.T6G(SCH_1):PAGE92_I177@PURE_QUANTA.SCONN288_DDR506112002KQ(CHIPS)':
 'VSS69': CDS_PINID='VSS69';
NODE_NAME     J69 164
 '@T6G_MB_LIB.T6G(SCH_1):PAGE92_I177@PURE_QUANTA.SCONN288_DDR506112002KQ(CHIPS)':
 'VSS70': CDS_PINID='VSS70';
NODE_NAME     J69 166
 '@T6G_MB_LIB.T6G(SCH_1):PAGE92_I177@PURE_QUANTA.SCONN288_DDR506112002KQ(CHIPS)':
 'VSS71': CDS_PINID='VSS71';
NODE_NAME     J69 169
 '@T6G_MB_LIB.T6G(SCH_1):PAGE92_I177@PURE_QUANTA.SCONN288_DDR506112002KQ(CHIPS)':
 'VSS72': CDS_PINID='VSS72';
NODE_NAME     J69 171
 '@T6G_MB_LIB.T6G(SCH_1):PAGE92_I177@PURE_QUANTA.SCONN288_DDR506112002KQ(CHIPS)':
 'VSS73': CDS_PINID='VSS73';
NODE_NAME     J69 173
 '@T6G_MB_LIB.T6G(SCH_1):PAGE92_I177@PURE_QUANTA.SCONN288_DDR506112002KQ(CHIPS)':
 'VSS74': CDS_PINID='VSS74';
NODE_NAME     J69 175
 '@T6G_MB_LIB.T6G(SCH_1):PAGE92_I177@PURE_QUANTA.SCONN288_DDR506112002KQ(CHIPS)':
 'VSS75': CDS_PINID='VSS75';
NODE_NAME     J69 177
 '@T6G_MB_LIB.T6G(SCH_1):PAGE92_I177@PURE_QUANTA.SCONN288_DDR506112002KQ(CHIPS)':
 'VSS76': CDS_PINID='VSS76';
NODE_NAME     J69 180
 '@T6G_MB_LIB.T6G(SCH_1):PAGE92_I177@PURE_QUANTA.SCONN288_DDR506112002KQ(CHIPS)':
 'VSS77': CDS_PINID='VSS77';
NODE_NAME     J69 182
 '@T6G_MB_LIB.T6G(SCH_1):PAGE92_I177@PURE_QUANTA.SCONN288_DDR506112002KQ(CHIPS)':
 'VSS78': CDS_PINID='VSS78';
NODE_NAME     J69 184
 '@T6G_MB_LIB.T6G(SCH_1):PAGE92_I177@PURE_QUANTA.SCONN288_DDR506112002KQ(CHIPS)':
 'VSS79': CDS_PINID='VSS79';
NODE_NAME     J69 186
 '@T6G_MB_LIB.T6G(SCH_1):PAGE92_I177@PURE_QUANTA.SCONN288_DDR506112002KQ(CHIPS)':
 'VSS80': CDS_PINID='VSS80';
NODE_NAME     J69 188
 '@T6G_MB_LIB.T6G(SCH_1):PAGE92_I177@PURE_QUANTA.SCONN288_DDR506112002KQ(CHIPS)':
 'VSS81': CDS_PINID='VSS81';
NODE_NAME     J69 191
 '@T6G_MB_LIB.T6G(SCH_1):PAGE92_I177@PURE_QUANTA.SCONN288_DDR506112002KQ(CHIPS)':
 'VSS82': CDS_PINID='VSS82';
NODE_NAME     J69 193
 '@T6G_MB_LIB.T6G(SCH_1):PAGE92_I177@PURE_QUANTA.SCONN288_DDR506112002KQ(CHIPS)':
 'VSS83': CDS_PINID='VSS83';
NODE_NAME     J69 195
 '@T6G_MB_LIB.T6G(SCH_1):PAGE92_I177@PURE_QUANTA.SCONN288_DDR506112002KQ(CHIPS)':
 'VSS84': CDS_PINID='VSS84';
NODE_NAME     J69 197
 '@T6G_MB_LIB.T6G(SCH_1):PAGE92_I177@PURE_QUANTA.SCONN288_DDR506112002KQ(CHIPS)':
 'VSS85': CDS_PINID='VSS85';
NODE_NAME     J69 199
 '@T6G_MB_LIB.T6G(SCH_1):PAGE92_I177@PURE_QUANTA.SCONN288_DDR506112002KQ(CHIPS)':
 'VSS86': CDS_PINID='VSS86';
NODE_NAME     J69 202
 '@T6G_MB_LIB.T6G(SCH_1):PAGE92_I177@PURE_QUANTA.SCONN288_DDR506112002KQ(CHIPS)':
 'VSS87': CDS_PINID='VSS87';
NODE_NAME     J69 204
 '@T6G_MB_LIB.T6G(SCH_1):PAGE92_I177@PURE_QUANTA.SCONN288_DDR506112002KQ(CHIPS)':
 'VSS88': CDS_PINID='VSS88';
NODE_NAME     J69 206
 '@T6G_MB_LIB.T6G(SCH_1):PAGE92_I177@PURE_QUANTA.SCONN288_DDR506112002KQ(CHIPS)':
 'VSS89': CDS_PINID='VSS89';
NODE_NAME     J69 208
 '@T6G_MB_LIB.T6G(SCH_1):PAGE92_I177@PURE_QUANTA.SCONN288_DDR506112002KQ(CHIPS)':
 'VSS90': CDS_PINID='VSS90';
NODE_NAME     J69 210
 '@T6G_MB_LIB.T6G(SCH_1):PAGE92_I177@PURE_QUANTA.SCONN288_DDR506112002KQ(CHIPS)':
 'VSS91': CDS_PINID='VSS91';
NODE_NAME     J69 212
 '@T6G_MB_LIB.T6G(SCH_1):PAGE92_I177@PURE_QUANTA.SCONN288_DDR506112002KQ(CHIPS)':
 'VSS92': CDS_PINID='VSS92';
NODE_NAME     J69 214
 '@T6G_MB_LIB.T6G(SCH_1):PAGE92_I177@PURE_QUANTA.SCONN288_DDR506112002KQ(CHIPS)':
 'VSS93': CDS_PINID='VSS93';
NODE_NAME     J69 216
 '@T6G_MB_LIB.T6G(SCH_1):PAGE92_I177@PURE_QUANTA.SCONN288_DDR506112002KQ(CHIPS)':
 'VSS94': CDS_PINID='VSS94';
NODE_NAME     J69 219
 '@T6G_MB_LIB.T6G(SCH_1):PAGE92_I177@PURE_QUANTA.SCONN288_DDR506112002KQ(CHIPS)':
 'VSS95': CDS_PINID='VSS95';
NODE_NAME     J69 222
 '@T6G_MB_LIB.T6G(SCH_1):PAGE92_I177@PURE_QUANTA.SCONN288_DDR506112002KQ(CHIPS)':
 'VSS96': CDS_PINID='VSS96';
NODE_NAME     J69 224
 '@T6G_MB_LIB.T6G(SCH_1):PAGE92_I177@PURE_QUANTA.SCONN288_DDR506112002KQ(CHIPS)':
 'VSS97': CDS_PINID='VSS97';
NODE_NAME     J69 226
 '@T6G_MB_LIB.T6G(SCH_1):PAGE92_I177@PURE_QUANTA.SCONN288_DDR506112002KQ(CHIPS)':
 'VSS98': CDS_PINID='VSS98';
NODE_NAME     J69 228
 '@T6G_MB_LIB.T6G(SCH_1):PAGE92_I177@PURE_QUANTA.SCONN288_DDR506112002KQ(CHIPS)':
 'VSS99': CDS_PINID='VSS99';
NODE_NAME     J69 230
 '@T6G_MB_LIB.T6G(SCH_1):PAGE92_I177@PURE_QUANTA.SCONN288_DDR506112002KQ(CHIPS)':
 'VSS100': CDS_PINID='VSS100';
NODE_NAME     J69 233
 '@T6G_MB_LIB.T6G(SCH_1):PAGE92_I177@PURE_QUANTA.SCONN288_DDR506112002KQ(CHIPS)':
 'VSS101': CDS_PINID='VSS101';
NODE_NAME     J69 235
 '@T6G_MB_LIB.T6G(SCH_1):PAGE92_I177@PURE_QUANTA.SCONN288_DDR506112002KQ(CHIPS)':
 'VSS102': CDS_PINID='VSS102';
NODE_NAME     J69 237
 '@T6G_MB_LIB.T6G(SCH_1):PAGE92_I177@PURE_QUANTA.SCONN288_DDR506112002KQ(CHIPS)':
 'VSS103': CDS_PINID='VSS103';
NODE_NAME     J69 240
 '@T6G_MB_LIB.T6G(SCH_1):PAGE92_I177@PURE_QUANTA.SCONN288_DDR506112002KQ(CHIPS)':
 'VSS104': CDS_PINID='VSS104';
NODE_NAME     J69 242
 '@T6G_MB_LIB.T6G(SCH_1):PAGE92_I177@PURE_QUANTA.SCONN288_DDR506112002KQ(CHIPS)':
 'VSS105': CDS_PINID='VSS105';
NODE_NAME     J69 244
 '@T6G_MB_LIB.T6G(SCH_1):PAGE92_I177@PURE_QUANTA.SCONN288_DDR506112002KQ(CHIPS)':
 'VSS106': CDS_PINID='VSS106';
NODE_NAME     J69 246
 '@T6G_MB_LIB.T6G(SCH_1):PAGE92_I177@PURE_QUANTA.SCONN288_DDR506112002KQ(CHIPS)':
 'VSS107': CDS_PINID='VSS107';
NODE_NAME     J69 248
 '@T6G_MB_LIB.T6G(SCH_1):PAGE92_I177@PURE_QUANTA.SCONN288_DDR506112002KQ(CHIPS)':
 'VSS108': CDS_PINID='VSS108';
NODE_NAME     J69 251
 '@T6G_MB_LIB.T6G(SCH_1):PAGE92_I177@PURE_QUANTA.SCONN288_DDR506112002KQ(CHIPS)':
 'VSS109': CDS_PINID='VSS109';
NODE_NAME     J69 253
 '@T6G_MB_LIB.T6G(SCH_1):PAGE92_I177@PURE_QUANTA.SCONN288_DDR506112002KQ(CHIPS)':
 'VSS110': CDS_PINID='VSS110';
NODE_NAME     J69 255
 '@T6G_MB_LIB.T6G(SCH_1):PAGE92_I177@PURE_QUANTA.SCONN288_DDR506112002KQ(CHIPS)':
 'VSS111': CDS_PINID='VSS111';
NODE_NAME     J69 257
 '@T6G_MB_LIB.T6G(SCH_1):PAGE92_I177@PURE_QUANTA.SCONN288_DDR506112002KQ(CHIPS)':
 'VSS112': CDS_PINID='VSS112';
NODE_NAME     J69 259
 '@T6G_MB_LIB.T6G(SCH_1):PAGE92_I177@PURE_QUANTA.SCONN288_DDR506112002KQ(CHIPS)':
 'VSS113': CDS_PINID='VSS113';
NODE_NAME     J69 262
 '@T6G_MB_LIB.T6G(SCH_1):PAGE92_I177@PURE_QUANTA.SCONN288_DDR506112002KQ(CHIPS)':
 'VSS114': CDS_PINID='VSS114';
NODE_NAME     J69 264
 '@T6G_MB_LIB.T6G(SCH_1):PAGE92_I177@PURE_QUANTA.SCONN288_DDR506112002KQ(CHIPS)':
 'VSS115': CDS_PINID='VSS115';
NODE_NAME     J69 266
 '@T6G_MB_LIB.T6G(SCH_1):PAGE92_I177@PURE_QUANTA.SCONN288_DDR506112002KQ(CHIPS)':
 'VSS116': CDS_PINID='VSS116';
NODE_NAME     J69 268
 '@T6G_MB_LIB.T6G(SCH_1):PAGE92_I177@PURE_QUANTA.SCONN288_DDR506112002KQ(CHIPS)':
 'VSS117': CDS_PINID='VSS117';
NODE_NAME     J69 270
 '@T6G_MB_LIB.T6G(SCH_1):PAGE92_I177@PURE_QUANTA.SCONN288_DDR506112002KQ(CHIPS)':
 'VSS118': CDS_PINID='VSS118';
NODE_NAME     J69 273
 '@T6G_MB_LIB.T6G(SCH_1):PAGE92_I177@PURE_QUANTA.SCONN288_DDR506112002KQ(CHIPS)':
 'VSS119': CDS_PINID='VSS119';
NODE_NAME     J69 275
 '@T6G_MB_LIB.T6G(SCH_1):PAGE92_I177@PURE_QUANTA.SCONN288_DDR506112002KQ(CHIPS)':
 'VSS120': CDS_PINID='VSS120';
NODE_NAME     J69 277
 '@T6G_MB_LIB.T6G(SCH_1):PAGE92_I177@PURE_QUANTA.SCONN288_DDR506112002KQ(CHIPS)':
 'VSS121': CDS_PINID='VSS121';
NODE_NAME     J69 279
 '@T6G_MB_LIB.T6G(SCH_1):PAGE92_I177@PURE_QUANTA.SCONN288_DDR506112002KQ(CHIPS)':
 'VSS122': CDS_PINID='VSS122';
NODE_NAME     J69 281
 '@T6G_MB_LIB.T6G(SCH_1):PAGE92_I177@PURE_QUANTA.SCONN288_DDR506112002KQ(CHIPS)':
 'VSS123': CDS_PINID='VSS123';
NODE_NAME     J69 284
 '@T6G_MB_LIB.T6G(SCH_1):PAGE92_I177@PURE_QUANTA.SCONN288_DDR506112002KQ(CHIPS)':
 'VSS124': CDS_PINID='VSS124';
NODE_NAME     J69 286
 '@T6G_MB_LIB.T6G(SCH_1):PAGE92_I177@PURE_QUANTA.SCONN288_DDR506112002KQ(CHIPS)':
 'VSS125': CDS_PINID='VSS125';
NODE_NAME     J69 288
 '@T6G_MB_LIB.T6G(SCH_1):PAGE92_I177@PURE_QUANTA.SCONN288_DDR506112002KQ(CHIPS)':
 'VSS126': CDS_PINID='VSS126';
NODE_NAME     C116 2
 '@T6G_MB_LIB.T6G(SCH_1):PAGE92_I186@PURE_QUANTA.Q_CAP(CHIPS)':
 'B': CDS_PINID='B';
NODE_NAME     C159 2
 '@T6G_MB_LIB.T6G(SCH_1):PAGE92_I239@PURE_QUANTA.Q_CAP(CHIPS)':
 'B': CDS_PINID='B';
NODE_NAME     C161 2
 '@T6G_MB_LIB.T6G(SCH_1):PAGE92_I240@PURE_QUANTA.Q_CAP(CHIPS)':
 'B': CDS_PINID='B';
NODE_NAME     R766 2
 '@T6G_MB_LIB.T6G(SCH_1):PAGE93_I128@PURE_QUANTA.Q_RES(CHIPS)':
 'B': CDS_PINID='B';
NODE_NAME     J18 G1
 '@T6G_MB_LIB.T6G(SCH_1):PAGE93_I143@PURE_QUANTA.SCONN288_DDR506112002KQ(CHIPS)':
 'G1': CDS_PINID='G1';
NODE_NAME     J18 G2
 '@T6G_MB_LIB.T6G(SCH_1):PAGE93_I143@PURE_QUANTA.SCONN288_DDR506112002KQ(CHIPS)':
 'G2': CDS_PINID='G2';
NODE_NAME     J18 G3
 '@T6G_MB_LIB.T6G(SCH_1):PAGE93_I143@PURE_QUANTA.SCONN288_DDR506112002KQ(CHIPS)':
 'G3': CDS_PINID='G3';
NODE_NAME     J18 6
 '@T6G_MB_LIB.T6G(SCH_1):PAGE93_I143@PURE_QUANTA.SCONN288_DDR506112002KQ(CHIPS)':
 'VSS0': CDS_PINID='VSS0';
NODE_NAME     J18 8
 '@T6G_MB_LIB.T6G(SCH_1):PAGE93_I143@PURE_QUANTA.SCONN288_DDR506112002KQ(CHIPS)':
 'VSS1': CDS_PINID='VSS1';
NODE_NAME     J18 10
 '@T6G_MB_LIB.T6G(SCH_1):PAGE93_I143@PURE_QUANTA.SCONN288_DDR506112002KQ(CHIPS)':
 'VSS2': CDS_PINID='VSS2';
NODE_NAME     J18 13
 '@T6G_MB_LIB.T6G(SCH_1):PAGE93_I143@PURE_QUANTA.SCONN288_DDR506112002KQ(CHIPS)':
 'VSS3': CDS_PINID='VSS3';
NODE_NAME     J18 15
 '@T6G_MB_LIB.T6G(SCH_1):PAGE93_I143@PURE_QUANTA.SCONN288_DDR506112002KQ(CHIPS)':
 'VSS4': CDS_PINID='VSS4';
NODE_NAME     J18 17
 '@T6G_MB_LIB.T6G(SCH_1):PAGE93_I143@PURE_QUANTA.SCONN288_DDR506112002KQ(CHIPS)':
 'VSS5': CDS_PINID='VSS5';
NODE_NAME     J18 19
 '@T6G_MB_LIB.T6G(SCH_1):PAGE93_I143@PURE_QUANTA.SCONN288_DDR506112002KQ(CHIPS)':
 'VSS6': CDS_PINID='VSS6';
NODE_NAME     J18 21
 '@T6G_MB_LIB.T6G(SCH_1):PAGE93_I143@PURE_QUANTA.SCONN288_DDR506112002KQ(CHIPS)':
 'VSS7': CDS_PINID='VSS7';
NODE_NAME     J18 24
 '@T6G_MB_LIB.T6G(SCH_1):PAGE93_I143@PURE_QUANTA.SCONN288_DDR506112002KQ(CHIPS)':
 'VSS8': CDS_PINID='VSS8';
NODE_NAME     J18 26
 '@T6G_MB_LIB.T6G(SCH_1):PAGE93_I143@PURE_QUANTA.SCONN288_DDR506112002KQ(CHIPS)':
 'VSS9': CDS_PINID='VSS9';
NODE_NAME     J18 28
 '@T6G_MB_LIB.T6G(SCH_1):PAGE93_I143@PURE_QUANTA.SCONN288_DDR506112002KQ(CHIPS)':
 'VSS10': CDS_PINID='VSS10';
NODE_NAME     J18 30
 '@T6G_MB_LIB.T6G(SCH_1):PAGE93_I143@PURE_QUANTA.SCONN288_DDR506112002KQ(CHIPS)':
 'VSS11': CDS_PINID='VSS11';
NODE_NAME     J18 32
 '@T6G_MB_LIB.T6G(SCH_1):PAGE93_I143@PURE_QUANTA.SCONN288_DDR506112002KQ(CHIPS)':
 'VSS12': CDS_PINID='VSS12';
NODE_NAME     J18 35
 '@T6G_MB_LIB.T6G(SCH_1):PAGE93_I143@PURE_QUANTA.SCONN288_DDR506112002KQ(CHIPS)':
 'VSS13': CDS_PINID='VSS13';
NODE_NAME     J18 37
 '@T6G_MB_LIB.T6G(SCH_1):PAGE93_I143@PURE_QUANTA.SCONN288_DDR506112002KQ(CHIPS)':
 'VSS14': CDS_PINID='VSS14';
NODE_NAME     J18 39
 '@T6G_MB_LIB.T6G(SCH_1):PAGE93_I143@PURE_QUANTA.SCONN288_DDR506112002KQ(CHIPS)':
 'VSS15': CDS_PINID='VSS15';
NODE_NAME     J18 41
 '@T6G_MB_LIB.T6G(SCH_1):PAGE93_I143@PURE_QUANTA.SCONN288_DDR506112002KQ(CHIPS)':
 'VSS16': CDS_PINID='VSS16';
NODE_NAME     J18 43
 '@T6G_MB_LIB.T6G(SCH_1):PAGE93_I143@PURE_QUANTA.SCONN288_DDR506112002KQ(CHIPS)':
 'VSS17': CDS_PINID='VSS17';
NODE_NAME     J18 46
 '@T6G_MB_LIB.T6G(SCH_1):PAGE93_I143@PURE_QUANTA.SCONN288_DDR506112002KQ(CHIPS)':
 'VSS18': CDS_PINID='VSS18';
NODE_NAME     J18 48
 '@T6G_MB_LIB.T6G(SCH_1):PAGE93_I143@PURE_QUANTA.SCONN288_DDR506112002KQ(CHIPS)':
 'VSS19': CDS_PINID='VSS19';
NODE_NAME     J18 50
 '@T6G_MB_LIB.T6G(SCH_1):PAGE93_I143@PURE_QUANTA.SCONN288_DDR506112002KQ(CHIPS)':
 'VSS20': CDS_PINID='VSS20';
NODE_NAME     J18 52
 '@T6G_MB_LIB.T6G(SCH_1):PAGE93_I143@PURE_QUANTA.SCONN288_DDR506112002KQ(CHIPS)':
 'VSS21': CDS_PINID='VSS21';
NODE_NAME     J18 54
 '@T6G_MB_LIB.T6G(SCH_1):PAGE93_I143@PURE_QUANTA.SCONN288_DDR506112002KQ(CHIPS)':
 'VSS22': CDS_PINID='VSS22';
NODE_NAME     J18 57
 '@T6G_MB_LIB.T6G(SCH_1):PAGE93_I143@PURE_QUANTA.SCONN288_DDR506112002KQ(CHIPS)':
 'VSS23': CDS_PINID='VSS23';
NODE_NAME     J18 59
 '@T6G_MB_LIB.T6G(SCH_1):PAGE93_I143@PURE_QUANTA.SCONN288_DDR506112002KQ(CHIPS)':
 'VSS24': CDS_PINID='VSS24';
NODE_NAME     J18 61
 '@T6G_MB_LIB.T6G(SCH_1):PAGE93_I143@PURE_QUANTA.SCONN288_DDR506112002KQ(CHIPS)':
 'VSS25': CDS_PINID='VSS25';
NODE_NAME     J18 63
 '@T6G_MB_LIB.T6G(SCH_1):PAGE93_I143@PURE_QUANTA.SCONN288_DDR506112002KQ(CHIPS)':
 'VSS26': CDS_PINID='VSS26';
NODE_NAME     J18 65
 '@T6G_MB_LIB.T6G(SCH_1):PAGE93_I143@PURE_QUANTA.SCONN288_DDR506112002KQ(CHIPS)':
 'VSS27': CDS_PINID='VSS27';
NODE_NAME     J18 67
 '@T6G_MB_LIB.T6G(SCH_1):PAGE93_I143@PURE_QUANTA.SCONN288_DDR506112002KQ(CHIPS)':
 'VSS28': CDS_PINID='VSS28';
NODE_NAME     J18 69
 '@T6G_MB_LIB.T6G(SCH_1):PAGE93_I143@PURE_QUANTA.SCONN288_DDR506112002KQ(CHIPS)':
 'VSS29': CDS_PINID='VSS29';
NODE_NAME     J18 71
 '@T6G_MB_LIB.T6G(SCH_1):PAGE93_I143@PURE_QUANTA.SCONN288_DDR506112002KQ(CHIPS)':
 'VSS30': CDS_PINID='VSS30';
NODE_NAME     J18 73
 '@T6G_MB_LIB.T6G(SCH_1):PAGE93_I143@PURE_QUANTA.SCONN288_DDR506112002KQ(CHIPS)':
 'VSS31': CDS_PINID='VSS31';
NODE_NAME     J18 75
 '@T6G_MB_LIB.T6G(SCH_1):PAGE93_I143@PURE_QUANTA.SCONN288_DDR506112002KQ(CHIPS)':
 'VSS32': CDS_PINID='VSS32';
NODE_NAME     J18 77
 '@T6G_MB_LIB.T6G(SCH_1):PAGE93_I143@PURE_QUANTA.SCONN288_DDR506112002KQ(CHIPS)':
 'VSS33': CDS_PINID='VSS33';
NODE_NAME     J18 79
 '@T6G_MB_LIB.T6G(SCH_1):PAGE93_I143@PURE_QUANTA.SCONN288_DDR506112002KQ(CHIPS)':
 'VSS34': CDS_PINID='VSS34';
NODE_NAME     J18 81
 '@T6G_MB_LIB.T6G(SCH_1):PAGE93_I143@PURE_QUANTA.SCONN288_DDR506112002KQ(CHIPS)':
 'VSS35': CDS_PINID='VSS35';
NODE_NAME     J18 83
 '@T6G_MB_LIB.T6G(SCH_1):PAGE93_I143@PURE_QUANTA.SCONN288_DDR506112002KQ(CHIPS)':
 'VSS36': CDS_PINID='VSS36';
NODE_NAME     J18 85
 '@T6G_MB_LIB.T6G(SCH_1):PAGE93_I143@PURE_QUANTA.SCONN288_DDR506112002KQ(CHIPS)':
 'VSS37': CDS_PINID='VSS37';
NODE_NAME     J18 88
 '@T6G_MB_LIB.T6G(SCH_1):PAGE93_I143@PURE_QUANTA.SCONN288_DDR506112002KQ(CHIPS)':
 'VSS38': CDS_PINID='VSS38';
NODE_NAME     J18 90
 '@T6G_MB_LIB.T6G(SCH_1):PAGE93_I143@PURE_QUANTA.SCONN288_DDR506112002KQ(CHIPS)':
 'VSS39': CDS_PINID='VSS39';
NODE_NAME     J18 92
 '@T6G_MB_LIB.T6G(SCH_1):PAGE93_I143@PURE_QUANTA.SCONN288_DDR506112002KQ(CHIPS)':
 'VSS40': CDS_PINID='VSS40';
NODE_NAME     J18 95
 '@T6G_MB_LIB.T6G(SCH_1):PAGE93_I143@PURE_QUANTA.SCONN288_DDR506112002KQ(CHIPS)':
 'VSS41': CDS_PINID='VSS41';
NODE_NAME     J18 97
 '@T6G_MB_LIB.T6G(SCH_1):PAGE93_I143@PURE_QUANTA.SCONN288_DDR506112002KQ(CHIPS)':
 'VSS42': CDS_PINID='VSS42';
NODE_NAME     J18 99
 '@T6G_MB_LIB.T6G(SCH_1):PAGE93_I143@PURE_QUANTA.SCONN288_DDR506112002KQ(CHIPS)':
 'VSS43': CDS_PINID='VSS43';
NODE_NAME     J18 101
 '@T6G_MB_LIB.T6G(SCH_1):PAGE93_I143@PURE_QUANTA.SCONN288_DDR506112002KQ(CHIPS)':
 'VSS44': CDS_PINID='VSS44';
NODE_NAME     J18 103
 '@T6G_MB_LIB.T6G(SCH_1):PAGE93_I143@PURE_QUANTA.SCONN288_DDR506112002KQ(CHIPS)':
 'VSS45': CDS_PINID='VSS45';
NODE_NAME     J18 106
 '@T6G_MB_LIB.T6G(SCH_1):PAGE93_I143@PURE_QUANTA.SCONN288_DDR506112002KQ(CHIPS)':
 'VSS46': CDS_PINID='VSS46';
NODE_NAME     J18 108
 '@T6G_MB_LIB.T6G(SCH_1):PAGE93_I143@PURE_QUANTA.SCONN288_DDR506112002KQ(CHIPS)':
 'VSS47': CDS_PINID='VSS47';
NODE_NAME     J18 110
 '@T6G_MB_LIB.T6G(SCH_1):PAGE93_I143@PURE_QUANTA.SCONN288_DDR506112002KQ(CHIPS)':
 'VSS48': CDS_PINID='VSS48';
NODE_NAME     J18 112
 '@T6G_MB_LIB.T6G(SCH_1):PAGE93_I143@PURE_QUANTA.SCONN288_DDR506112002KQ(CHIPS)':
 'VSS49': CDS_PINID='VSS49';
NODE_NAME     J18 114
 '@T6G_MB_LIB.T6G(SCH_1):PAGE93_I143@PURE_QUANTA.SCONN288_DDR506112002KQ(CHIPS)':
 'VSS50': CDS_PINID='VSS50';
NODE_NAME     J18 117
 '@T6G_MB_LIB.T6G(SCH_1):PAGE93_I143@PURE_QUANTA.SCONN288_DDR506112002KQ(CHIPS)':
 'VSS51': CDS_PINID='VSS51';
NODE_NAME     J18 119
 '@T6G_MB_LIB.T6G(SCH_1):PAGE93_I143@PURE_QUANTA.SCONN288_DDR506112002KQ(CHIPS)':
 'VSS52': CDS_PINID='VSS52';
NODE_NAME     J18 121
 '@T6G_MB_LIB.T6G(SCH_1):PAGE93_I143@PURE_QUANTA.SCONN288_DDR506112002KQ(CHIPS)':
 'VSS53': CDS_PINID='VSS53';
NODE_NAME     J18 123
 '@T6G_MB_LIB.T6G(SCH_1):PAGE93_I143@PURE_QUANTA.SCONN288_DDR506112002KQ(CHIPS)':
 'VSS54': CDS_PINID='VSS54';
NODE_NAME     J18 125
 '@T6G_MB_LIB.T6G(SCH_1):PAGE93_I143@PURE_QUANTA.SCONN288_DDR506112002KQ(CHIPS)':
 'VSS55': CDS_PINID='VSS55';
NODE_NAME     J18 128
 '@T6G_MB_LIB.T6G(SCH_1):PAGE93_I143@PURE_QUANTA.SCONN288_DDR506112002KQ(CHIPS)':
 'VSS56': CDS_PINID='VSS56';
NODE_NAME     J18 130
 '@T6G_MB_LIB.T6G(SCH_1):PAGE93_I143@PURE_QUANTA.SCONN288_DDR506112002KQ(CHIPS)':
 'VSS57': CDS_PINID='VSS57';
NODE_NAME     J18 132
 '@T6G_MB_LIB.T6G(SCH_1):PAGE93_I143@PURE_QUANTA.SCONN288_DDR506112002KQ(CHIPS)':
 'VSS58': CDS_PINID='VSS58';
NODE_NAME     J18 134
 '@T6G_MB_LIB.T6G(SCH_1):PAGE93_I143@PURE_QUANTA.SCONN288_DDR506112002KQ(CHIPS)':
 'VSS59': CDS_PINID='VSS59';
NODE_NAME     J18 136
 '@T6G_MB_LIB.T6G(SCH_1):PAGE93_I143@PURE_QUANTA.SCONN288_DDR506112002KQ(CHIPS)':
 'VSS60': CDS_PINID='VSS60';
NODE_NAME     J18 139
 '@T6G_MB_LIB.T6G(SCH_1):PAGE93_I143@PURE_QUANTA.SCONN288_DDR506112002KQ(CHIPS)':
 'VSS61': CDS_PINID='VSS61';
NODE_NAME     J18 141
 '@T6G_MB_LIB.T6G(SCH_1):PAGE93_I143@PURE_QUANTA.SCONN288_DDR506112002KQ(CHIPS)':
 'VSS62': CDS_PINID='VSS62';
NODE_NAME     J18 143
 '@T6G_MB_LIB.T6G(SCH_1):PAGE93_I143@PURE_QUANTA.SCONN288_DDR506112002KQ(CHIPS)':
 'VSS63': CDS_PINID='VSS63';
NODE_NAME     J18 151
 '@T6G_MB_LIB.T6G(SCH_1):PAGE93_I143@PURE_QUANTA.SCONN288_DDR506112002KQ(CHIPS)':
 'VSS64': CDS_PINID='VSS64';
NODE_NAME     J18 153
 '@T6G_MB_LIB.T6G(SCH_1):PAGE93_I143@PURE_QUANTA.SCONN288_DDR506112002KQ(CHIPS)':
 'VSS65': CDS_PINID='VSS65';
NODE_NAME     J18 155
 '@T6G_MB_LIB.T6G(SCH_1):PAGE93_I143@PURE_QUANTA.SCONN288_DDR506112002KQ(CHIPS)':
 'VSS66': CDS_PINID='VSS66';
NODE_NAME     J18 158
 '@T6G_MB_LIB.T6G(SCH_1):PAGE93_I143@PURE_QUANTA.SCONN288_DDR506112002KQ(CHIPS)':
 'VSS67': CDS_PINID='VSS67';
NODE_NAME     J18 160
 '@T6G_MB_LIB.T6G(SCH_1):PAGE93_I143@PURE_QUANTA.SCONN288_DDR506112002KQ(CHIPS)':
 'VSS68': CDS_PINID='VSS68';
NODE_NAME     J18 162
 '@T6G_MB_LIB.T6G(SCH_1):PAGE93_I143@PURE_QUANTA.SCONN288_DDR506112002KQ(CHIPS)':
 'VSS69': CDS_PINID='VSS69';
NODE_NAME     J18 164
 '@T6G_MB_LIB.T6G(SCH_1):PAGE93_I143@PURE_QUANTA.SCONN288_DDR506112002KQ(CHIPS)':
 'VSS70': CDS_PINID='VSS70';
NODE_NAME     J18 166
 '@T6G_MB_LIB.T6G(SCH_1):PAGE93_I143@PURE_QUANTA.SCONN288_DDR506112002KQ(CHIPS)':
 'VSS71': CDS_PINID='VSS71';
NODE_NAME     J18 169
 '@T6G_MB_LIB.T6G(SCH_1):PAGE93_I143@PURE_QUANTA.SCONN288_DDR506112002KQ(CHIPS)':
 'VSS72': CDS_PINID='VSS72';
NODE_NAME     J18 171
 '@T6G_MB_LIB.T6G(SCH_1):PAGE93_I143@PURE_QUANTA.SCONN288_DDR506112002KQ(CHIPS)':
 'VSS73': CDS_PINID='VSS73';
NODE_NAME     J18 173
 '@T6G_MB_LIB.T6G(SCH_1):PAGE93_I143@PURE_QUANTA.SCONN288_DDR506112002KQ(CHIPS)':
 'VSS74': CDS_PINID='VSS74';
NODE_NAME     J18 175
 '@T6G_MB_LIB.T6G(SCH_1):PAGE93_I143@PURE_QUANTA.SCONN288_DDR506112002KQ(CHIPS)':
 'VSS75': CDS_PINID='VSS75';
NODE_NAME     J18 177
 '@T6G_MB_LIB.T6G(SCH_1):PAGE93_I143@PURE_QUANTA.SCONN288_DDR506112002KQ(CHIPS)':
 'VSS76': CDS_PINID='VSS76';
NODE_NAME     J18 180
 '@T6G_MB_LIB.T6G(SCH_1):PAGE93_I143@PURE_QUANTA.SCONN288_DDR506112002KQ(CHIPS)':
 'VSS77': CDS_PINID='VSS77';
NODE_NAME     J18 182
 '@T6G_MB_LIB.T6G(SCH_1):PAGE93_I143@PURE_QUANTA.SCONN288_DDR506112002KQ(CHIPS)':
 'VSS78': CDS_PINID='VSS78';
NODE_NAME     J18 184
 '@T6G_MB_LIB.T6G(SCH_1):PAGE93_I143@PURE_QUANTA.SCONN288_DDR506112002KQ(CHIPS)':
 'VSS79': CDS_PINID='VSS79';
NODE_NAME     J18 186
 '@T6G_MB_LIB.T6G(SCH_1):PAGE93_I143@PURE_QUANTA.SCONN288_DDR506112002KQ(CHIPS)':
 'VSS80': CDS_PINID='VSS80';
NODE_NAME     J18 188
 '@T6G_MB_LIB.T6G(SCH_1):PAGE93_I143@PURE_QUANTA.SCONN288_DDR506112002KQ(CHIPS)':
 'VSS81': CDS_PINID='VSS81';
NODE_NAME     J18 191
 '@T6G_MB_LIB.T6G(SCH_1):PAGE93_I143@PURE_QUANTA.SCONN288_DDR506112002KQ(CHIPS)':
 'VSS82': CDS_PINID='VSS82';
NODE_NAME     J18 193
 '@T6G_MB_LIB.T6G(SCH_1):PAGE93_I143@PURE_QUANTA.SCONN288_DDR506112002KQ(CHIPS)':
 'VSS83': CDS_PINID='VSS83';
NODE_NAME     J18 195
 '@T6G_MB_LIB.T6G(SCH_1):PAGE93_I143@PURE_QUANTA.SCONN288_DDR506112002KQ(CHIPS)':
 'VSS84': CDS_PINID='VSS84';
NODE_NAME     J18 197
 '@T6G_MB_LIB.T6G(SCH_1):PAGE93_I143@PURE_QUANTA.SCONN288_DDR506112002KQ(CHIPS)':
 'VSS85': CDS_PINID='VSS85';
NODE_NAME     J18 199
 '@T6G_MB_LIB.T6G(SCH_1):PAGE93_I143@PURE_QUANTA.SCONN288_DDR506112002KQ(CHIPS)':
 'VSS86': CDS_PINID='VSS86';
NODE_NAME     J18 202
 '@T6G_MB_LIB.T6G(SCH_1):PAGE93_I143@PURE_QUANTA.SCONN288_DDR506112002KQ(CHIPS)':
 'VSS87': CDS_PINID='VSS87';
NODE_NAME     J18 204
 '@T6G_MB_LIB.T6G(SCH_1):PAGE93_I143@PURE_QUANTA.SCONN288_DDR506112002KQ(CHIPS)':
 'VSS88': CDS_PINID='VSS88';
NODE_NAME     J18 206
 '@T6G_MB_LIB.T6G(SCH_1):PAGE93_I143@PURE_QUANTA.SCONN288_DDR506112002KQ(CHIPS)':
 'VSS89': CDS_PINID='VSS89';
NODE_NAME     J18 208
 '@T6G_MB_LIB.T6G(SCH_1):PAGE93_I143@PURE_QUANTA.SCONN288_DDR506112002KQ(CHIPS)':
 'VSS90': CDS_PINID='VSS90';
NODE_NAME     J18 210
 '@T6G_MB_LIB.T6G(SCH_1):PAGE93_I143@PURE_QUANTA.SCONN288_DDR506112002KQ(CHIPS)':
 'VSS91': CDS_PINID='VSS91';
NODE_NAME     J18 212
 '@T6G_MB_LIB.T6G(SCH_1):PAGE93_I143@PURE_QUANTA.SCONN288_DDR506112002KQ(CHIPS)':
 'VSS92': CDS_PINID='VSS92';
NODE_NAME     J18 214
 '@T6G_MB_LIB.T6G(SCH_1):PAGE93_I143@PURE_QUANTA.SCONN288_DDR506112002KQ(CHIPS)':
 'VSS93': CDS_PINID='VSS93';
NODE_NAME     J18 216
 '@T6G_MB_LIB.T6G(SCH_1):PAGE93_I143@PURE_QUANTA.SCONN288_DDR506112002KQ(CHIPS)':
 'VSS94': CDS_PINID='VSS94';
NODE_NAME     J18 219
 '@T6G_MB_LIB.T6G(SCH_1):PAGE93_I143@PURE_QUANTA.SCONN288_DDR506112002KQ(CHIPS)':
 'VSS95': CDS_PINID='VSS95';
NODE_NAME     J18 222
 '@T6G_MB_LIB.T6G(SCH_1):PAGE93_I143@PURE_QUANTA.SCONN288_DDR506112002KQ(CHIPS)':
 'VSS96': CDS_PINID='VSS96';
NODE_NAME     J18 224
 '@T6G_MB_LIB.T6G(SCH_1):PAGE93_I143@PURE_QUANTA.SCONN288_DDR506112002KQ(CHIPS)':
 'VSS97': CDS_PINID='VSS97';
NODE_NAME     J18 226
 '@T6G_MB_LIB.T6G(SCH_1):PAGE93_I143@PURE_QUANTA.SCONN288_DDR506112002KQ(CHIPS)':
 'VSS98': CDS_PINID='VSS98';
NODE_NAME     J18 228
 '@T6G_MB_LIB.T6G(SCH_1):PAGE93_I143@PURE_QUANTA.SCONN288_DDR506112002KQ(CHIPS)':
 'VSS99': CDS_PINID='VSS99';
NODE_NAME     J18 230
 '@T6G_MB_LIB.T6G(SCH_1):PAGE93_I143@PURE_QUANTA.SCONN288_DDR506112002KQ(CHIPS)':
 'VSS100': CDS_PINID='VSS100';
NODE_NAME     J18 233
 '@T6G_MB_LIB.T6G(SCH_1):PAGE93_I143@PURE_QUANTA.SCONN288_DDR506112002KQ(CHIPS)':
 'VSS101': CDS_PINID='VSS101';
NODE_NAME     J18 235
 '@T6G_MB_LIB.T6G(SCH_1):PAGE93_I143@PURE_QUANTA.SCONN288_DDR506112002KQ(CHIPS)':
 'VSS102': CDS_PINID='VSS102';
NODE_NAME     J18 237
 '@T6G_MB_LIB.T6G(SCH_1):PAGE93_I143@PURE_QUANTA.SCONN288_DDR506112002KQ(CHIPS)':
 'VSS103': CDS_PINID='VSS103';
NODE_NAME     J18 240
 '@T6G_MB_LIB.T6G(SCH_1):PAGE93_I143@PURE_QUANTA.SCONN288_DDR506112002KQ(CHIPS)':
 'VSS104': CDS_PINID='VSS104';
NODE_NAME     J18 242
 '@T6G_MB_LIB.T6G(SCH_1):PAGE93_I143@PURE_QUANTA.SCONN288_DDR506112002KQ(CHIPS)':
 'VSS105': CDS_PINID='VSS105';
NODE_NAME     J18 244
 '@T6G_MB_LIB.T6G(SCH_1):PAGE93_I143@PURE_QUANTA.SCONN288_DDR506112002KQ(CHIPS)':
 'VSS106': CDS_PINID='VSS106';
NODE_NAME     J18 246
 '@T6G_MB_LIB.T6G(SCH_1):PAGE93_I143@PURE_QUANTA.SCONN288_DDR506112002KQ(CHIPS)':
 'VSS107': CDS_PINID='VSS107';
NODE_NAME     J18 248
 '@T6G_MB_LIB.T6G(SCH_1):PAGE93_I143@PURE_QUANTA.SCONN288_DDR506112002KQ(CHIPS)':
 'VSS108': CDS_PINID='VSS108';
NODE_NAME     J18 251
 '@T6G_MB_LIB.T6G(SCH_1):PAGE93_I143@PURE_QUANTA.SCONN288_DDR506112002KQ(CHIPS)':
 'VSS109': CDS_PINID='VSS109';
NODE_NAME     J18 253
 '@T6G_MB_LIB.T6G(SCH_1):PAGE93_I143@PURE_QUANTA.SCONN288_DDR506112002KQ(CHIPS)':
 'VSS110': CDS_PINID='VSS110';
NODE_NAME     J18 255
 '@T6G_MB_LIB.T6G(SCH_1):PAGE93_I143@PURE_QUANTA.SCONN288_DDR506112002KQ(CHIPS)':
 'VSS111': CDS_PINID='VSS111';
NODE_NAME     J18 257
 '@T6G_MB_LIB.T6G(SCH_1):PAGE93_I143@PURE_QUANTA.SCONN288_DDR506112002KQ(CHIPS)':
 'VSS112': CDS_PINID='VSS112';
NODE_NAME     J18 259
 '@T6G_MB_LIB.T6G(SCH_1):PAGE93_I143@PURE_QUANTA.SCONN288_DDR506112002KQ(CHIPS)':
 'VSS113': CDS_PINID='VSS113';
NODE_NAME     J18 262
 '@T6G_MB_LIB.T6G(SCH_1):PAGE93_I143@PURE_QUANTA.SCONN288_DDR506112002KQ(CHIPS)':
 'VSS114': CDS_PINID='VSS114';
NODE_NAME     J18 264
 '@T6G_MB_LIB.T6G(SCH_1):PAGE93_I143@PURE_QUANTA.SCONN288_DDR506112002KQ(CHIPS)':
 'VSS115': CDS_PINID='VSS115';
NODE_NAME     J18 266
 '@T6G_MB_LIB.T6G(SCH_1):PAGE93_I143@PURE_QUANTA.SCONN288_DDR506112002KQ(CHIPS)':
 'VSS116': CDS_PINID='VSS116';
NODE_NAME     J18 268
 '@T6G_MB_LIB.T6G(SCH_1):PAGE93_I143@PURE_QUANTA.SCONN288_DDR506112002KQ(CHIPS)':
 'VSS117': CDS_PINID='VSS117';
NODE_NAME     J18 270
 '@T6G_MB_LIB.T6G(SCH_1):PAGE93_I143@PURE_QUANTA.SCONN288_DDR506112002KQ(CHIPS)':
 'VSS118': CDS_PINID='VSS118';
NODE_NAME     J18 273
 '@T6G_MB_LIB.T6G(SCH_1):PAGE93_I143@PURE_QUANTA.SCONN288_DDR506112002KQ(CHIPS)':
 'VSS119': CDS_PINID='VSS119';
NODE_NAME     J18 275
 '@T6G_MB_LIB.T6G(SCH_1):PAGE93_I143@PURE_QUANTA.SCONN288_DDR506112002KQ(CHIPS)':
 'VSS120': CDS_PINID='VSS120';
NODE_NAME     J18 277
 '@T6G_MB_LIB.T6G(SCH_1):PAGE93_I143@PURE_QUANTA.SCONN288_DDR506112002KQ(CHIPS)':
 'VSS121': CDS_PINID='VSS121';
NODE_NAME     J18 279
 '@T6G_MB_LIB.T6G(SCH_1):PAGE93_I143@PURE_QUANTA.SCONN288_DDR506112002KQ(CHIPS)':
 'VSS122': CDS_PINID='VSS122';
NODE_NAME     J18 281
 '@T6G_MB_LIB.T6G(SCH_1):PAGE93_I143@PURE_QUANTA.SCONN288_DDR506112002KQ(CHIPS)':
 'VSS123': CDS_PINID='VSS123';
NODE_NAME     J18 284
 '@T6G_MB_LIB.T6G(SCH_1):PAGE93_I143@PURE_QUANTA.SCONN288_DDR506112002KQ(CHIPS)':
 'VSS124': CDS_PINID='VSS124';
NODE_NAME     J18 286
 '@T6G_MB_LIB.T6G(SCH_1):PAGE93_I143@PURE_QUANTA.SCONN288_DDR506112002KQ(CHIPS)':
 'VSS125': CDS_PINID='VSS125';
NODE_NAME     J18 288
 '@T6G_MB_LIB.T6G(SCH_1):PAGE93_I143@PURE_QUANTA.SCONN288_DDR506112002KQ(CHIPS)':
 'VSS126': CDS_PINID='VSS126';
NODE_NAME     C120 2
 '@T6G_MB_LIB.T6G(SCH_1):PAGE93_I185@PURE_QUANTA.Q_CAP(CHIPS)':
 'B': CDS_PINID='B';
NODE_NAME     C162 2
 '@T6G_MB_LIB.T6G(SCH_1):PAGE93_I238@PURE_QUANTA.Q_CAP(CHIPS)':
 'B': CDS_PINID='B';
NODE_NAME     C163 2
 '@T6G_MB_LIB.T6G(SCH_1):PAGE93_I239@PURE_QUANTA.Q_CAP(CHIPS)':
 'B': CDS_PINID='B';
NODE_NAME     R767 2
 '@T6G_MB_LIB.T6G(SCH_1):PAGE94_I129@PURE_QUANTA.Q_RES(CHIPS)':
 'B': CDS_PINID='B';
NODE_NAME     J68 G1
 '@T6G_MB_LIB.T6G(SCH_1):PAGE94_I177@PURE_QUANTA.SCONN288_DDR506112002KQ(CHIPS)':
 'G1': CDS_PINID='G1';
NODE_NAME     J68 G2
 '@T6G_MB_LIB.T6G(SCH_1):PAGE94_I177@PURE_QUANTA.SCONN288_DDR506112002KQ(CHIPS)':
 'G2': CDS_PINID='G2';
NODE_NAME     J68 G3
 '@T6G_MB_LIB.T6G(SCH_1):PAGE94_I177@PURE_QUANTA.SCONN288_DDR506112002KQ(CHIPS)':
 'G3': CDS_PINID='G3';
NODE_NAME     J68 6
 '@T6G_MB_LIB.T6G(SCH_1):PAGE94_I177@PURE_QUANTA.SCONN288_DDR506112002KQ(CHIPS)':
 'VSS0': CDS_PINID='VSS0';
NODE_NAME     J68 8
 '@T6G_MB_LIB.T6G(SCH_1):PAGE94_I177@PURE_QUANTA.SCONN288_DDR506112002KQ(CHIPS)':
 'VSS1': CDS_PINID='VSS1';
NODE_NAME     J68 10
 '@T6G_MB_LIB.T6G(SCH_1):PAGE94_I177@PURE_QUANTA.SCONN288_DDR506112002KQ(CHIPS)':
 'VSS2': CDS_PINID='VSS2';
NODE_NAME     J68 13
 '@T6G_MB_LIB.T6G(SCH_1):PAGE94_I177@PURE_QUANTA.SCONN288_DDR506112002KQ(CHIPS)':
 'VSS3': CDS_PINID='VSS3';
NODE_NAME     J68 15
 '@T6G_MB_LIB.T6G(SCH_1):PAGE94_I177@PURE_QUANTA.SCONN288_DDR506112002KQ(CHIPS)':
 'VSS4': CDS_PINID='VSS4';
NODE_NAME     J68 17
 '@T6G_MB_LIB.T6G(SCH_1):PAGE94_I177@PURE_QUANTA.SCONN288_DDR506112002KQ(CHIPS)':
 'VSS5': CDS_PINID='VSS5';
NODE_NAME     J68 19
 '@T6G_MB_LIB.T6G(SCH_1):PAGE94_I177@PURE_QUANTA.SCONN288_DDR506112002KQ(CHIPS)':
 'VSS6': CDS_PINID='VSS6';
NODE_NAME     J68 21
 '@T6G_MB_LIB.T6G(SCH_1):PAGE94_I177@PURE_QUANTA.SCONN288_DDR506112002KQ(CHIPS)':
 'VSS7': CDS_PINID='VSS7';
NODE_NAME     J68 24
 '@T6G_MB_LIB.T6G(SCH_1):PAGE94_I177@PURE_QUANTA.SCONN288_DDR506112002KQ(CHIPS)':
 'VSS8': CDS_PINID='VSS8';
NODE_NAME     J68 26
 '@T6G_MB_LIB.T6G(SCH_1):PAGE94_I177@PURE_QUANTA.SCONN288_DDR506112002KQ(CHIPS)':
 'VSS9': CDS_PINID='VSS9';
NODE_NAME     J68 28
 '@T6G_MB_LIB.T6G(SCH_1):PAGE94_I177@PURE_QUANTA.SCONN288_DDR506112002KQ(CHIPS)':
 'VSS10': CDS_PINID='VSS10';
NODE_NAME     J68 30
 '@T6G_MB_LIB.T6G(SCH_1):PAGE94_I177@PURE_QUANTA.SCONN288_DDR506112002KQ(CHIPS)':
 'VSS11': CDS_PINID='VSS11';
NODE_NAME     J68 32
 '@T6G_MB_LIB.T6G(SCH_1):PAGE94_I177@PURE_QUANTA.SCONN288_DDR506112002KQ(CHIPS)':
 'VSS12': CDS_PINID='VSS12';
NODE_NAME     J68 35
 '@T6G_MB_LIB.T6G(SCH_1):PAGE94_I177@PURE_QUANTA.SCONN288_DDR506112002KQ(CHIPS)':
 'VSS13': CDS_PINID='VSS13';
NODE_NAME     J68 37
 '@T6G_MB_LIB.T6G(SCH_1):PAGE94_I177@PURE_QUANTA.SCONN288_DDR506112002KQ(CHIPS)':
 'VSS14': CDS_PINID='VSS14';
NODE_NAME     J68 39
 '@T6G_MB_LIB.T6G(SCH_1):PAGE94_I177@PURE_QUANTA.SCONN288_DDR506112002KQ(CHIPS)':
 'VSS15': CDS_PINID='VSS15';
NODE_NAME     J68 41
 '@T6G_MB_LIB.T6G(SCH_1):PAGE94_I177@PURE_QUANTA.SCONN288_DDR506112002KQ(CHIPS)':
 'VSS16': CDS_PINID='VSS16';
NODE_NAME     J68 43
 '@T6G_MB_LIB.T6G(SCH_1):PAGE94_I177@PURE_QUANTA.SCONN288_DDR506112002KQ(CHIPS)':
 'VSS17': CDS_PINID='VSS17';
NODE_NAME     J68 46
 '@T6G_MB_LIB.T6G(SCH_1):PAGE94_I177@PURE_QUANTA.SCONN288_DDR506112002KQ(CHIPS)':
 'VSS18': CDS_PINID='VSS18';
NODE_NAME     J68 48
 '@T6G_MB_LIB.T6G(SCH_1):PAGE94_I177@PURE_QUANTA.SCONN288_DDR506112002KQ(CHIPS)':
 'VSS19': CDS_PINID='VSS19';
NODE_NAME     J68 50
 '@T6G_MB_LIB.T6G(SCH_1):PAGE94_I177@PURE_QUANTA.SCONN288_DDR506112002KQ(CHIPS)':
 'VSS20': CDS_PINID='VSS20';
NODE_NAME     J68 52
 '@T6G_MB_LIB.T6G(SCH_1):PAGE94_I177@PURE_QUANTA.SCONN288_DDR506112002KQ(CHIPS)':
 'VSS21': CDS_PINID='VSS21';
NODE_NAME     J68 54
 '@T6G_MB_LIB.T6G(SCH_1):PAGE94_I177@PURE_QUANTA.SCONN288_DDR506112002KQ(CHIPS)':
 'VSS22': CDS_PINID='VSS22';
NODE_NAME     J68 57
 '@T6G_MB_LIB.T6G(SCH_1):PAGE94_I177@PURE_QUANTA.SCONN288_DDR506112002KQ(CHIPS)':
 'VSS23': CDS_PINID='VSS23';
NODE_NAME     J68 59
 '@T6G_MB_LIB.T6G(SCH_1):PAGE94_I177@PURE_QUANTA.SCONN288_DDR506112002KQ(CHIPS)':
 'VSS24': CDS_PINID='VSS24';
NODE_NAME     J68 61
 '@T6G_MB_LIB.T6G(SCH_1):PAGE94_I177@PURE_QUANTA.SCONN288_DDR506112002KQ(CHIPS)':
 'VSS25': CDS_PINID='VSS25';
NODE_NAME     J68 63
 '@T6G_MB_LIB.T6G(SCH_1):PAGE94_I177@PURE_QUANTA.SCONN288_DDR506112002KQ(CHIPS)':
 'VSS26': CDS_PINID='VSS26';
NODE_NAME     J68 65
 '@T6G_MB_LIB.T6G(SCH_1):PAGE94_I177@PURE_QUANTA.SCONN288_DDR506112002KQ(CHIPS)':
 'VSS27': CDS_PINID='VSS27';
NODE_NAME     J68 67
 '@T6G_MB_LIB.T6G(SCH_1):PAGE94_I177@PURE_QUANTA.SCONN288_DDR506112002KQ(CHIPS)':
 'VSS28': CDS_PINID='VSS28';
NODE_NAME     J68 69
 '@T6G_MB_LIB.T6G(SCH_1):PAGE94_I177@PURE_QUANTA.SCONN288_DDR506112002KQ(CHIPS)':
 'VSS29': CDS_PINID='VSS29';
NODE_NAME     J68 71
 '@T6G_MB_LIB.T6G(SCH_1):PAGE94_I177@PURE_QUANTA.SCONN288_DDR506112002KQ(CHIPS)':
 'VSS30': CDS_PINID='VSS30';
NODE_NAME     J68 73
 '@T6G_MB_LIB.T6G(SCH_1):PAGE94_I177@PURE_QUANTA.SCONN288_DDR506112002KQ(CHIPS)':
 'VSS31': CDS_PINID='VSS31';
NODE_NAME     J68 75
 '@T6G_MB_LIB.T6G(SCH_1):PAGE94_I177@PURE_QUANTA.SCONN288_DDR506112002KQ(CHIPS)':
 'VSS32': CDS_PINID='VSS32';
NODE_NAME     J68 77
 '@T6G_MB_LIB.T6G(SCH_1):PAGE94_I177@PURE_QUANTA.SCONN288_DDR506112002KQ(CHIPS)':
 'VSS33': CDS_PINID='VSS33';
NODE_NAME     J68 79
 '@T6G_MB_LIB.T6G(SCH_1):PAGE94_I177@PURE_QUANTA.SCONN288_DDR506112002KQ(CHIPS)':
 'VSS34': CDS_PINID='VSS34';
NODE_NAME     J68 81
 '@T6G_MB_LIB.T6G(SCH_1):PAGE94_I177@PURE_QUANTA.SCONN288_DDR506112002KQ(CHIPS)':
 'VSS35': CDS_PINID='VSS35';
NODE_NAME     J68 83
 '@T6G_MB_LIB.T6G(SCH_1):PAGE94_I177@PURE_QUANTA.SCONN288_DDR506112002KQ(CHIPS)':
 'VSS36': CDS_PINID='VSS36';
NODE_NAME     J68 85
 '@T6G_MB_LIB.T6G(SCH_1):PAGE94_I177@PURE_QUANTA.SCONN288_DDR506112002KQ(CHIPS)':
 'VSS37': CDS_PINID='VSS37';
NODE_NAME     J68 88
 '@T6G_MB_LIB.T6G(SCH_1):PAGE94_I177@PURE_QUANTA.SCONN288_DDR506112002KQ(CHIPS)':
 'VSS38': CDS_PINID='VSS38';
NODE_NAME     J68 90
 '@T6G_MB_LIB.T6G(SCH_1):PAGE94_I177@PURE_QUANTA.SCONN288_DDR506112002KQ(CHIPS)':
 'VSS39': CDS_PINID='VSS39';
NODE_NAME     J68 92
 '@T6G_MB_LIB.T6G(SCH_1):PAGE94_I177@PURE_QUANTA.SCONN288_DDR506112002KQ(CHIPS)':
 'VSS40': CDS_PINID='VSS40';
NODE_NAME     J68 95
 '@T6G_MB_LIB.T6G(SCH_1):PAGE94_I177@PURE_QUANTA.SCONN288_DDR506112002KQ(CHIPS)':
 'VSS41': CDS_PINID='VSS41';
NODE_NAME     J68 97
 '@T6G_MB_LIB.T6G(SCH_1):PAGE94_I177@PURE_QUANTA.SCONN288_DDR506112002KQ(CHIPS)':
 'VSS42': CDS_PINID='VSS42';
NODE_NAME     J68 99
 '@T6G_MB_LIB.T6G(SCH_1):PAGE94_I177@PURE_QUANTA.SCONN288_DDR506112002KQ(CHIPS)':
 'VSS43': CDS_PINID='VSS43';
NODE_NAME     J68 101
 '@T6G_MB_LIB.T6G(SCH_1):PAGE94_I177@PURE_QUANTA.SCONN288_DDR506112002KQ(CHIPS)':
 'VSS44': CDS_PINID='VSS44';
NODE_NAME     J68 103
 '@T6G_MB_LIB.T6G(SCH_1):PAGE94_I177@PURE_QUANTA.SCONN288_DDR506112002KQ(CHIPS)':
 'VSS45': CDS_PINID='VSS45';
NODE_NAME     J68 106
 '@T6G_MB_LIB.T6G(SCH_1):PAGE94_I177@PURE_QUANTA.SCONN288_DDR506112002KQ(CHIPS)':
 'VSS46': CDS_PINID='VSS46';
NODE_NAME     J68 108
 '@T6G_MB_LIB.T6G(SCH_1):PAGE94_I177@PURE_QUANTA.SCONN288_DDR506112002KQ(CHIPS)':
 'VSS47': CDS_PINID='VSS47';
NODE_NAME     J68 110
 '@T6G_MB_LIB.T6G(SCH_1):PAGE94_I177@PURE_QUANTA.SCONN288_DDR506112002KQ(CHIPS)':
 'VSS48': CDS_PINID='VSS48';
NODE_NAME     J68 112
 '@T6G_MB_LIB.T6G(SCH_1):PAGE94_I177@PURE_QUANTA.SCONN288_DDR506112002KQ(CHIPS)':
 'VSS49': CDS_PINID='VSS49';
NODE_NAME     J68 114
 '@T6G_MB_LIB.T6G(SCH_1):PAGE94_I177@PURE_QUANTA.SCONN288_DDR506112002KQ(CHIPS)':
 'VSS50': CDS_PINID='VSS50';
NODE_NAME     J68 117
 '@T6G_MB_LIB.T6G(SCH_1):PAGE94_I177@PURE_QUANTA.SCONN288_DDR506112002KQ(CHIPS)':
 'VSS51': CDS_PINID='VSS51';
NODE_NAME     J68 119
 '@T6G_MB_LIB.T6G(SCH_1):PAGE94_I177@PURE_QUANTA.SCONN288_DDR506112002KQ(CHIPS)':
 'VSS52': CDS_PINID='VSS52';
NODE_NAME     J68 121
 '@T6G_MB_LIB.T6G(SCH_1):PAGE94_I177@PURE_QUANTA.SCONN288_DDR506112002KQ(CHIPS)':
 'VSS53': CDS_PINID='VSS53';
NODE_NAME     J68 123
 '@T6G_MB_LIB.T6G(SCH_1):PAGE94_I177@PURE_QUANTA.SCONN288_DDR506112002KQ(CHIPS)':
 'VSS54': CDS_PINID='VSS54';
NODE_NAME     J68 125
 '@T6G_MB_LIB.T6G(SCH_1):PAGE94_I177@PURE_QUANTA.SCONN288_DDR506112002KQ(CHIPS)':
 'VSS55': CDS_PINID='VSS55';
NODE_NAME     J68 128
 '@T6G_MB_LIB.T6G(SCH_1):PAGE94_I177@PURE_QUANTA.SCONN288_DDR506112002KQ(CHIPS)':
 'VSS56': CDS_PINID='VSS56';
NODE_NAME     J68 130
 '@T6G_MB_LIB.T6G(SCH_1):PAGE94_I177@PURE_QUANTA.SCONN288_DDR506112002KQ(CHIPS)':
 'VSS57': CDS_PINID='VSS57';
NODE_NAME     J68 132
 '@T6G_MB_LIB.T6G(SCH_1):PAGE94_I177@PURE_QUANTA.SCONN288_DDR506112002KQ(CHIPS)':
 'VSS58': CDS_PINID='VSS58';
NODE_NAME     J68 134
 '@T6G_MB_LIB.T6G(SCH_1):PAGE94_I177@PURE_QUANTA.SCONN288_DDR506112002KQ(CHIPS)':
 'VSS59': CDS_PINID='VSS59';
NODE_NAME     J68 136
 '@T6G_MB_LIB.T6G(SCH_1):PAGE94_I177@PURE_QUANTA.SCONN288_DDR506112002KQ(CHIPS)':
 'VSS60': CDS_PINID='VSS60';
NODE_NAME     J68 139
 '@T6G_MB_LIB.T6G(SCH_1):PAGE94_I177@PURE_QUANTA.SCONN288_DDR506112002KQ(CHIPS)':
 'VSS61': CDS_PINID='VSS61';
NODE_NAME     J68 141
 '@T6G_MB_LIB.T6G(SCH_1):PAGE94_I177@PURE_QUANTA.SCONN288_DDR506112002KQ(CHIPS)':
 'VSS62': CDS_PINID='VSS62';
NODE_NAME     J68 143
 '@T6G_MB_LIB.T6G(SCH_1):PAGE94_I177@PURE_QUANTA.SCONN288_DDR506112002KQ(CHIPS)':
 'VSS63': CDS_PINID='VSS63';
NODE_NAME     J68 151
 '@T6G_MB_LIB.T6G(SCH_1):PAGE94_I177@PURE_QUANTA.SCONN288_DDR506112002KQ(CHIPS)':
 'VSS64': CDS_PINID='VSS64';
NODE_NAME     J68 153
 '@T6G_MB_LIB.T6G(SCH_1):PAGE94_I177@PURE_QUANTA.SCONN288_DDR506112002KQ(CHIPS)':
 'VSS65': CDS_PINID='VSS65';
NODE_NAME     J68 155
 '@T6G_MB_LIB.T6G(SCH_1):PAGE94_I177@PURE_QUANTA.SCONN288_DDR506112002KQ(CHIPS)':
 'VSS66': CDS_PINID='VSS66';
NODE_NAME     J68 158
 '@T6G_MB_LIB.T6G(SCH_1):PAGE94_I177@PURE_QUANTA.SCONN288_DDR506112002KQ(CHIPS)':
 'VSS67': CDS_PINID='VSS67';
NODE_NAME     J68 160
 '@T6G_MB_LIB.T6G(SCH_1):PAGE94_I177@PURE_QUANTA.SCONN288_DDR506112002KQ(CHIPS)':
 'VSS68': CDS_PINID='VSS68';
NODE_NAME     J68 162
 '@T6G_MB_LIB.T6G(SCH_1):PAGE94_I177@PURE_QUANTA.SCONN288_DDR506112002KQ(CHIPS)':
 'VSS69': CDS_PINID='VSS69';
NODE_NAME     J68 164
 '@T6G_MB_LIB.T6G(SCH_1):PAGE94_I177@PURE_QUANTA.SCONN288_DDR506112002KQ(CHIPS)':
 'VSS70': CDS_PINID='VSS70';
NODE_NAME     J68 166
 '@T6G_MB_LIB.T6G(SCH_1):PAGE94_I177@PURE_QUANTA.SCONN288_DDR506112002KQ(CHIPS)':
 'VSS71': CDS_PINID='VSS71';
NODE_NAME     J68 169
 '@T6G_MB_LIB.T6G(SCH_1):PAGE94_I177@PURE_QUANTA.SCONN288_DDR506112002KQ(CHIPS)':
 'VSS72': CDS_PINID='VSS72';
NODE_NAME     J68 171
 '@T6G_MB_LIB.T6G(SCH_1):PAGE94_I177@PURE_QUANTA.SCONN288_DDR506112002KQ(CHIPS)':
 'VSS73': CDS_PINID='VSS73';
NODE_NAME     J68 173
 '@T6G_MB_LIB.T6G(SCH_1):PAGE94_I177@PURE_QUANTA.SCONN288_DDR506112002KQ(CHIPS)':
 'VSS74': CDS_PINID='VSS74';
NODE_NAME     J68 175
 '@T6G_MB_LIB.T6G(SCH_1):PAGE94_I177@PURE_QUANTA.SCONN288_DDR506112002KQ(CHIPS)':
 'VSS75': CDS_PINID='VSS75';
NODE_NAME     J68 177
 '@T6G_MB_LIB.T6G(SCH_1):PAGE94_I177@PURE_QUANTA.SCONN288_DDR506112002KQ(CHIPS)':
 'VSS76': CDS_PINID='VSS76';
NODE_NAME     J68 180
 '@T6G_MB_LIB.T6G(SCH_1):PAGE94_I177@PURE_QUANTA.SCONN288_DDR506112002KQ(CHIPS)':
 'VSS77': CDS_PINID='VSS77';
NODE_NAME     J68 182
 '@T6G_MB_LIB.T6G(SCH_1):PAGE94_I177@PURE_QUANTA.SCONN288_DDR506112002KQ(CHIPS)':
 'VSS78': CDS_PINID='VSS78';
NODE_NAME     J68 184
 '@T6G_MB_LIB.T6G(SCH_1):PAGE94_I177@PURE_QUANTA.SCONN288_DDR506112002KQ(CHIPS)':
 'VSS79': CDS_PINID='VSS79';
NODE_NAME     J68 186
 '@T6G_MB_LIB.T6G(SCH_1):PAGE94_I177@PURE_QUANTA.SCONN288_DDR506112002KQ(CHIPS)':
 'VSS80': CDS_PINID='VSS80';
NODE_NAME     J68 188
 '@T6G_MB_LIB.T6G(SCH_1):PAGE94_I177@PURE_QUANTA.SCONN288_DDR506112002KQ(CHIPS)':
 'VSS81': CDS_PINID='VSS81';
NODE_NAME     J68 191
 '@T6G_MB_LIB.T6G(SCH_1):PAGE94_I177@PURE_QUANTA.SCONN288_DDR506112002KQ(CHIPS)':
 'VSS82': CDS_PINID='VSS82';
NODE_NAME     J68 193
 '@T6G_MB_LIB.T6G(SCH_1):PAGE94_I177@PURE_QUANTA.SCONN288_DDR506112002KQ(CHIPS)':
 'VSS83': CDS_PINID='VSS83';
NODE_NAME     J68 195
 '@T6G_MB_LIB.T6G(SCH_1):PAGE94_I177@PURE_QUANTA.SCONN288_DDR506112002KQ(CHIPS)':
 'VSS84': CDS_PINID='VSS84';
NODE_NAME     J68 197
 '@T6G_MB_LIB.T6G(SCH_1):PAGE94_I177@PURE_QUANTA.SCONN288_DDR506112002KQ(CHIPS)':
 'VSS85': CDS_PINID='VSS85';
NODE_NAME     J68 199
 '@T6G_MB_LIB.T6G(SCH_1):PAGE94_I177@PURE_QUANTA.SCONN288_DDR506112002KQ(CHIPS)':
 'VSS86': CDS_PINID='VSS86';
NODE_NAME     J68 202
 '@T6G_MB_LIB.T6G(SCH_1):PAGE94_I177@PURE_QUANTA.SCONN288_DDR506112002KQ(CHIPS)':
 'VSS87': CDS_PINID='VSS87';
NODE_NAME     J68 204
 '@T6G_MB_LIB.T6G(SCH_1):PAGE94_I177@PURE_QUANTA.SCONN288_DDR506112002KQ(CHIPS)':
 'VSS88': CDS_PINID='VSS88';
NODE_NAME     J68 206
 '@T6G_MB_LIB.T6G(SCH_1):PAGE94_I177@PURE_QUANTA.SCONN288_DDR506112002KQ(CHIPS)':
 'VSS89': CDS_PINID='VSS89';
NODE_NAME     J68 208
 '@T6G_MB_LIB.T6G(SCH_1):PAGE94_I177@PURE_QUANTA.SCONN288_DDR506112002KQ(CHIPS)':
 'VSS90': CDS_PINID='VSS90';
NODE_NAME     J68 210
 '@T6G_MB_LIB.T6G(SCH_1):PAGE94_I177@PURE_QUANTA.SCONN288_DDR506112002KQ(CHIPS)':
 'VSS91': CDS_PINID='VSS91';
NODE_NAME     J68 212
 '@T6G_MB_LIB.T6G(SCH_1):PAGE94_I177@PURE_QUANTA.SCONN288_DDR506112002KQ(CHIPS)':
 'VSS92': CDS_PINID='VSS92';
NODE_NAME     J68 214
 '@T6G_MB_LIB.T6G(SCH_1):PAGE94_I177@PURE_QUANTA.SCONN288_DDR506112002KQ(CHIPS)':
 'VSS93': CDS_PINID='VSS93';
NODE_NAME     J68 216
 '@T6G_MB_LIB.T6G(SCH_1):PAGE94_I177@PURE_QUANTA.SCONN288_DDR506112002KQ(CHIPS)':
 'VSS94': CDS_PINID='VSS94';
NODE_NAME     J68 219
 '@T6G_MB_LIB.T6G(SCH_1):PAGE94_I177@PURE_QUANTA.SCONN288_DDR506112002KQ(CHIPS)':
 'VSS95': CDS_PINID='VSS95';
NODE_NAME     J68 222
 '@T6G_MB_LIB.T6G(SCH_1):PAGE94_I177@PURE_QUANTA.SCONN288_DDR506112002KQ(CHIPS)':
 'VSS96': CDS_PINID='VSS96';
NODE_NAME     J68 224
 '@T6G_MB_LIB.T6G(SCH_1):PAGE94_I177@PURE_QUANTA.SCONN288_DDR506112002KQ(CHIPS)':
 'VSS97': CDS_PINID='VSS97';
NODE_NAME     J68 226
 '@T6G_MB_LIB.T6G(SCH_1):PAGE94_I177@PURE_QUANTA.SCONN288_DDR506112002KQ(CHIPS)':
 'VSS98': CDS_PINID='VSS98';
NODE_NAME     J68 228
 '@T6G_MB_LIB.T6G(SCH_1):PAGE94_I177@PURE_QUANTA.SCONN288_DDR506112002KQ(CHIPS)':
 'VSS99': CDS_PINID='VSS99';
NODE_NAME     J68 230
 '@T6G_MB_LIB.T6G(SCH_1):PAGE94_I177@PURE_QUANTA.SCONN288_DDR506112002KQ(CHIPS)':
 'VSS100': CDS_PINID='VSS100';
NODE_NAME     J68 233
 '@T6G_MB_LIB.T6G(SCH_1):PAGE94_I177@PURE_QUANTA.SCONN288_DDR506112002KQ(CHIPS)':
 'VSS101': CDS_PINID='VSS101';
NODE_NAME     J68 235
 '@T6G_MB_LIB.T6G(SCH_1):PAGE94_I177@PURE_QUANTA.SCONN288_DDR506112002KQ(CHIPS)':
 'VSS102': CDS_PINID='VSS102';
NODE_NAME     J68 237
 '@T6G_MB_LIB.T6G(SCH_1):PAGE94_I177@PURE_QUANTA.SCONN288_DDR506112002KQ(CHIPS)':
 'VSS103': CDS_PINID='VSS103';
NODE_NAME     J68 240
 '@T6G_MB_LIB.T6G(SCH_1):PAGE94_I177@PURE_QUANTA.SCONN288_DDR506112002KQ(CHIPS)':
 'VSS104': CDS_PINID='VSS104';
NODE_NAME     J68 242
 '@T6G_MB_LIB.T6G(SCH_1):PAGE94_I177@PURE_QUANTA.SCONN288_DDR506112002KQ(CHIPS)':
 'VSS105': CDS_PINID='VSS105';
NODE_NAME     J68 244
 '@T6G_MB_LIB.T6G(SCH_1):PAGE94_I177@PURE_QUANTA.SCONN288_DDR506112002KQ(CHIPS)':
 'VSS106': CDS_PINID='VSS106';
NODE_NAME     J68 246
 '@T6G_MB_LIB.T6G(SCH_1):PAGE94_I177@PURE_QUANTA.SCONN288_DDR506112002KQ(CHIPS)':
 'VSS107': CDS_PINID='VSS107';
NODE_NAME     J68 248
 '@T6G_MB_LIB.T6G(SCH_1):PAGE94_I177@PURE_QUANTA.SCONN288_DDR506112002KQ(CHIPS)':
 'VSS108': CDS_PINID='VSS108';
NODE_NAME     J68 251
 '@T6G_MB_LIB.T6G(SCH_1):PAGE94_I177@PURE_QUANTA.SCONN288_DDR506112002KQ(CHIPS)':
 'VSS109': CDS_PINID='VSS109';
NODE_NAME     J68 253
 '@T6G_MB_LIB.T6G(SCH_1):PAGE94_I177@PURE_QUANTA.SCONN288_DDR506112002KQ(CHIPS)':
 'VSS110': CDS_PINID='VSS110';
NODE_NAME     J68 255
 '@T6G_MB_LIB.T6G(SCH_1):PAGE94_I177@PURE_QUANTA.SCONN288_DDR506112002KQ(CHIPS)':
 'VSS111': CDS_PINID='VSS111';
NODE_NAME     J68 257
 '@T6G_MB_LIB.T6G(SCH_1):PAGE94_I177@PURE_QUANTA.SCONN288_DDR506112002KQ(CHIPS)':
 'VSS112': CDS_PINID='VSS112';
NODE_NAME     J68 259
 '@T6G_MB_LIB.T6G(SCH_1):PAGE94_I177@PURE_QUANTA.SCONN288_DDR506112002KQ(CHIPS)':
 'VSS113': CDS_PINID='VSS113';
NODE_NAME     J68 262
 '@T6G_MB_LIB.T6G(SCH_1):PAGE94_I177@PURE_QUANTA.SCONN288_DDR506112002KQ(CHIPS)':
 'VSS114': CDS_PINID='VSS114';
NODE_NAME     J68 264
 '@T6G_MB_LIB.T6G(SCH_1):PAGE94_I177@PURE_QUANTA.SCONN288_DDR506112002KQ(CHIPS)':
 'VSS115': CDS_PINID='VSS115';
NODE_NAME     J68 266
 '@T6G_MB_LIB.T6G(SCH_1):PAGE94_I177@PURE_QUANTA.SCONN288_DDR506112002KQ(CHIPS)':
 'VSS116': CDS_PINID='VSS116';
NODE_NAME     J68 268
 '@T6G_MB_LIB.T6G(SCH_1):PAGE94_I177@PURE_QUANTA.SCONN288_DDR506112002KQ(CHIPS)':
 'VSS117': CDS_PINID='VSS117';
NODE_NAME     J68 270
 '@T6G_MB_LIB.T6G(SCH_1):PAGE94_I177@PURE_QUANTA.SCONN288_DDR506112002KQ(CHIPS)':
 'VSS118': CDS_PINID='VSS118';
NODE_NAME     J68 273
 '@T6G_MB_LIB.T6G(SCH_1):PAGE94_I177@PURE_QUANTA.SCONN288_DDR506112002KQ(CHIPS)':
 'VSS119': CDS_PINID='VSS119';
NODE_NAME     J68 275
 '@T6G_MB_LIB.T6G(SCH_1):PAGE94_I177@PURE_QUANTA.SCONN288_DDR506112002KQ(CHIPS)':
 'VSS120': CDS_PINID='VSS120';
NODE_NAME     J68 277
 '@T6G_MB_LIB.T6G(SCH_1):PAGE94_I177@PURE_QUANTA.SCONN288_DDR506112002KQ(CHIPS)':
 'VSS121': CDS_PINID='VSS121';
NODE_NAME     J68 279
 '@T6G_MB_LIB.T6G(SCH_1):PAGE94_I177@PURE_QUANTA.SCONN288_DDR506112002KQ(CHIPS)':
 'VSS122': CDS_PINID='VSS122';
NODE_NAME     J68 281
 '@T6G_MB_LIB.T6G(SCH_1):PAGE94_I177@PURE_QUANTA.SCONN288_DDR506112002KQ(CHIPS)':
 'VSS123': CDS_PINID='VSS123';
NODE_NAME     J68 284
 '@T6G_MB_LIB.T6G(SCH_1):PAGE94_I177@PURE_QUANTA.SCONN288_DDR506112002KQ(CHIPS)':
 'VSS124': CDS_PINID='VSS124';
NODE_NAME     J68 286
 '@T6G_MB_LIB.T6G(SCH_1):PAGE94_I177@PURE_QUANTA.SCONN288_DDR506112002KQ(CHIPS)':
 'VSS125': CDS_PINID='VSS125';
NODE_NAME     J68 288
 '@T6G_MB_LIB.T6G(SCH_1):PAGE94_I177@PURE_QUANTA.SCONN288_DDR506112002KQ(CHIPS)':
 'VSS126': CDS_PINID='VSS126';
NODE_NAME     C124 2
 '@T6G_MB_LIB.T6G(SCH_1):PAGE94_I185@PURE_QUANTA.Q_CAP(CHIPS)':
 'B': CDS_PINID='B';
NODE_NAME     C165 2
 '@T6G_MB_LIB.T6G(SCH_1):PAGE94_I238@PURE_QUANTA.Q_CAP(CHIPS)':
 'B': CDS_PINID='B';
NODE_NAME     C166 2
 '@T6G_MB_LIB.T6G(SCH_1):PAGE94_I239@PURE_QUANTA.Q_CAP(CHIPS)':
 'B': CDS_PINID='B';
NODE_NAME     R768 2
 '@T6G_MB_LIB.T6G(SCH_1):PAGE95_I129@PURE_QUANTA.Q_RES(CHIPS)':
 'B': CDS_PINID='B';
NODE_NAME     J20 G1
 '@T6G_MB_LIB.T6G(SCH_1):PAGE95_I177@PURE_QUANTA.SCONN288_DDR506112002KQ(CHIPS)':
 'G1': CDS_PINID='G1';
NODE_NAME     J20 G2
 '@T6G_MB_LIB.T6G(SCH_1):PAGE95_I177@PURE_QUANTA.SCONN288_DDR506112002KQ(CHIPS)':
 'G2': CDS_PINID='G2';
NODE_NAME     J20 G3
 '@T6G_MB_LIB.T6G(SCH_1):PAGE95_I177@PURE_QUANTA.SCONN288_DDR506112002KQ(CHIPS)':
 'G3': CDS_PINID='G3';
NODE_NAME     J20 6
 '@T6G_MB_LIB.T6G(SCH_1):PAGE95_I177@PURE_QUANTA.SCONN288_DDR506112002KQ(CHIPS)':
 'VSS0': CDS_PINID='VSS0';
NODE_NAME     J20 8
 '@T6G_MB_LIB.T6G(SCH_1):PAGE95_I177@PURE_QUANTA.SCONN288_DDR506112002KQ(CHIPS)':
 'VSS1': CDS_PINID='VSS1';
NODE_NAME     J20 10
 '@T6G_MB_LIB.T6G(SCH_1):PAGE95_I177@PURE_QUANTA.SCONN288_DDR506112002KQ(CHIPS)':
 'VSS2': CDS_PINID='VSS2';
NODE_NAME     J20 13
 '@T6G_MB_LIB.T6G(SCH_1):PAGE95_I177@PURE_QUANTA.SCONN288_DDR506112002KQ(CHIPS)':
 'VSS3': CDS_PINID='VSS3';
NODE_NAME     J20 15
 '@T6G_MB_LIB.T6G(SCH_1):PAGE95_I177@PURE_QUANTA.SCONN288_DDR506112002KQ(CHIPS)':
 'VSS4': CDS_PINID='VSS4';
NODE_NAME     J20 17
 '@T6G_MB_LIB.T6G(SCH_1):PAGE95_I177@PURE_QUANTA.SCONN288_DDR506112002KQ(CHIPS)':
 'VSS5': CDS_PINID='VSS5';
NODE_NAME     J20 19
 '@T6G_MB_LIB.T6G(SCH_1):PAGE95_I177@PURE_QUANTA.SCONN288_DDR506112002KQ(CHIPS)':
 'VSS6': CDS_PINID='VSS6';
NODE_NAME     J20 21
 '@T6G_MB_LIB.T6G(SCH_1):PAGE95_I177@PURE_QUANTA.SCONN288_DDR506112002KQ(CHIPS)':
 'VSS7': CDS_PINID='VSS7';
NODE_NAME     J20 24
 '@T6G_MB_LIB.T6G(SCH_1):PAGE95_I177@PURE_QUANTA.SCONN288_DDR506112002KQ(CHIPS)':
 'VSS8': CDS_PINID='VSS8';
NODE_NAME     J20 26
 '@T6G_MB_LIB.T6G(SCH_1):PAGE95_I177@PURE_QUANTA.SCONN288_DDR506112002KQ(CHIPS)':
 'VSS9': CDS_PINID='VSS9';
NODE_NAME     J20 28
 '@T6G_MB_LIB.T6G(SCH_1):PAGE95_I177@PURE_QUANTA.SCONN288_DDR506112002KQ(CHIPS)':
 'VSS10': CDS_PINID='VSS10';
NODE_NAME     J20 30
 '@T6G_MB_LIB.T6G(SCH_1):PAGE95_I177@PURE_QUANTA.SCONN288_DDR506112002KQ(CHIPS)':
 'VSS11': CDS_PINID='VSS11';
NODE_NAME     J20 32
 '@T6G_MB_LIB.T6G(SCH_1):PAGE95_I177@PURE_QUANTA.SCONN288_DDR506112002KQ(CHIPS)':
 'VSS12': CDS_PINID='VSS12';
NODE_NAME     J20 35
 '@T6G_MB_LIB.T6G(SCH_1):PAGE95_I177@PURE_QUANTA.SCONN288_DDR506112002KQ(CHIPS)':
 'VSS13': CDS_PINID='VSS13';
NODE_NAME     J20 37
 '@T6G_MB_LIB.T6G(SCH_1):PAGE95_I177@PURE_QUANTA.SCONN288_DDR506112002KQ(CHIPS)':
 'VSS14': CDS_PINID='VSS14';
NODE_NAME     J20 39
 '@T6G_MB_LIB.T6G(SCH_1):PAGE95_I177@PURE_QUANTA.SCONN288_DDR506112002KQ(CHIPS)':
 'VSS15': CDS_PINID='VSS15';
NODE_NAME     J20 41
 '@T6G_MB_LIB.T6G(SCH_1):PAGE95_I177@PURE_QUANTA.SCONN288_DDR506112002KQ(CHIPS)':
 'VSS16': CDS_PINID='VSS16';
NODE_NAME     J20 43
 '@T6G_MB_LIB.T6G(SCH_1):PAGE95_I177@PURE_QUANTA.SCONN288_DDR506112002KQ(CHIPS)':
 'VSS17': CDS_PINID='VSS17';
NODE_NAME     J20 46
 '@T6G_MB_LIB.T6G(SCH_1):PAGE95_I177@PURE_QUANTA.SCONN288_DDR506112002KQ(CHIPS)':
 'VSS18': CDS_PINID='VSS18';
NODE_NAME     J20 48
 '@T6G_MB_LIB.T6G(SCH_1):PAGE95_I177@PURE_QUANTA.SCONN288_DDR506112002KQ(CHIPS)':
 'VSS19': CDS_PINID='VSS19';
NODE_NAME     J20 50
 '@T6G_MB_LIB.T6G(SCH_1):PAGE95_I177@PURE_QUANTA.SCONN288_DDR506112002KQ(CHIPS)':
 'VSS20': CDS_PINID='VSS20';
NODE_NAME     J20 52
 '@T6G_MB_LIB.T6G(SCH_1):PAGE95_I177@PURE_QUANTA.SCONN288_DDR506112002KQ(CHIPS)':
 'VSS21': CDS_PINID='VSS21';
NODE_NAME     J20 54
 '@T6G_MB_LIB.T6G(SCH_1):PAGE95_I177@PURE_QUANTA.SCONN288_DDR506112002KQ(CHIPS)':
 'VSS22': CDS_PINID='VSS22';
NODE_NAME     J20 57
 '@T6G_MB_LIB.T6G(SCH_1):PAGE95_I177@PURE_QUANTA.SCONN288_DDR506112002KQ(CHIPS)':
 'VSS23': CDS_PINID='VSS23';
NODE_NAME     J20 59
 '@T6G_MB_LIB.T6G(SCH_1):PAGE95_I177@PURE_QUANTA.SCONN288_DDR506112002KQ(CHIPS)':
 'VSS24': CDS_PINID='VSS24';
NODE_NAME     J20 61
 '@T6G_MB_LIB.T6G(SCH_1):PAGE95_I177@PURE_QUANTA.SCONN288_DDR506112002KQ(CHIPS)':
 'VSS25': CDS_PINID='VSS25';
NODE_NAME     J20 63
 '@T6G_MB_LIB.T6G(SCH_1):PAGE95_I177@PURE_QUANTA.SCONN288_DDR506112002KQ(CHIPS)':
 'VSS26': CDS_PINID='VSS26';
NODE_NAME     J20 65
 '@T6G_MB_LIB.T6G(SCH_1):PAGE95_I177@PURE_QUANTA.SCONN288_DDR506112002KQ(CHIPS)':
 'VSS27': CDS_PINID='VSS27';
NODE_NAME     J20 67
 '@T6G_MB_LIB.T6G(SCH_1):PAGE95_I177@PURE_QUANTA.SCONN288_DDR506112002KQ(CHIPS)':
 'VSS28': CDS_PINID='VSS28';
NODE_NAME     J20 69
 '@T6G_MB_LIB.T6G(SCH_1):PAGE95_I177@PURE_QUANTA.SCONN288_DDR506112002KQ(CHIPS)':
 'VSS29': CDS_PINID='VSS29';
NODE_NAME     J20 71
 '@T6G_MB_LIB.T6G(SCH_1):PAGE95_I177@PURE_QUANTA.SCONN288_DDR506112002KQ(CHIPS)':
 'VSS30': CDS_PINID='VSS30';
NODE_NAME     J20 73
 '@T6G_MB_LIB.T6G(SCH_1):PAGE95_I177@PURE_QUANTA.SCONN288_DDR506112002KQ(CHIPS)':
 'VSS31': CDS_PINID='VSS31';
NODE_NAME     J20 75
 '@T6G_MB_LIB.T6G(SCH_1):PAGE95_I177@PURE_QUANTA.SCONN288_DDR506112002KQ(CHIPS)':
 'VSS32': CDS_PINID='VSS32';
NODE_NAME     J20 77
 '@T6G_MB_LIB.T6G(SCH_1):PAGE95_I177@PURE_QUANTA.SCONN288_DDR506112002KQ(CHIPS)':
 'VSS33': CDS_PINID='VSS33';
NODE_NAME     J20 79
 '@T6G_MB_LIB.T6G(SCH_1):PAGE95_I177@PURE_QUANTA.SCONN288_DDR506112002KQ(CHIPS)':
 'VSS34': CDS_PINID='VSS34';
NODE_NAME     J20 81
 '@T6G_MB_LIB.T6G(SCH_1):PAGE95_I177@PURE_QUANTA.SCONN288_DDR506112002KQ(CHIPS)':
 'VSS35': CDS_PINID='VSS35';
NODE_NAME     J20 83
 '@T6G_MB_LIB.T6G(SCH_1):PAGE95_I177@PURE_QUANTA.SCONN288_DDR506112002KQ(CHIPS)':
 'VSS36': CDS_PINID='VSS36';
NODE_NAME     J20 85
 '@T6G_MB_LIB.T6G(SCH_1):PAGE95_I177@PURE_QUANTA.SCONN288_DDR506112002KQ(CHIPS)':
 'VSS37': CDS_PINID='VSS37';
NODE_NAME     J20 88
 '@T6G_MB_LIB.T6G(SCH_1):PAGE95_I177@PURE_QUANTA.SCONN288_DDR506112002KQ(CHIPS)':
 'VSS38': CDS_PINID='VSS38';
NODE_NAME     J20 90
 '@T6G_MB_LIB.T6G(SCH_1):PAGE95_I177@PURE_QUANTA.SCONN288_DDR506112002KQ(CHIPS)':
 'VSS39': CDS_PINID='VSS39';
NODE_NAME     J20 92
 '@T6G_MB_LIB.T6G(SCH_1):PAGE95_I177@PURE_QUANTA.SCONN288_DDR506112002KQ(CHIPS)':
 'VSS40': CDS_PINID='VSS40';
NODE_NAME     J20 95
 '@T6G_MB_LIB.T6G(SCH_1):PAGE95_I177@PURE_QUANTA.SCONN288_DDR506112002KQ(CHIPS)':
 'VSS41': CDS_PINID='VSS41';
NODE_NAME     J20 97
 '@T6G_MB_LIB.T6G(SCH_1):PAGE95_I177@PURE_QUANTA.SCONN288_DDR506112002KQ(CHIPS)':
 'VSS42': CDS_PINID='VSS42';
NODE_NAME     J20 99
 '@T6G_MB_LIB.T6G(SCH_1):PAGE95_I177@PURE_QUANTA.SCONN288_DDR506112002KQ(CHIPS)':
 'VSS43': CDS_PINID='VSS43';
NODE_NAME     J20 101
 '@T6G_MB_LIB.T6G(SCH_1):PAGE95_I177@PURE_QUANTA.SCONN288_DDR506112002KQ(CHIPS)':
 'VSS44': CDS_PINID='VSS44';
NODE_NAME     J20 103
 '@T6G_MB_LIB.T6G(SCH_1):PAGE95_I177@PURE_QUANTA.SCONN288_DDR506112002KQ(CHIPS)':
 'VSS45': CDS_PINID='VSS45';
NODE_NAME     J20 106
 '@T6G_MB_LIB.T6G(SCH_1):PAGE95_I177@PURE_QUANTA.SCONN288_DDR506112002KQ(CHIPS)':
 'VSS46': CDS_PINID='VSS46';
NODE_NAME     J20 108
 '@T6G_MB_LIB.T6G(SCH_1):PAGE95_I177@PURE_QUANTA.SCONN288_DDR506112002KQ(CHIPS)':
 'VSS47': CDS_PINID='VSS47';
NODE_NAME     J20 110
 '@T6G_MB_LIB.T6G(SCH_1):PAGE95_I177@PURE_QUANTA.SCONN288_DDR506112002KQ(CHIPS)':
 'VSS48': CDS_PINID='VSS48';
NODE_NAME     J20 112
 '@T6G_MB_LIB.T6G(SCH_1):PAGE95_I177@PURE_QUANTA.SCONN288_DDR506112002KQ(CHIPS)':
 'VSS49': CDS_PINID='VSS49';
NODE_NAME     J20 114
 '@T6G_MB_LIB.T6G(SCH_1):PAGE95_I177@PURE_QUANTA.SCONN288_DDR506112002KQ(CHIPS)':
 'VSS50': CDS_PINID='VSS50';
NODE_NAME     J20 117
 '@T6G_MB_LIB.T6G(SCH_1):PAGE95_I177@PURE_QUANTA.SCONN288_DDR506112002KQ(CHIPS)':
 'VSS51': CDS_PINID='VSS51';
NODE_NAME     J20 119
 '@T6G_MB_LIB.T6G(SCH_1):PAGE95_I177@PURE_QUANTA.SCONN288_DDR506112002KQ(CHIPS)':
 'VSS52': CDS_PINID='VSS52';
NODE_NAME     J20 121
 '@T6G_MB_LIB.T6G(SCH_1):PAGE95_I177@PURE_QUANTA.SCONN288_DDR506112002KQ(CHIPS)':
 'VSS53': CDS_PINID='VSS53';
NODE_NAME     J20 123
 '@T6G_MB_LIB.T6G(SCH_1):PAGE95_I177@PURE_QUANTA.SCONN288_DDR506112002KQ(CHIPS)':
 'VSS54': CDS_PINID='VSS54';
NODE_NAME     J20 125
 '@T6G_MB_LIB.T6G(SCH_1):PAGE95_I177@PURE_QUANTA.SCONN288_DDR506112002KQ(CHIPS)':
 'VSS55': CDS_PINID='VSS55';
NODE_NAME     J20 128
 '@T6G_MB_LIB.T6G(SCH_1):PAGE95_I177@PURE_QUANTA.SCONN288_DDR506112002KQ(CHIPS)':
 'VSS56': CDS_PINID='VSS56';
NODE_NAME     J20 130
 '@T6G_MB_LIB.T6G(SCH_1):PAGE95_I177@PURE_QUANTA.SCONN288_DDR506112002KQ(CHIPS)':
 'VSS57': CDS_PINID='VSS57';
NODE_NAME     J20 132
 '@T6G_MB_LIB.T6G(SCH_1):PAGE95_I177@PURE_QUANTA.SCONN288_DDR506112002KQ(CHIPS)':
 'VSS58': CDS_PINID='VSS58';
NODE_NAME     J20 134
 '@T6G_MB_LIB.T6G(SCH_1):PAGE95_I177@PURE_QUANTA.SCONN288_DDR506112002KQ(CHIPS)':
 'VSS59': CDS_PINID='VSS59';
NODE_NAME     J20 136
 '@T6G_MB_LIB.T6G(SCH_1):PAGE95_I177@PURE_QUANTA.SCONN288_DDR506112002KQ(CHIPS)':
 'VSS60': CDS_PINID='VSS60';
NODE_NAME     J20 139
 '@T6G_MB_LIB.T6G(SCH_1):PAGE95_I177@PURE_QUANTA.SCONN288_DDR506112002KQ(CHIPS)':
 'VSS61': CDS_PINID='VSS61';
NODE_NAME     J20 141
 '@T6G_MB_LIB.T6G(SCH_1):PAGE95_I177@PURE_QUANTA.SCONN288_DDR506112002KQ(CHIPS)':
 'VSS62': CDS_PINID='VSS62';
NODE_NAME     J20 143
 '@T6G_MB_LIB.T6G(SCH_1):PAGE95_I177@PURE_QUANTA.SCONN288_DDR506112002KQ(CHIPS)':
 'VSS63': CDS_PINID='VSS63';
NODE_NAME     J20 151
 '@T6G_MB_LIB.T6G(SCH_1):PAGE95_I177@PURE_QUANTA.SCONN288_DDR506112002KQ(CHIPS)':
 'VSS64': CDS_PINID='VSS64';
NODE_NAME     J20 153
 '@T6G_MB_LIB.T6G(SCH_1):PAGE95_I177@PURE_QUANTA.SCONN288_DDR506112002KQ(CHIPS)':
 'VSS65': CDS_PINID='VSS65';
NODE_NAME     J20 155
 '@T6G_MB_LIB.T6G(SCH_1):PAGE95_I177@PURE_QUANTA.SCONN288_DDR506112002KQ(CHIPS)':
 'VSS66': CDS_PINID='VSS66';
NODE_NAME     J20 158
 '@T6G_MB_LIB.T6G(SCH_1):PAGE95_I177@PURE_QUANTA.SCONN288_DDR506112002KQ(CHIPS)':
 'VSS67': CDS_PINID='VSS67';
NODE_NAME     J20 160
 '@T6G_MB_LIB.T6G(SCH_1):PAGE95_I177@PURE_QUANTA.SCONN288_DDR506112002KQ(CHIPS)':
 'VSS68': CDS_PINID='VSS68';
NODE_NAME     J20 162
 '@T6G_MB_LIB.T6G(SCH_1):PAGE95_I177@PURE_QUANTA.SCONN288_DDR506112002KQ(CHIPS)':
 'VSS69': CDS_PINID='VSS69';
NODE_NAME     J20 164
 '@T6G_MB_LIB.T6G(SCH_1):PAGE95_I177@PURE_QUANTA.SCONN288_DDR506112002KQ(CHIPS)':
 'VSS70': CDS_PINID='VSS70';
NODE_NAME     J20 166
 '@T6G_MB_LIB.T6G(SCH_1):PAGE95_I177@PURE_QUANTA.SCONN288_DDR506112002KQ(CHIPS)':
 'VSS71': CDS_PINID='VSS71';
NODE_NAME     J20 169
 '@T6G_MB_LIB.T6G(SCH_1):PAGE95_I177@PURE_QUANTA.SCONN288_DDR506112002KQ(CHIPS)':
 'VSS72': CDS_PINID='VSS72';
NODE_NAME     J20 171
 '@T6G_MB_LIB.T6G(SCH_1):PAGE95_I177@PURE_QUANTA.SCONN288_DDR506112002KQ(CHIPS)':
 'VSS73': CDS_PINID='VSS73';
NODE_NAME     J20 173
 '@T6G_MB_LIB.T6G(SCH_1):PAGE95_I177@PURE_QUANTA.SCONN288_DDR506112002KQ(CHIPS)':
 'VSS74': CDS_PINID='VSS74';
NODE_NAME     J20 175
 '@T6G_MB_LIB.T6G(SCH_1):PAGE95_I177@PURE_QUANTA.SCONN288_DDR506112002KQ(CHIPS)':
 'VSS75': CDS_PINID='VSS75';
NODE_NAME     J20 177
 '@T6G_MB_LIB.T6G(SCH_1):PAGE95_I177@PURE_QUANTA.SCONN288_DDR506112002KQ(CHIPS)':
 'VSS76': CDS_PINID='VSS76';
NODE_NAME     J20 180
 '@T6G_MB_LIB.T6G(SCH_1):PAGE95_I177@PURE_QUANTA.SCONN288_DDR506112002KQ(CHIPS)':
 'VSS77': CDS_PINID='VSS77';
NODE_NAME     J20 182
 '@T6G_MB_LIB.T6G(SCH_1):PAGE95_I177@PURE_QUANTA.SCONN288_DDR506112002KQ(CHIPS)':
 'VSS78': CDS_PINID='VSS78';
NODE_NAME     J20 184
 '@T6G_MB_LIB.T6G(SCH_1):PAGE95_I177@PURE_QUANTA.SCONN288_DDR506112002KQ(CHIPS)':
 'VSS79': CDS_PINID='VSS79';
NODE_NAME     J20 186
 '@T6G_MB_LIB.T6G(SCH_1):PAGE95_I177@PURE_QUANTA.SCONN288_DDR506112002KQ(CHIPS)':
 'VSS80': CDS_PINID='VSS80';
NODE_NAME     J20 188
 '@T6G_MB_LIB.T6G(SCH_1):PAGE95_I177@PURE_QUANTA.SCONN288_DDR506112002KQ(CHIPS)':
 'VSS81': CDS_PINID='VSS81';
NODE_NAME     J20 191
 '@T6G_MB_LIB.T6G(SCH_1):PAGE95_I177@PURE_QUANTA.SCONN288_DDR506112002KQ(CHIPS)':
 'VSS82': CDS_PINID='VSS82';
NODE_NAME     J20 193
 '@T6G_MB_LIB.T6G(SCH_1):PAGE95_I177@PURE_QUANTA.SCONN288_DDR506112002KQ(CHIPS)':
 'VSS83': CDS_PINID='VSS83';
NODE_NAME     J20 195
 '@T6G_MB_LIB.T6G(SCH_1):PAGE95_I177@PURE_QUANTA.SCONN288_DDR506112002KQ(CHIPS)':
 'VSS84': CDS_PINID='VSS84';
NODE_NAME     J20 197
 '@T6G_MB_LIB.T6G(SCH_1):PAGE95_I177@PURE_QUANTA.SCONN288_DDR506112002KQ(CHIPS)':
 'VSS85': CDS_PINID='VSS85';
NODE_NAME     J20 199
 '@T6G_MB_LIB.T6G(SCH_1):PAGE95_I177@PURE_QUANTA.SCONN288_DDR506112002KQ(CHIPS)':
 'VSS86': CDS_PINID='VSS86';
NODE_NAME     J20 202
 '@T6G_MB_LIB.T6G(SCH_1):PAGE95_I177@PURE_QUANTA.SCONN288_DDR506112002KQ(CHIPS)':
 'VSS87': CDS_PINID='VSS87';
NODE_NAME     J20 204
 '@T6G_MB_LIB.T6G(SCH_1):PAGE95_I177@PURE_QUANTA.SCONN288_DDR506112002KQ(CHIPS)':
 'VSS88': CDS_PINID='VSS88';
NODE_NAME     J20 206
 '@T6G_MB_LIB.T6G(SCH_1):PAGE95_I177@PURE_QUANTA.SCONN288_DDR506112002KQ(CHIPS)':
 'VSS89': CDS_PINID='VSS89';
NODE_NAME     J20 208
 '@T6G_MB_LIB.T6G(SCH_1):PAGE95_I177@PURE_QUANTA.SCONN288_DDR506112002KQ(CHIPS)':
 'VSS90': CDS_PINID='VSS90';
NODE_NAME     J20 210
 '@T6G_MB_LIB.T6G(SCH_1):PAGE95_I177@PURE_QUANTA.SCONN288_DDR506112002KQ(CHIPS)':
 'VSS91': CDS_PINID='VSS91';
NODE_NAME     J20 212
 '@T6G_MB_LIB.T6G(SCH_1):PAGE95_I177@PURE_QUANTA.SCONN288_DDR506112002KQ(CHIPS)':
 'VSS92': CDS_PINID='VSS92';
NODE_NAME     J20 214
 '@T6G_MB_LIB.T6G(SCH_1):PAGE95_I177@PURE_QUANTA.SCONN288_DDR506112002KQ(CHIPS)':
 'VSS93': CDS_PINID='VSS93';
NODE_NAME     J20 216
 '@T6G_MB_LIB.T6G(SCH_1):PAGE95_I177@PURE_QUANTA.SCONN288_DDR506112002KQ(CHIPS)':
 'VSS94': CDS_PINID='VSS94';
NODE_NAME     J20 219
 '@T6G_MB_LIB.T6G(SCH_1):PAGE95_I177@PURE_QUANTA.SCONN288_DDR506112002KQ(CHIPS)':
 'VSS95': CDS_PINID='VSS95';
NODE_NAME     J20 222
 '@T6G_MB_LIB.T6G(SCH_1):PAGE95_I177@PURE_QUANTA.SCONN288_DDR506112002KQ(CHIPS)':
 'VSS96': CDS_PINID='VSS96';
NODE_NAME     J20 224
 '@T6G_MB_LIB.T6G(SCH_1):PAGE95_I177@PURE_QUANTA.SCONN288_DDR506112002KQ(CHIPS)':
 'VSS97': CDS_PINID='VSS97';
NODE_NAME     J20 226
 '@T6G_MB_LIB.T6G(SCH_1):PAGE95_I177@PURE_QUANTA.SCONN288_DDR506112002KQ(CHIPS)':
 'VSS98': CDS_PINID='VSS98';
NODE_NAME     J20 228
 '@T6G_MB_LIB.T6G(SCH_1):PAGE95_I177@PURE_QUANTA.SCONN288_DDR506112002KQ(CHIPS)':
 'VSS99': CDS_PINID='VSS99';
NODE_NAME     J20 230
 '@T6G_MB_LIB.T6G(SCH_1):PAGE95_I177@PURE_QUANTA.SCONN288_DDR506112002KQ(CHIPS)':
 'VSS100': CDS_PINID='VSS100';
NODE_NAME     J20 233
 '@T6G_MB_LIB.T6G(SCH_1):PAGE95_I177@PURE_QUANTA.SCONN288_DDR506112002KQ(CHIPS)':
 'VSS101': CDS_PINID='VSS101';
NODE_NAME     J20 235
 '@T6G_MB_LIB.T6G(SCH_1):PAGE95_I177@PURE_QUANTA.SCONN288_DDR506112002KQ(CHIPS)':
 'VSS102': CDS_PINID='VSS102';
NODE_NAME     J20 237
 '@T6G_MB_LIB.T6G(SCH_1):PAGE95_I177@PURE_QUANTA.SCONN288_DDR506112002KQ(CHIPS)':
 'VSS103': CDS_PINID='VSS103';
NODE_NAME     J20 240
 '@T6G_MB_LIB.T6G(SCH_1):PAGE95_I177@PURE_QUANTA.SCONN288_DDR506112002KQ(CHIPS)':
 'VSS104': CDS_PINID='VSS104';
NODE_NAME     J20 242
 '@T6G_MB_LIB.T6G(SCH_1):PAGE95_I177@PURE_QUANTA.SCONN288_DDR506112002KQ(CHIPS)':
 'VSS105': CDS_PINID='VSS105';
NODE_NAME     J20 244
 '@T6G_MB_LIB.T6G(SCH_1):PAGE95_I177@PURE_QUANTA.SCONN288_DDR506112002KQ(CHIPS)':
 'VSS106': CDS_PINID='VSS106';
NODE_NAME     J20 246
 '@T6G_MB_LIB.T6G(SCH_1):PAGE95_I177@PURE_QUANTA.SCONN288_DDR506112002KQ(CHIPS)':
 'VSS107': CDS_PINID='VSS107';
NODE_NAME     J20 248
 '@T6G_MB_LIB.T6G(SCH_1):PAGE95_I177@PURE_QUANTA.SCONN288_DDR506112002KQ(CHIPS)':
 'VSS108': CDS_PINID='VSS108';
NODE_NAME     J20 251
 '@T6G_MB_LIB.T6G(SCH_1):PAGE95_I177@PURE_QUANTA.SCONN288_DDR506112002KQ(CHIPS)':
 'VSS109': CDS_PINID='VSS109';
NODE_NAME     J20 253
 '@T6G_MB_LIB.T6G(SCH_1):PAGE95_I177@PURE_QUANTA.SCONN288_DDR506112002KQ(CHIPS)':
 'VSS110': CDS_PINID='VSS110';
NODE_NAME     J20 255
 '@T6G_MB_LIB.T6G(SCH_1):PAGE95_I177@PURE_QUANTA.SCONN288_DDR506112002KQ(CHIPS)':
 'VSS111': CDS_PINID='VSS111';
NODE_NAME     J20 257
 '@T6G_MB_LIB.T6G(SCH_1):PAGE95_I177@PURE_QUANTA.SCONN288_DDR506112002KQ(CHIPS)':
 'VSS112': CDS_PINID='VSS112';
NODE_NAME     J20 259
 '@T6G_MB_LIB.T6G(SCH_1):PAGE95_I177@PURE_QUANTA.SCONN288_DDR506112002KQ(CHIPS)':
 'VSS113': CDS_PINID='VSS113';
NODE_NAME     J20 262
 '@T6G_MB_LIB.T6G(SCH_1):PAGE95_I177@PURE_QUANTA.SCONN288_DDR506112002KQ(CHIPS)':
 'VSS114': CDS_PINID='VSS114';
NODE_NAME     J20 264
 '@T6G_MB_LIB.T6G(SCH_1):PAGE95_I177@PURE_QUANTA.SCONN288_DDR506112002KQ(CHIPS)':
 'VSS115': CDS_PINID='VSS115';
NODE_NAME     J20 266
 '@T6G_MB_LIB.T6G(SCH_1):PAGE95_I177@PURE_QUANTA.SCONN288_DDR506112002KQ(CHIPS)':
 'VSS116': CDS_PINID='VSS116';
NODE_NAME     J20 268
 '@T6G_MB_LIB.T6G(SCH_1):PAGE95_I177@PURE_QUANTA.SCONN288_DDR506112002KQ(CHIPS)':
 'VSS117': CDS_PINID='VSS117';
NODE_NAME     J20 270
 '@T6G_MB_LIB.T6G(SCH_1):PAGE95_I177@PURE_QUANTA.SCONN288_DDR506112002KQ(CHIPS)':
 'VSS118': CDS_PINID='VSS118';
NODE_NAME     J20 273
 '@T6G_MB_LIB.T6G(SCH_1):PAGE95_I177@PURE_QUANTA.SCONN288_DDR506112002KQ(CHIPS)':
 'VSS119': CDS_PINID='VSS119';
NODE_NAME     J20 275
 '@T6G_MB_LIB.T6G(SCH_1):PAGE95_I177@PURE_QUANTA.SCONN288_DDR506112002KQ(CHIPS)':
 'VSS120': CDS_PINID='VSS120';
NODE_NAME     J20 277
 '@T6G_MB_LIB.T6G(SCH_1):PAGE95_I177@PURE_QUANTA.SCONN288_DDR506112002KQ(CHIPS)':
 'VSS121': CDS_PINID='VSS121';
NODE_NAME     J20 279
 '@T6G_MB_LIB.T6G(SCH_1):PAGE95_I177@PURE_QUANTA.SCONN288_DDR506112002KQ(CHIPS)':
 'VSS122': CDS_PINID='VSS122';
NODE_NAME     J20 281
 '@T6G_MB_LIB.T6G(SCH_1):PAGE95_I177@PURE_QUANTA.SCONN288_DDR506112002KQ(CHIPS)':
 'VSS123': CDS_PINID='VSS123';
NODE_NAME     J20 284
 '@T6G_MB_LIB.T6G(SCH_1):PAGE95_I177@PURE_QUANTA.SCONN288_DDR506112002KQ(CHIPS)':
 'VSS124': CDS_PINID='VSS124';
NODE_NAME     J20 286
 '@T6G_MB_LIB.T6G(SCH_1):PAGE95_I177@PURE_QUANTA.SCONN288_DDR506112002KQ(CHIPS)':
 'VSS125': CDS_PINID='VSS125';
NODE_NAME     J20 288
 '@T6G_MB_LIB.T6G(SCH_1):PAGE95_I177@PURE_QUANTA.SCONN288_DDR506112002KQ(CHIPS)':
 'VSS126': CDS_PINID='VSS126';
NODE_NAME     C128 2
 '@T6G_MB_LIB.T6G(SCH_1):PAGE95_I185@PURE_QUANTA.Q_CAP(CHIPS)':
 'B': CDS_PINID='B';
NODE_NAME     C167 2
 '@T6G_MB_LIB.T6G(SCH_1):PAGE95_I238@PURE_QUANTA.Q_CAP(CHIPS)':
 'B': CDS_PINID='B';
NODE_NAME     C169 2
 '@T6G_MB_LIB.T6G(SCH_1):PAGE95_I239@PURE_QUANTA.Q_CAP(CHIPS)':
 'B': CDS_PINID='B';
NODE_NAME     R769 2
 '@T6G_MB_LIB.T6G(SCH_1):PAGE96_I127@PURE_QUANTA.Q_RES(CHIPS)':
 'B': CDS_PINID='B';
NODE_NAME     J67 G1
 '@T6G_MB_LIB.T6G(SCH_1):PAGE96_I140@PURE_QUANTA.SCONN288_DDR506112002KQ(CHIPS)':
 'G1': CDS_PINID='G1';
NODE_NAME     J67 G2
 '@T6G_MB_LIB.T6G(SCH_1):PAGE96_I140@PURE_QUANTA.SCONN288_DDR506112002KQ(CHIPS)':
 'G2': CDS_PINID='G2';
NODE_NAME     J67 G3
 '@T6G_MB_LIB.T6G(SCH_1):PAGE96_I140@PURE_QUANTA.SCONN288_DDR506112002KQ(CHIPS)':
 'G3': CDS_PINID='G3';
NODE_NAME     J67 6
 '@T6G_MB_LIB.T6G(SCH_1):PAGE96_I140@PURE_QUANTA.SCONN288_DDR506112002KQ(CHIPS)':
 'VSS0': CDS_PINID='VSS0';
NODE_NAME     J67 8
 '@T6G_MB_LIB.T6G(SCH_1):PAGE96_I140@PURE_QUANTA.SCONN288_DDR506112002KQ(CHIPS)':
 'VSS1': CDS_PINID='VSS1';
NODE_NAME     J67 10
 '@T6G_MB_LIB.T6G(SCH_1):PAGE96_I140@PURE_QUANTA.SCONN288_DDR506112002KQ(CHIPS)':
 'VSS2': CDS_PINID='VSS2';
NODE_NAME     J67 13
 '@T6G_MB_LIB.T6G(SCH_1):PAGE96_I140@PURE_QUANTA.SCONN288_DDR506112002KQ(CHIPS)':
 'VSS3': CDS_PINID='VSS3';
NODE_NAME     J67 15
 '@T6G_MB_LIB.T6G(SCH_1):PAGE96_I140@PURE_QUANTA.SCONN288_DDR506112002KQ(CHIPS)':
 'VSS4': CDS_PINID='VSS4';
NODE_NAME     J67 17
 '@T6G_MB_LIB.T6G(SCH_1):PAGE96_I140@PURE_QUANTA.SCONN288_DDR506112002KQ(CHIPS)':
 'VSS5': CDS_PINID='VSS5';
NODE_NAME     J67 19
 '@T6G_MB_LIB.T6G(SCH_1):PAGE96_I140@PURE_QUANTA.SCONN288_DDR506112002KQ(CHIPS)':
 'VSS6': CDS_PINID='VSS6';
NODE_NAME     J67 21
 '@T6G_MB_LIB.T6G(SCH_1):PAGE96_I140@PURE_QUANTA.SCONN288_DDR506112002KQ(CHIPS)':
 'VSS7': CDS_PINID='VSS7';
NODE_NAME     J67 24
 '@T6G_MB_LIB.T6G(SCH_1):PAGE96_I140@PURE_QUANTA.SCONN288_DDR506112002KQ(CHIPS)':
 'VSS8': CDS_PINID='VSS8';
NODE_NAME     J67 26
 '@T6G_MB_LIB.T6G(SCH_1):PAGE96_I140@PURE_QUANTA.SCONN288_DDR506112002KQ(CHIPS)':
 'VSS9': CDS_PINID='VSS9';
NODE_NAME     J67 28
 '@T6G_MB_LIB.T6G(SCH_1):PAGE96_I140@PURE_QUANTA.SCONN288_DDR506112002KQ(CHIPS)':
 'VSS10': CDS_PINID='VSS10';
NODE_NAME     J67 30
 '@T6G_MB_LIB.T6G(SCH_1):PAGE96_I140@PURE_QUANTA.SCONN288_DDR506112002KQ(CHIPS)':
 'VSS11': CDS_PINID='VSS11';
NODE_NAME     J67 32
 '@T6G_MB_LIB.T6G(SCH_1):PAGE96_I140@PURE_QUANTA.SCONN288_DDR506112002KQ(CHIPS)':
 'VSS12': CDS_PINID='VSS12';
NODE_NAME     J67 35
 '@T6G_MB_LIB.T6G(SCH_1):PAGE96_I140@PURE_QUANTA.SCONN288_DDR506112002KQ(CHIPS)':
 'VSS13': CDS_PINID='VSS13';
NODE_NAME     J67 37
 '@T6G_MB_LIB.T6G(SCH_1):PAGE96_I140@PURE_QUANTA.SCONN288_DDR506112002KQ(CHIPS)':
 'VSS14': CDS_PINID='VSS14';
NODE_NAME     J67 39
 '@T6G_MB_LIB.T6G(SCH_1):PAGE96_I140@PURE_QUANTA.SCONN288_DDR506112002KQ(CHIPS)':
 'VSS15': CDS_PINID='VSS15';
NODE_NAME     J67 41
 '@T6G_MB_LIB.T6G(SCH_1):PAGE96_I140@PURE_QUANTA.SCONN288_DDR506112002KQ(CHIPS)':
 'VSS16': CDS_PINID='VSS16';
NODE_NAME     J67 43
 '@T6G_MB_LIB.T6G(SCH_1):PAGE96_I140@PURE_QUANTA.SCONN288_DDR506112002KQ(CHIPS)':
 'VSS17': CDS_PINID='VSS17';
NODE_NAME     J67 46
 '@T6G_MB_LIB.T6G(SCH_1):PAGE96_I140@PURE_QUANTA.SCONN288_DDR506112002KQ(CHIPS)':
 'VSS18': CDS_PINID='VSS18';
NODE_NAME     J67 48
 '@T6G_MB_LIB.T6G(SCH_1):PAGE96_I140@PURE_QUANTA.SCONN288_DDR506112002KQ(CHIPS)':
 'VSS19': CDS_PINID='VSS19';
NODE_NAME     J67 50
 '@T6G_MB_LIB.T6G(SCH_1):PAGE96_I140@PURE_QUANTA.SCONN288_DDR506112002KQ(CHIPS)':
 'VSS20': CDS_PINID='VSS20';
NODE_NAME     J67 52
 '@T6G_MB_LIB.T6G(SCH_1):PAGE96_I140@PURE_QUANTA.SCONN288_DDR506112002KQ(CHIPS)':
 'VSS21': CDS_PINID='VSS21';
NODE_NAME     J67 54
 '@T6G_MB_LIB.T6G(SCH_1):PAGE96_I140@PURE_QUANTA.SCONN288_DDR506112002KQ(CHIPS)':
 'VSS22': CDS_PINID='VSS22';
NODE_NAME     J67 57
 '@T6G_MB_LIB.T6G(SCH_1):PAGE96_I140@PURE_QUANTA.SCONN288_DDR506112002KQ(CHIPS)':
 'VSS23': CDS_PINID='VSS23';
NODE_NAME     J67 59
 '@T6G_MB_LIB.T6G(SCH_1):PAGE96_I140@PURE_QUANTA.SCONN288_DDR506112002KQ(CHIPS)':
 'VSS24': CDS_PINID='VSS24';
NODE_NAME     J67 61
 '@T6G_MB_LIB.T6G(SCH_1):PAGE96_I140@PURE_QUANTA.SCONN288_DDR506112002KQ(CHIPS)':
 'VSS25': CDS_PINID='VSS25';
NODE_NAME     J67 63
 '@T6G_MB_LIB.T6G(SCH_1):PAGE96_I140@PURE_QUANTA.SCONN288_DDR506112002KQ(CHIPS)':
 'VSS26': CDS_PINID='VSS26';
NODE_NAME     J67 65
 '@T6G_MB_LIB.T6G(SCH_1):PAGE96_I140@PURE_QUANTA.SCONN288_DDR506112002KQ(CHIPS)':
 'VSS27': CDS_PINID='VSS27';
NODE_NAME     J67 67
 '@T6G_MB_LIB.T6G(SCH_1):PAGE96_I140@PURE_QUANTA.SCONN288_DDR506112002KQ(CHIPS)':
 'VSS28': CDS_PINID='VSS28';
NODE_NAME     J67 69
 '@T6G_MB_LIB.T6G(SCH_1):PAGE96_I140@PURE_QUANTA.SCONN288_DDR506112002KQ(CHIPS)':
 'VSS29': CDS_PINID='VSS29';
NODE_NAME     J67 71
 '@T6G_MB_LIB.T6G(SCH_1):PAGE96_I140@PURE_QUANTA.SCONN288_DDR506112002KQ(CHIPS)':
 'VSS30': CDS_PINID='VSS30';
NODE_NAME     J67 73
 '@T6G_MB_LIB.T6G(SCH_1):PAGE96_I140@PURE_QUANTA.SCONN288_DDR506112002KQ(CHIPS)':
 'VSS31': CDS_PINID='VSS31';
NODE_NAME     J67 75
 '@T6G_MB_LIB.T6G(SCH_1):PAGE96_I140@PURE_QUANTA.SCONN288_DDR506112002KQ(CHIPS)':
 'VSS32': CDS_PINID='VSS32';
NODE_NAME     J67 77
 '@T6G_MB_LIB.T6G(SCH_1):PAGE96_I140@PURE_QUANTA.SCONN288_DDR506112002KQ(CHIPS)':
 'VSS33': CDS_PINID='VSS33';
NODE_NAME     J67 79
 '@T6G_MB_LIB.T6G(SCH_1):PAGE96_I140@PURE_QUANTA.SCONN288_DDR506112002KQ(CHIPS)':
 'VSS34': CDS_PINID='VSS34';
NODE_NAME     J67 81
 '@T6G_MB_LIB.T6G(SCH_1):PAGE96_I140@PURE_QUANTA.SCONN288_DDR506112002KQ(CHIPS)':
 'VSS35': CDS_PINID='VSS35';
NODE_NAME     J67 83
 '@T6G_MB_LIB.T6G(SCH_1):PAGE96_I140@PURE_QUANTA.SCONN288_DDR506112002KQ(CHIPS)':
 'VSS36': CDS_PINID='VSS36';
NODE_NAME     J67 85
 '@T6G_MB_LIB.T6G(SCH_1):PAGE96_I140@PURE_QUANTA.SCONN288_DDR506112002KQ(CHIPS)':
 'VSS37': CDS_PINID='VSS37';
NODE_NAME     J67 88
 '@T6G_MB_LIB.T6G(SCH_1):PAGE96_I140@PURE_QUANTA.SCONN288_DDR506112002KQ(CHIPS)':
 'VSS38': CDS_PINID='VSS38';
NODE_NAME     J67 90
 '@T6G_MB_LIB.T6G(SCH_1):PAGE96_I140@PURE_QUANTA.SCONN288_DDR506112002KQ(CHIPS)':
 'VSS39': CDS_PINID='VSS39';
NODE_NAME     J67 92
 '@T6G_MB_LIB.T6G(SCH_1):PAGE96_I140@PURE_QUANTA.SCONN288_DDR506112002KQ(CHIPS)':
 'VSS40': CDS_PINID='VSS40';
NODE_NAME     J67 95
 '@T6G_MB_LIB.T6G(SCH_1):PAGE96_I140@PURE_QUANTA.SCONN288_DDR506112002KQ(CHIPS)':
 'VSS41': CDS_PINID='VSS41';
NODE_NAME     J67 97
 '@T6G_MB_LIB.T6G(SCH_1):PAGE96_I140@PURE_QUANTA.SCONN288_DDR506112002KQ(CHIPS)':
 'VSS42': CDS_PINID='VSS42';
NODE_NAME     J67 99
 '@T6G_MB_LIB.T6G(SCH_1):PAGE96_I140@PURE_QUANTA.SCONN288_DDR506112002KQ(CHIPS)':
 'VSS43': CDS_PINID='VSS43';
NODE_NAME     J67 101
 '@T6G_MB_LIB.T6G(SCH_1):PAGE96_I140@PURE_QUANTA.SCONN288_DDR506112002KQ(CHIPS)':
 'VSS44': CDS_PINID='VSS44';
NODE_NAME     J67 103
 '@T6G_MB_LIB.T6G(SCH_1):PAGE96_I140@PURE_QUANTA.SCONN288_DDR506112002KQ(CHIPS)':
 'VSS45': CDS_PINID='VSS45';
NODE_NAME     J67 106
 '@T6G_MB_LIB.T6G(SCH_1):PAGE96_I140@PURE_QUANTA.SCONN288_DDR506112002KQ(CHIPS)':
 'VSS46': CDS_PINID='VSS46';
NODE_NAME     J67 108
 '@T6G_MB_LIB.T6G(SCH_1):PAGE96_I140@PURE_QUANTA.SCONN288_DDR506112002KQ(CHIPS)':
 'VSS47': CDS_PINID='VSS47';
NODE_NAME     J67 110
 '@T6G_MB_LIB.T6G(SCH_1):PAGE96_I140@PURE_QUANTA.SCONN288_DDR506112002KQ(CHIPS)':
 'VSS48': CDS_PINID='VSS48';
NODE_NAME     J67 112
 '@T6G_MB_LIB.T6G(SCH_1):PAGE96_I140@PURE_QUANTA.SCONN288_DDR506112002KQ(CHIPS)':
 'VSS49': CDS_PINID='VSS49';
NODE_NAME     J67 114
 '@T6G_MB_LIB.T6G(SCH_1):PAGE96_I140@PURE_QUANTA.SCONN288_DDR506112002KQ(CHIPS)':
 'VSS50': CDS_PINID='VSS50';
NODE_NAME     J67 117
 '@T6G_MB_LIB.T6G(SCH_1):PAGE96_I140@PURE_QUANTA.SCONN288_DDR506112002KQ(CHIPS)':
 'VSS51': CDS_PINID='VSS51';
NODE_NAME     J67 119
 '@T6G_MB_LIB.T6G(SCH_1):PAGE96_I140@PURE_QUANTA.SCONN288_DDR506112002KQ(CHIPS)':
 'VSS52': CDS_PINID='VSS52';
NODE_NAME     J67 121
 '@T6G_MB_LIB.T6G(SCH_1):PAGE96_I140@PURE_QUANTA.SCONN288_DDR506112002KQ(CHIPS)':
 'VSS53': CDS_PINID='VSS53';
NODE_NAME     J67 123
 '@T6G_MB_LIB.T6G(SCH_1):PAGE96_I140@PURE_QUANTA.SCONN288_DDR506112002KQ(CHIPS)':
 'VSS54': CDS_PINID='VSS54';
NODE_NAME     J67 125
 '@T6G_MB_LIB.T6G(SCH_1):PAGE96_I140@PURE_QUANTA.SCONN288_DDR506112002KQ(CHIPS)':
 'VSS55': CDS_PINID='VSS55';
NODE_NAME     J67 128
 '@T6G_MB_LIB.T6G(SCH_1):PAGE96_I140@PURE_QUANTA.SCONN288_DDR506112002KQ(CHIPS)':
 'VSS56': CDS_PINID='VSS56';
NODE_NAME     J67 130
 '@T6G_MB_LIB.T6G(SCH_1):PAGE96_I140@PURE_QUANTA.SCONN288_DDR506112002KQ(CHIPS)':
 'VSS57': CDS_PINID='VSS57';
NODE_NAME     J67 132
 '@T6G_MB_LIB.T6G(SCH_1):PAGE96_I140@PURE_QUANTA.SCONN288_DDR506112002KQ(CHIPS)':
 'VSS58': CDS_PINID='VSS58';
NODE_NAME     J67 134
 '@T6G_MB_LIB.T6G(SCH_1):PAGE96_I140@PURE_QUANTA.SCONN288_DDR506112002KQ(CHIPS)':
 'VSS59': CDS_PINID='VSS59';
NODE_NAME     J67 136
 '@T6G_MB_LIB.T6G(SCH_1):PAGE96_I140@PURE_QUANTA.SCONN288_DDR506112002KQ(CHIPS)':
 'VSS60': CDS_PINID='VSS60';
NODE_NAME     J67 139
 '@T6G_MB_LIB.T6G(SCH_1):PAGE96_I140@PURE_QUANTA.SCONN288_DDR506112002KQ(CHIPS)':
 'VSS61': CDS_PINID='VSS61';
NODE_NAME     J67 141
 '@T6G_MB_LIB.T6G(SCH_1):PAGE96_I140@PURE_QUANTA.SCONN288_DDR506112002KQ(CHIPS)':
 'VSS62': CDS_PINID='VSS62';
NODE_NAME     J67 143
 '@T6G_MB_LIB.T6G(SCH_1):PAGE96_I140@PURE_QUANTA.SCONN288_DDR506112002KQ(CHIPS)':
 'VSS63': CDS_PINID='VSS63';
NODE_NAME     J67 151
 '@T6G_MB_LIB.T6G(SCH_1):PAGE96_I140@PURE_QUANTA.SCONN288_DDR506112002KQ(CHIPS)':
 'VSS64': CDS_PINID='VSS64';
NODE_NAME     J67 153
 '@T6G_MB_LIB.T6G(SCH_1):PAGE96_I140@PURE_QUANTA.SCONN288_DDR506112002KQ(CHIPS)':
 'VSS65': CDS_PINID='VSS65';
NODE_NAME     J67 155
 '@T6G_MB_LIB.T6G(SCH_1):PAGE96_I140@PURE_QUANTA.SCONN288_DDR506112002KQ(CHIPS)':
 'VSS66': CDS_PINID='VSS66';
NODE_NAME     J67 158
 '@T6G_MB_LIB.T6G(SCH_1):PAGE96_I140@PURE_QUANTA.SCONN288_DDR506112002KQ(CHIPS)':
 'VSS67': CDS_PINID='VSS67';
NODE_NAME     J67 160
 '@T6G_MB_LIB.T6G(SCH_1):PAGE96_I140@PURE_QUANTA.SCONN288_DDR506112002KQ(CHIPS)':
 'VSS68': CDS_PINID='VSS68';
NODE_NAME     J67 162
 '@T6G_MB_LIB.T6G(SCH_1):PAGE96_I140@PURE_QUANTA.SCONN288_DDR506112002KQ(CHIPS)':
 'VSS69': CDS_PINID='VSS69';
NODE_NAME     J67 164
 '@T6G_MB_LIB.T6G(SCH_1):PAGE96_I140@PURE_QUANTA.SCONN288_DDR506112002KQ(CHIPS)':
 'VSS70': CDS_PINID='VSS70';
NODE_NAME     J67 166
 '@T6G_MB_LIB.T6G(SCH_1):PAGE96_I140@PURE_QUANTA.SCONN288_DDR506112002KQ(CHIPS)':
 'VSS71': CDS_PINID='VSS71';
NODE_NAME     J67 169
 '@T6G_MB_LIB.T6G(SCH_1):PAGE96_I140@PURE_QUANTA.SCONN288_DDR506112002KQ(CHIPS)':
 'VSS72': CDS_PINID='VSS72';
NODE_NAME     J67 171
 '@T6G_MB_LIB.T6G(SCH_1):PAGE96_I140@PURE_QUANTA.SCONN288_DDR506112002KQ(CHIPS)':
 'VSS73': CDS_PINID='VSS73';
NODE_NAME     J67 173
 '@T6G_MB_LIB.T6G(SCH_1):PAGE96_I140@PURE_QUANTA.SCONN288_DDR506112002KQ(CHIPS)':
 'VSS74': CDS_PINID='VSS74';
NODE_NAME     J67 175
 '@T6G_MB_LIB.T6G(SCH_1):PAGE96_I140@PURE_QUANTA.SCONN288_DDR506112002KQ(CHIPS)':
 'VSS75': CDS_PINID='VSS75';
NODE_NAME     J67 177
 '@T6G_MB_LIB.T6G(SCH_1):PAGE96_I140@PURE_QUANTA.SCONN288_DDR506112002KQ(CHIPS)':
 'VSS76': CDS_PINID='VSS76';
NODE_NAME     J67 180
 '@T6G_MB_LIB.T6G(SCH_1):PAGE96_I140@PURE_QUANTA.SCONN288_DDR506112002KQ(CHIPS)':
 'VSS77': CDS_PINID='VSS77';
NODE_NAME     J67 182
 '@T6G_MB_LIB.T6G(SCH_1):PAGE96_I140@PURE_QUANTA.SCONN288_DDR506112002KQ(CHIPS)':
 'VSS78': CDS_PINID='VSS78';
NODE_NAME     J67 184
 '@T6G_MB_LIB.T6G(SCH_1):PAGE96_I140@PURE_QUANTA.SCONN288_DDR506112002KQ(CHIPS)':
 'VSS79': CDS_PINID='VSS79';
NODE_NAME     J67 186
 '@T6G_MB_LIB.T6G(SCH_1):PAGE96_I140@PURE_QUANTA.SCONN288_DDR506112002KQ(CHIPS)':
 'VSS80': CDS_PINID='VSS80';
NODE_NAME     J67 188
 '@T6G_MB_LIB.T6G(SCH_1):PAGE96_I140@PURE_QUANTA.SCONN288_DDR506112002KQ(CHIPS)':
 'VSS81': CDS_PINID='VSS81';
NODE_NAME     J67 191
 '@T6G_MB_LIB.T6G(SCH_1):PAGE96_I140@PURE_QUANTA.SCONN288_DDR506112002KQ(CHIPS)':
 'VSS82': CDS_PINID='VSS82';
NODE_NAME     J67 193
 '@T6G_MB_LIB.T6G(SCH_1):PAGE96_I140@PURE_QUANTA.SCONN288_DDR506112002KQ(CHIPS)':
 'VSS83': CDS_PINID='VSS83';
NODE_NAME     J67 195
 '@T6G_MB_LIB.T6G(SCH_1):PAGE96_I140@PURE_QUANTA.SCONN288_DDR506112002KQ(CHIPS)':
 'VSS84': CDS_PINID='VSS84';
NODE_NAME     J67 197
 '@T6G_MB_LIB.T6G(SCH_1):PAGE96_I140@PURE_QUANTA.SCONN288_DDR506112002KQ(CHIPS)':
 'VSS85': CDS_PINID='VSS85';
NODE_NAME     J67 199
 '@T6G_MB_LIB.T6G(SCH_1):PAGE96_I140@PURE_QUANTA.SCONN288_DDR506112002KQ(CHIPS)':
 'VSS86': CDS_PINID='VSS86';
NODE_NAME     J67 202
 '@T6G_MB_LIB.T6G(SCH_1):PAGE96_I140@PURE_QUANTA.SCONN288_DDR506112002KQ(CHIPS)':
 'VSS87': CDS_PINID='VSS87';
NODE_NAME     J67 204
 '@T6G_MB_LIB.T6G(SCH_1):PAGE96_I140@PURE_QUANTA.SCONN288_DDR506112002KQ(CHIPS)':
 'VSS88': CDS_PINID='VSS88';
NODE_NAME     J67 206
 '@T6G_MB_LIB.T6G(SCH_1):PAGE96_I140@PURE_QUANTA.SCONN288_DDR506112002KQ(CHIPS)':
 'VSS89': CDS_PINID='VSS89';
NODE_NAME     J67 208
 '@T6G_MB_LIB.T6G(SCH_1):PAGE96_I140@PURE_QUANTA.SCONN288_DDR506112002KQ(CHIPS)':
 'VSS90': CDS_PINID='VSS90';
NODE_NAME     J67 210
 '@T6G_MB_LIB.T6G(SCH_1):PAGE96_I140@PURE_QUANTA.SCONN288_DDR506112002KQ(CHIPS)':
 'VSS91': CDS_PINID='VSS91';
NODE_NAME     J67 212
 '@T6G_MB_LIB.T6G(SCH_1):PAGE96_I140@PURE_QUANTA.SCONN288_DDR506112002KQ(CHIPS)':
 'VSS92': CDS_PINID='VSS92';
NODE_NAME     J67 214
 '@T6G_MB_LIB.T6G(SCH_1):PAGE96_I140@PURE_QUANTA.SCONN288_DDR506112002KQ(CHIPS)':
 'VSS93': CDS_PINID='VSS93';
NODE_NAME     J67 216
 '@T6G_MB_LIB.T6G(SCH_1):PAGE96_I140@PURE_QUANTA.SCONN288_DDR506112002KQ(CHIPS)':
 'VSS94': CDS_PINID='VSS94';
NODE_NAME     J67 219
 '@T6G_MB_LIB.T6G(SCH_1):PAGE96_I140@PURE_QUANTA.SCONN288_DDR506112002KQ(CHIPS)':
 'VSS95': CDS_PINID='VSS95';
NODE_NAME     J67 222
 '@T6G_MB_LIB.T6G(SCH_1):PAGE96_I140@PURE_QUANTA.SCONN288_DDR506112002KQ(CHIPS)':
 'VSS96': CDS_PINID='VSS96';
NODE_NAME     J67 224
 '@T6G_MB_LIB.T6G(SCH_1):PAGE96_I140@PURE_QUANTA.SCONN288_DDR506112002KQ(CHIPS)':
 'VSS97': CDS_PINID='VSS97';
NODE_NAME     J67 226
 '@T6G_MB_LIB.T6G(SCH_1):PAGE96_I140@PURE_QUANTA.SCONN288_DDR506112002KQ(CHIPS)':
 'VSS98': CDS_PINID='VSS98';
NODE_NAME     J67 228
 '@T6G_MB_LIB.T6G(SCH_1):PAGE96_I140@PURE_QUANTA.SCONN288_DDR506112002KQ(CHIPS)':
 'VSS99': CDS_PINID='VSS99';
NODE_NAME     J67 230
 '@T6G_MB_LIB.T6G(SCH_1):PAGE96_I140@PURE_QUANTA.SCONN288_DDR506112002KQ(CHIPS)':
 'VSS100': CDS_PINID='VSS100';
NODE_NAME     J67 233
 '@T6G_MB_LIB.T6G(SCH_1):PAGE96_I140@PURE_QUANTA.SCONN288_DDR506112002KQ(CHIPS)':
 'VSS101': CDS_PINID='VSS101';
NODE_NAME     J67 235
 '@T6G_MB_LIB.T6G(SCH_1):PAGE96_I140@PURE_QUANTA.SCONN288_DDR506112002KQ(CHIPS)':
 'VSS102': CDS_PINID='VSS102';
NODE_NAME     J67 237
 '@T6G_MB_LIB.T6G(SCH_1):PAGE96_I140@PURE_QUANTA.SCONN288_DDR506112002KQ(CHIPS)':
 'VSS103': CDS_PINID='VSS103';
NODE_NAME     J67 240
 '@T6G_MB_LIB.T6G(SCH_1):PAGE96_I140@PURE_QUANTA.SCONN288_DDR506112002KQ(CHIPS)':
 'VSS104': CDS_PINID='VSS104';
NODE_NAME     J67 242
 '@T6G_MB_LIB.T6G(SCH_1):PAGE96_I140@PURE_QUANTA.SCONN288_DDR506112002KQ(CHIPS)':
 'VSS105': CDS_PINID='VSS105';
NODE_NAME     J67 244
 '@T6G_MB_LIB.T6G(SCH_1):PAGE96_I140@PURE_QUANTA.SCONN288_DDR506112002KQ(CHIPS)':
 'VSS106': CDS_PINID='VSS106';
NODE_NAME     J67 246
 '@T6G_MB_LIB.T6G(SCH_1):PAGE96_I140@PURE_QUANTA.SCONN288_DDR506112002KQ(CHIPS)':
 'VSS107': CDS_PINID='VSS107';
NODE_NAME     J67 248
 '@T6G_MB_LIB.T6G(SCH_1):PAGE96_I140@PURE_QUANTA.SCONN288_DDR506112002KQ(CHIPS)':
 'VSS108': CDS_PINID='VSS108';
NODE_NAME     J67 251
 '@T6G_MB_LIB.T6G(SCH_1):PAGE96_I140@PURE_QUANTA.SCONN288_DDR506112002KQ(CHIPS)':
 'VSS109': CDS_PINID='VSS109';
NODE_NAME     J67 253
 '@T6G_MB_LIB.T6G(SCH_1):PAGE96_I140@PURE_QUANTA.SCONN288_DDR506112002KQ(CHIPS)':
 'VSS110': CDS_PINID='VSS110';
NODE_NAME     J67 255
 '@T6G_MB_LIB.T6G(SCH_1):PAGE96_I140@PURE_QUANTA.SCONN288_DDR506112002KQ(CHIPS)':
 'VSS111': CDS_PINID='VSS111';
NODE_NAME     J67 257
 '@T6G_MB_LIB.T6G(SCH_1):PAGE96_I140@PURE_QUANTA.SCONN288_DDR506112002KQ(CHIPS)':
 'VSS112': CDS_PINID='VSS112';
NODE_NAME     J67 259
 '@T6G_MB_LIB.T6G(SCH_1):PAGE96_I140@PURE_QUANTA.SCONN288_DDR506112002KQ(CHIPS)':
 'VSS113': CDS_PINID='VSS113';
NODE_NAME     J67 262
 '@T6G_MB_LIB.T6G(SCH_1):PAGE96_I140@PURE_QUANTA.SCONN288_DDR506112002KQ(CHIPS)':
 'VSS114': CDS_PINID='VSS114';
NODE_NAME     J67 264
 '@T6G_MB_LIB.T6G(SCH_1):PAGE96_I140@PURE_QUANTA.SCONN288_DDR506112002KQ(CHIPS)':
 'VSS115': CDS_PINID='VSS115';
NODE_NAME     J67 266
 '@T6G_MB_LIB.T6G(SCH_1):PAGE96_I140@PURE_QUANTA.SCONN288_DDR506112002KQ(CHIPS)':
 'VSS116': CDS_PINID='VSS116';
NODE_NAME     J67 268
 '@T6G_MB_LIB.T6G(SCH_1):PAGE96_I140@PURE_QUANTA.SCONN288_DDR506112002KQ(CHIPS)':
 'VSS117': CDS_PINID='VSS117';
NODE_NAME     J67 270
 '@T6G_MB_LIB.T6G(SCH_1):PAGE96_I140@PURE_QUANTA.SCONN288_DDR506112002KQ(CHIPS)':
 'VSS118': CDS_PINID='VSS118';
NODE_NAME     J67 273
 '@T6G_MB_LIB.T6G(SCH_1):PAGE96_I140@PURE_QUANTA.SCONN288_DDR506112002KQ(CHIPS)':
 'VSS119': CDS_PINID='VSS119';
NODE_NAME     J67 275
 '@T6G_MB_LIB.T6G(SCH_1):PAGE96_I140@PURE_QUANTA.SCONN288_DDR506112002KQ(CHIPS)':
 'VSS120': CDS_PINID='VSS120';
NODE_NAME     J67 277
 '@T6G_MB_LIB.T6G(SCH_1):PAGE96_I140@PURE_QUANTA.SCONN288_DDR506112002KQ(CHIPS)':
 'VSS121': CDS_PINID='VSS121';
NODE_NAME     J67 279
 '@T6G_MB_LIB.T6G(SCH_1):PAGE96_I140@PURE_QUANTA.SCONN288_DDR506112002KQ(CHIPS)':
 'VSS122': CDS_PINID='VSS122';
NODE_NAME     J67 281
 '@T6G_MB_LIB.T6G(SCH_1):PAGE96_I140@PURE_QUANTA.SCONN288_DDR506112002KQ(CHIPS)':
 'VSS123': CDS_PINID='VSS123';
NODE_NAME     J67 284
 '@T6G_MB_LIB.T6G(SCH_1):PAGE96_I140@PURE_QUANTA.SCONN288_DDR506112002KQ(CHIPS)':
 'VSS124': CDS_PINID='VSS124';
NODE_NAME     J67 286
 '@T6G_MB_LIB.T6G(SCH_1):PAGE96_I140@PURE_QUANTA.SCONN288_DDR506112002KQ(CHIPS)':
 'VSS125': CDS_PINID='VSS125';
NODE_NAME     J67 288
 '@T6G_MB_LIB.T6G(SCH_1):PAGE96_I140@PURE_QUANTA.SCONN288_DDR506112002KQ(CHIPS)':
 'VSS126': CDS_PINID='VSS126';
NODE_NAME     C132 2
 '@T6G_MB_LIB.T6G(SCH_1):PAGE96_I185@PURE_QUANTA.Q_CAP(CHIPS)':
 'B': CDS_PINID='B';
NODE_NAME     C170 2
 '@T6G_MB_LIB.T6G(SCH_1):PAGE96_I238@PURE_QUANTA.Q_CAP(CHIPS)':
 'B': CDS_PINID='B';
NODE_NAME     C171 2
 '@T6G_MB_LIB.T6G(SCH_1):PAGE96_I239@PURE_QUANTA.Q_CAP(CHIPS)':
 'B': CDS_PINID='B';
NODE_NAME     R36 2
 '@T6G_MB_LIB.T6G(SCH_1):PAGE97_I129@PURE_QUANTA.Q_RES(CHIPS)':
 'B':XNET_PINS='2',
 CDS_PINID='B';
NODE_NAME     J24 G1
 '@T6G_MB_LIB.T6G(SCH_1):PAGE97_I177@PURE_QUANTA.SCONN288_DDR506112002KQ(CHIPS)':
 'G1': CDS_PINID='G1';
NODE_NAME     J24 G2
 '@T6G_MB_LIB.T6G(SCH_1):PAGE97_I177@PURE_QUANTA.SCONN288_DDR506112002KQ(CHIPS)':
 'G2': CDS_PINID='G2';
NODE_NAME     J24 G3
 '@T6G_MB_LIB.T6G(SCH_1):PAGE97_I177@PURE_QUANTA.SCONN288_DDR506112002KQ(CHIPS)':
 'G3': CDS_PINID='G3';
NODE_NAME     J24 6
 '@T6G_MB_LIB.T6G(SCH_1):PAGE97_I177@PURE_QUANTA.SCONN288_DDR506112002KQ(CHIPS)':
 'VSS0': CDS_PINID='VSS0';
NODE_NAME     J24 8
 '@T6G_MB_LIB.T6G(SCH_1):PAGE97_I177@PURE_QUANTA.SCONN288_DDR506112002KQ(CHIPS)':
 'VSS1': CDS_PINID='VSS1';
NODE_NAME     J24 10
 '@T6G_MB_LIB.T6G(SCH_1):PAGE97_I177@PURE_QUANTA.SCONN288_DDR506112002KQ(CHIPS)':
 'VSS2': CDS_PINID='VSS2';
NODE_NAME     J24 13
 '@T6G_MB_LIB.T6G(SCH_1):PAGE97_I177@PURE_QUANTA.SCONN288_DDR506112002KQ(CHIPS)':
 'VSS3': CDS_PINID='VSS3';
NODE_NAME     J24 15
 '@T6G_MB_LIB.T6G(SCH_1):PAGE97_I177@PURE_QUANTA.SCONN288_DDR506112002KQ(CHIPS)':
 'VSS4': CDS_PINID='VSS4';
NODE_NAME     J24 17
 '@T6G_MB_LIB.T6G(SCH_1):PAGE97_I177@PURE_QUANTA.SCONN288_DDR506112002KQ(CHIPS)':
 'VSS5': CDS_PINID='VSS5';
NODE_NAME     J24 19
 '@T6G_MB_LIB.T6G(SCH_1):PAGE97_I177@PURE_QUANTA.SCONN288_DDR506112002KQ(CHIPS)':
 'VSS6': CDS_PINID='VSS6';
NODE_NAME     J24 21
 '@T6G_MB_LIB.T6G(SCH_1):PAGE97_I177@PURE_QUANTA.SCONN288_DDR506112002KQ(CHIPS)':
 'VSS7': CDS_PINID='VSS7';
NODE_NAME     J24 24
 '@T6G_MB_LIB.T6G(SCH_1):PAGE97_I177@PURE_QUANTA.SCONN288_DDR506112002KQ(CHIPS)':
 'VSS8': CDS_PINID='VSS8';
NODE_NAME     J24 26
 '@T6G_MB_LIB.T6G(SCH_1):PAGE97_I177@PURE_QUANTA.SCONN288_DDR506112002KQ(CHIPS)':
 'VSS9': CDS_PINID='VSS9';
NODE_NAME     J24 28
 '@T6G_MB_LIB.T6G(SCH_1):PAGE97_I177@PURE_QUANTA.SCONN288_DDR506112002KQ(CHIPS)':
 'VSS10': CDS_PINID='VSS10';
NODE_NAME     J24 30
 '@T6G_MB_LIB.T6G(SCH_1):PAGE97_I177@PURE_QUANTA.SCONN288_DDR506112002KQ(CHIPS)':
 'VSS11': CDS_PINID='VSS11';
NODE_NAME     J24 32
 '@T6G_MB_LIB.T6G(SCH_1):PAGE97_I177@PURE_QUANTA.SCONN288_DDR506112002KQ(CHIPS)':
 'VSS12': CDS_PINID='VSS12';
NODE_NAME     J24 35
 '@T6G_MB_LIB.T6G(SCH_1):PAGE97_I177@PURE_QUANTA.SCONN288_DDR506112002KQ(CHIPS)':
 'VSS13': CDS_PINID='VSS13';
NODE_NAME     J24 37
 '@T6G_MB_LIB.T6G(SCH_1):PAGE97_I177@PURE_QUANTA.SCONN288_DDR506112002KQ(CHIPS)':
 'VSS14': CDS_PINID='VSS14';
NODE_NAME     J24 39
 '@T6G_MB_LIB.T6G(SCH_1):PAGE97_I177@PURE_QUANTA.SCONN288_DDR506112002KQ(CHIPS)':
 'VSS15': CDS_PINID='VSS15';
NODE_NAME     J24 41
 '@T6G_MB_LIB.T6G(SCH_1):PAGE97_I177@PURE_QUANTA.SCONN288_DDR506112002KQ(CHIPS)':
 'VSS16': CDS_PINID='VSS16';
NODE_NAME     J24 43
 '@T6G_MB_LIB.T6G(SCH_1):PAGE97_I177@PURE_QUANTA.SCONN288_DDR506112002KQ(CHIPS)':
 'VSS17': CDS_PINID='VSS17';
NODE_NAME     J24 46
 '@T6G_MB_LIB.T6G(SCH_1):PAGE97_I177@PURE_QUANTA.SCONN288_DDR506112002KQ(CHIPS)':
 'VSS18': CDS_PINID='VSS18';
NODE_NAME     J24 48
 '@T6G_MB_LIB.T6G(SCH_1):PAGE97_I177@PURE_QUANTA.SCONN288_DDR506112002KQ(CHIPS)':
 'VSS19': CDS_PINID='VSS19';
NODE_NAME     J24 50
 '@T6G_MB_LIB.T6G(SCH_1):PAGE97_I177@PURE_QUANTA.SCONN288_DDR506112002KQ(CHIPS)':
 'VSS20': CDS_PINID='VSS20';
NODE_NAME     J24 52
 '@T6G_MB_LIB.T6G(SCH_1):PAGE97_I177@PURE_QUANTA.SCONN288_DDR506112002KQ(CHIPS)':
 'VSS21': CDS_PINID='VSS21';
NODE_NAME     J24 54
 '@T6G_MB_LIB.T6G(SCH_1):PAGE97_I177@PURE_QUANTA.SCONN288_DDR506112002KQ(CHIPS)':
 'VSS22': CDS_PINID='VSS22';
NODE_NAME     J24 57
 '@T6G_MB_LIB.T6G(SCH_1):PAGE97_I177@PURE_QUANTA.SCONN288_DDR506112002KQ(CHIPS)':
 'VSS23': CDS_PINID='VSS23';
NODE_NAME     J24 59
 '@T6G_MB_LIB.T6G(SCH_1):PAGE97_I177@PURE_QUANTA.SCONN288_DDR506112002KQ(CHIPS)':
 'VSS24': CDS_PINID='VSS24';
NODE_NAME     J24 61
 '@T6G_MB_LIB.T6G(SCH_1):PAGE97_I177@PURE_QUANTA.SCONN288_DDR506112002KQ(CHIPS)':
 'VSS25': CDS_PINID='VSS25';
NODE_NAME     J24 63
 '@T6G_MB_LIB.T6G(SCH_1):PAGE97_I177@PURE_QUANTA.SCONN288_DDR506112002KQ(CHIPS)':
 'VSS26': CDS_PINID='VSS26';
NODE_NAME     J24 65
 '@T6G_MB_LIB.T6G(SCH_1):PAGE97_I177@PURE_QUANTA.SCONN288_DDR506112002KQ(CHIPS)':
 'VSS27': CDS_PINID='VSS27';
NODE_NAME     J24 67
 '@T6G_MB_LIB.T6G(SCH_1):PAGE97_I177@PURE_QUANTA.SCONN288_DDR506112002KQ(CHIPS)':
 'VSS28': CDS_PINID='VSS28';
NODE_NAME     J24 69
 '@T6G_MB_LIB.T6G(SCH_1):PAGE97_I177@PURE_QUANTA.SCONN288_DDR506112002KQ(CHIPS)':
 'VSS29': CDS_PINID='VSS29';
NODE_NAME     J24 71
 '@T6G_MB_LIB.T6G(SCH_1):PAGE97_I177@PURE_QUANTA.SCONN288_DDR506112002KQ(CHIPS)':
 'VSS30': CDS_PINID='VSS30';
NODE_NAME     J24 73
 '@T6G_MB_LIB.T6G(SCH_1):PAGE97_I177@PURE_QUANTA.SCONN288_DDR506112002KQ(CHIPS)':
 'VSS31': CDS_PINID='VSS31';
NODE_NAME     J24 75
 '@T6G_MB_LIB.T6G(SCH_1):PAGE97_I177@PURE_QUANTA.SCONN288_DDR506112002KQ(CHIPS)':
 'VSS32': CDS_PINID='VSS32';
NODE_NAME     J24 77
 '@T6G_MB_LIB.T6G(SCH_1):PAGE97_I177@PURE_QUANTA.SCONN288_DDR506112002KQ(CHIPS)':
 'VSS33': CDS_PINID='VSS33';
NODE_NAME     J24 79
 '@T6G_MB_LIB.T6G(SCH_1):PAGE97_I177@PURE_QUANTA.SCONN288_DDR506112002KQ(CHIPS)':
 'VSS34': CDS_PINID='VSS34';
NODE_NAME     J24 81
 '@T6G_MB_LIB.T6G(SCH_1):PAGE97_I177@PURE_QUANTA.SCONN288_DDR506112002KQ(CHIPS)':
 'VSS35': CDS_PINID='VSS35';
NODE_NAME     J24 83
 '@T6G_MB_LIB.T6G(SCH_1):PAGE97_I177@PURE_QUANTA.SCONN288_DDR506112002KQ(CHIPS)':
 'VSS36': CDS_PINID='VSS36';
NODE_NAME     J24 85
 '@T6G_MB_LIB.T6G(SCH_1):PAGE97_I177@PURE_QUANTA.SCONN288_DDR506112002KQ(CHIPS)':
 'VSS37': CDS_PINID='VSS37';
NODE_NAME     J24 88
 '@T6G_MB_LIB.T6G(SCH_1):PAGE97_I177@PURE_QUANTA.SCONN288_DDR506112002KQ(CHIPS)':
 'VSS38': CDS_PINID='VSS38';
NODE_NAME     J24 90
 '@T6G_MB_LIB.T6G(SCH_1):PAGE97_I177@PURE_QUANTA.SCONN288_DDR506112002KQ(CHIPS)':
 'VSS39': CDS_PINID='VSS39';
NODE_NAME     J24 92
 '@T6G_MB_LIB.T6G(SCH_1):PAGE97_I177@PURE_QUANTA.SCONN288_DDR506112002KQ(CHIPS)':
 'VSS40': CDS_PINID='VSS40';
NODE_NAME     J24 95
 '@T6G_MB_LIB.T6G(SCH_1):PAGE97_I177@PURE_QUANTA.SCONN288_DDR506112002KQ(CHIPS)':
 'VSS41': CDS_PINID='VSS41';
NODE_NAME     J24 97
 '@T6G_MB_LIB.T6G(SCH_1):PAGE97_I177@PURE_QUANTA.SCONN288_DDR506112002KQ(CHIPS)':
 'VSS42': CDS_PINID='VSS42';
NODE_NAME     J24 99
 '@T6G_MB_LIB.T6G(SCH_1):PAGE97_I177@PURE_QUANTA.SCONN288_DDR506112002KQ(CHIPS)':
 'VSS43': CDS_PINID='VSS43';
NODE_NAME     J24 101
 '@T6G_MB_LIB.T6G(SCH_1):PAGE97_I177@PURE_QUANTA.SCONN288_DDR506112002KQ(CHIPS)':
 'VSS44': CDS_PINID='VSS44';
NODE_NAME     J24 103
 '@T6G_MB_LIB.T6G(SCH_1):PAGE97_I177@PURE_QUANTA.SCONN288_DDR506112002KQ(CHIPS)':
 'VSS45': CDS_PINID='VSS45';
NODE_NAME     J24 106
 '@T6G_MB_LIB.T6G(SCH_1):PAGE97_I177@PURE_QUANTA.SCONN288_DDR506112002KQ(CHIPS)':
 'VSS46': CDS_PINID='VSS46';
NODE_NAME     J24 108
 '@T6G_MB_LIB.T6G(SCH_1):PAGE97_I177@PURE_QUANTA.SCONN288_DDR506112002KQ(CHIPS)':
 'VSS47': CDS_PINID='VSS47';
NODE_NAME     J24 110
 '@T6G_MB_LIB.T6G(SCH_1):PAGE97_I177@PURE_QUANTA.SCONN288_DDR506112002KQ(CHIPS)':
 'VSS48': CDS_PINID='VSS48';
NODE_NAME     J24 112
 '@T6G_MB_LIB.T6G(SCH_1):PAGE97_I177@PURE_QUANTA.SCONN288_DDR506112002KQ(CHIPS)':
 'VSS49': CDS_PINID='VSS49';
NODE_NAME     J24 114
 '@T6G_MB_LIB.T6G(SCH_1):PAGE97_I177@PURE_QUANTA.SCONN288_DDR506112002KQ(CHIPS)':
 'VSS50': CDS_PINID='VSS50';
NODE_NAME     J24 117
 '@T6G_MB_LIB.T6G(SCH_1):PAGE97_I177@PURE_QUANTA.SCONN288_DDR506112002KQ(CHIPS)':
 'VSS51': CDS_PINID='VSS51';
NODE_NAME     J24 119
 '@T6G_MB_LIB.T6G(SCH_1):PAGE97_I177@PURE_QUANTA.SCONN288_DDR506112002KQ(CHIPS)':
 'VSS52': CDS_PINID='VSS52';
NODE_NAME     J24 121
 '@T6G_MB_LIB.T6G(SCH_1):PAGE97_I177@PURE_QUANTA.SCONN288_DDR506112002KQ(CHIPS)':
 'VSS53': CDS_PINID='VSS53';
NODE_NAME     J24 123
 '@T6G_MB_LIB.T6G(SCH_1):PAGE97_I177@PURE_QUANTA.SCONN288_DDR506112002KQ(CHIPS)':
 'VSS54': CDS_PINID='VSS54';
NODE_NAME     J24 125
 '@T6G_MB_LIB.T6G(SCH_1):PAGE97_I177@PURE_QUANTA.SCONN288_DDR506112002KQ(CHIPS)':
 'VSS55': CDS_PINID='VSS55';
NODE_NAME     J24 128
 '@T6G_MB_LIB.T6G(SCH_1):PAGE97_I177@PURE_QUANTA.SCONN288_DDR506112002KQ(CHIPS)':
 'VSS56': CDS_PINID='VSS56';
NODE_NAME     J24 130
 '@T6G_MB_LIB.T6G(SCH_1):PAGE97_I177@PURE_QUANTA.SCONN288_DDR506112002KQ(CHIPS)':
 'VSS57': CDS_PINID='VSS57';
NODE_NAME     J24 132
 '@T6G_MB_LIB.T6G(SCH_1):PAGE97_I177@PURE_QUANTA.SCONN288_DDR506112002KQ(CHIPS)':
 'VSS58': CDS_PINID='VSS58';
NODE_NAME     J24 134
 '@T6G_MB_LIB.T6G(SCH_1):PAGE97_I177@PURE_QUANTA.SCONN288_DDR506112002KQ(CHIPS)':
 'VSS59': CDS_PINID='VSS59';
NODE_NAME     J24 136
 '@T6G_MB_LIB.T6G(SCH_1):PAGE97_I177@PURE_QUANTA.SCONN288_DDR506112002KQ(CHIPS)':
 'VSS60': CDS_PINID='VSS60';
NODE_NAME     J24 139
 '@T6G_MB_LIB.T6G(SCH_1):PAGE97_I177@PURE_QUANTA.SCONN288_DDR506112002KQ(CHIPS)':
 'VSS61': CDS_PINID='VSS61';
NODE_NAME     J24 141
 '@T6G_MB_LIB.T6G(SCH_1):PAGE97_I177@PURE_QUANTA.SCONN288_DDR506112002KQ(CHIPS)':
 'VSS62': CDS_PINID='VSS62';
NODE_NAME     J24 143
 '@T6G_MB_LIB.T6G(SCH_1):PAGE97_I177@PURE_QUANTA.SCONN288_DDR506112002KQ(CHIPS)':
 'VSS63': CDS_PINID='VSS63';
NODE_NAME     J24 151
 '@T6G_MB_LIB.T6G(SCH_1):PAGE97_I177@PURE_QUANTA.SCONN288_DDR506112002KQ(CHIPS)':
 'VSS64': CDS_PINID='VSS64';
NODE_NAME     J24 153
 '@T6G_MB_LIB.T6G(SCH_1):PAGE97_I177@PURE_QUANTA.SCONN288_DDR506112002KQ(CHIPS)':
 'VSS65': CDS_PINID='VSS65';
NODE_NAME     J24 155
 '@T6G_MB_LIB.T6G(SCH_1):PAGE97_I177@PURE_QUANTA.SCONN288_DDR506112002KQ(CHIPS)':
 'VSS66': CDS_PINID='VSS66';
NODE_NAME     J24 158
 '@T6G_MB_LIB.T6G(SCH_1):PAGE97_I177@PURE_QUANTA.SCONN288_DDR506112002KQ(CHIPS)':
 'VSS67': CDS_PINID='VSS67';
NODE_NAME     J24 160
 '@T6G_MB_LIB.T6G(SCH_1):PAGE97_I177@PURE_QUANTA.SCONN288_DDR506112002KQ(CHIPS)':
 'VSS68': CDS_PINID='VSS68';
NODE_NAME     J24 162
 '@T6G_MB_LIB.T6G(SCH_1):PAGE97_I177@PURE_QUANTA.SCONN288_DDR506112002KQ(CHIPS)':
 'VSS69': CDS_PINID='VSS69';
NODE_NAME     J24 164
 '@T6G_MB_LIB.T6G(SCH_1):PAGE97_I177@PURE_QUANTA.SCONN288_DDR506112002KQ(CHIPS)':
 'VSS70': CDS_PINID='VSS70';
NODE_NAME     J24 166
 '@T6G_MB_LIB.T6G(SCH_1):PAGE97_I177@PURE_QUANTA.SCONN288_DDR506112002KQ(CHIPS)':
 'VSS71': CDS_PINID='VSS71';
NODE_NAME     J24 169
 '@T6G_MB_LIB.T6G(SCH_1):PAGE97_I177@PURE_QUANTA.SCONN288_DDR506112002KQ(CHIPS)':
 'VSS72': CDS_PINID='VSS72';
NODE_NAME     J24 171
 '@T6G_MB_LIB.T6G(SCH_1):PAGE97_I177@PURE_QUANTA.SCONN288_DDR506112002KQ(CHIPS)':
 'VSS73': CDS_PINID='VSS73';
NODE_NAME     J24 173
 '@T6G_MB_LIB.T6G(SCH_1):PAGE97_I177@PURE_QUANTA.SCONN288_DDR506112002KQ(CHIPS)':
 'VSS74': CDS_PINID='VSS74';
NODE_NAME     J24 175
 '@T6G_MB_LIB.T6G(SCH_1):PAGE97_I177@PURE_QUANTA.SCONN288_DDR506112002KQ(CHIPS)':
 'VSS75': CDS_PINID='VSS75';
NODE_NAME     J24 177
 '@T6G_MB_LIB.T6G(SCH_1):PAGE97_I177@PURE_QUANTA.SCONN288_DDR506112002KQ(CHIPS)':
 'VSS76': CDS_PINID='VSS76';
NODE_NAME     J24 180
 '@T6G_MB_LIB.T6G(SCH_1):PAGE97_I177@PURE_QUANTA.SCONN288_DDR506112002KQ(CHIPS)':
 'VSS77': CDS_PINID='VSS77';
NODE_NAME     J24 182
 '@T6G_MB_LIB.T6G(SCH_1):PAGE97_I177@PURE_QUANTA.SCONN288_DDR506112002KQ(CHIPS)':
 'VSS78': CDS_PINID='VSS78';
NODE_NAME     J24 184
 '@T6G_MB_LIB.T6G(SCH_1):PAGE97_I177@PURE_QUANTA.SCONN288_DDR506112002KQ(CHIPS)':
 'VSS79': CDS_PINID='VSS79';
NODE_NAME     J24 186
 '@T6G_MB_LIB.T6G(SCH_1):PAGE97_I177@PURE_QUANTA.SCONN288_DDR506112002KQ(CHIPS)':
 'VSS80': CDS_PINID='VSS80';
NODE_NAME     J24 188
 '@T6G_MB_LIB.T6G(SCH_1):PAGE97_I177@PURE_QUANTA.SCONN288_DDR506112002KQ(CHIPS)':
 'VSS81': CDS_PINID='VSS81';
NODE_NAME     J24 191
 '@T6G_MB_LIB.T6G(SCH_1):PAGE97_I177@PURE_QUANTA.SCONN288_DDR506112002KQ(CHIPS)':
 'VSS82': CDS_PINID='VSS82';
NODE_NAME     J24 193
 '@T6G_MB_LIB.T6G(SCH_1):PAGE97_I177@PURE_QUANTA.SCONN288_DDR506112002KQ(CHIPS)':
 'VSS83': CDS_PINID='VSS83';
NODE_NAME     J24 195
 '@T6G_MB_LIB.T6G(SCH_1):PAGE97_I177@PURE_QUANTA.SCONN288_DDR506112002KQ(CHIPS)':
 'VSS84': CDS_PINID='VSS84';
NODE_NAME     J24 197
 '@T6G_MB_LIB.T6G(SCH_1):PAGE97_I177@PURE_QUANTA.SCONN288_DDR506112002KQ(CHIPS)':
 'VSS85': CDS_PINID='VSS85';
NODE_NAME     J24 199
 '@T6G_MB_LIB.T6G(SCH_1):PAGE97_I177@PURE_QUANTA.SCONN288_DDR506112002KQ(CHIPS)':
 'VSS86': CDS_PINID='VSS86';
NODE_NAME     J24 202
 '@T6G_MB_LIB.T6G(SCH_1):PAGE97_I177@PURE_QUANTA.SCONN288_DDR506112002KQ(CHIPS)':
 'VSS87': CDS_PINID='VSS87';
NODE_NAME     J24 204
 '@T6G_MB_LIB.T6G(SCH_1):PAGE97_I177@PURE_QUANTA.SCONN288_DDR506112002KQ(CHIPS)':
 'VSS88': CDS_PINID='VSS88';
NODE_NAME     J24 206
 '@T6G_MB_LIB.T6G(SCH_1):PAGE97_I177@PURE_QUANTA.SCONN288_DDR506112002KQ(CHIPS)':
 'VSS89': CDS_PINID='VSS89';
NODE_NAME     J24 208
 '@T6G_MB_LIB.T6G(SCH_1):PAGE97_I177@PURE_QUANTA.SCONN288_DDR506112002KQ(CHIPS)':
 'VSS90': CDS_PINID='VSS90';
NODE_NAME     J24 210
 '@T6G_MB_LIB.T6G(SCH_1):PAGE97_I177@PURE_QUANTA.SCONN288_DDR506112002KQ(CHIPS)':
 'VSS91': CDS_PINID='VSS91';
NODE_NAME     J24 212
 '@T6G_MB_LIB.T6G(SCH_1):PAGE97_I177@PURE_QUANTA.SCONN288_DDR506112002KQ(CHIPS)':
 'VSS92': CDS_PINID='VSS92';
NODE_NAME     J24 214
 '@T6G_MB_LIB.T6G(SCH_1):PAGE97_I177@PURE_QUANTA.SCONN288_DDR506112002KQ(CHIPS)':
 'VSS93': CDS_PINID='VSS93';
NODE_NAME     J24 216
 '@T6G_MB_LIB.T6G(SCH_1):PAGE97_I177@PURE_QUANTA.SCONN288_DDR506112002KQ(CHIPS)':
 'VSS94': CDS_PINID='VSS94';
NODE_NAME     J24 219
 '@T6G_MB_LIB.T6G(SCH_1):PAGE97_I177@PURE_QUANTA.SCONN288_DDR506112002KQ(CHIPS)':
 'VSS95': CDS_PINID='VSS95';
NODE_NAME     J24 222
 '@T6G_MB_LIB.T6G(SCH_1):PAGE97_I177@PURE_QUANTA.SCONN288_DDR506112002KQ(CHIPS)':
 'VSS96': CDS_PINID='VSS96';
NODE_NAME     J24 224
 '@T6G_MB_LIB.T6G(SCH_1):PAGE97_I177@PURE_QUANTA.SCONN288_DDR506112002KQ(CHIPS)':
 'VSS97': CDS_PINID='VSS97';
NODE_NAME     J24 226
 '@T6G_MB_LIB.T6G(SCH_1):PAGE97_I177@PURE_QUANTA.SCONN288_DDR506112002KQ(CHIPS)':
 'VSS98': CDS_PINID='VSS98';
NODE_NAME     J24 228
 '@T6G_MB_LIB.T6G(SCH_1):PAGE97_I177@PURE_QUANTA.SCONN288_DDR506112002KQ(CHIPS)':
 'VSS99': CDS_PINID='VSS99';
NODE_NAME     J24 230
 '@T6G_MB_LIB.T6G(SCH_1):PAGE97_I177@PURE_QUANTA.SCONN288_DDR506112002KQ(CHIPS)':
 'VSS100': CDS_PINID='VSS100';
NODE_NAME     J24 233
 '@T6G_MB_LIB.T6G(SCH_1):PAGE97_I177@PURE_QUANTA.SCONN288_DDR506112002KQ(CHIPS)':
 'VSS101': CDS_PINID='VSS101';
NODE_NAME     J24 235
 '@T6G_MB_LIB.T6G(SCH_1):PAGE97_I177@PURE_QUANTA.SCONN288_DDR506112002KQ(CHIPS)':
 'VSS102': CDS_PINID='VSS102';
NODE_NAME     J24 237
 '@T6G_MB_LIB.T6G(SCH_1):PAGE97_I177@PURE_QUANTA.SCONN288_DDR506112002KQ(CHIPS)':
 'VSS103': CDS_PINID='VSS103';
NODE_NAME     J24 240
 '@T6G_MB_LIB.T6G(SCH_1):PAGE97_I177@PURE_QUANTA.SCONN288_DDR506112002KQ(CHIPS)':
 'VSS104': CDS_PINID='VSS104';
NODE_NAME     J24 242
 '@T6G_MB_LIB.T6G(SCH_1):PAGE97_I177@PURE_QUANTA.SCONN288_DDR506112002KQ(CHIPS)':
 'VSS105': CDS_PINID='VSS105';
NODE_NAME     J24 244
 '@T6G_MB_LIB.T6G(SCH_1):PAGE97_I177@PURE_QUANTA.SCONN288_DDR506112002KQ(CHIPS)':
 'VSS106': CDS_PINID='VSS106';
NODE_NAME     J24 246
 '@T6G_MB_LIB.T6G(SCH_1):PAGE97_I177@PURE_QUANTA.SCONN288_DDR506112002KQ(CHIPS)':
 'VSS107': CDS_PINID='VSS107';
NODE_NAME     J24 248
 '@T6G_MB_LIB.T6G(SCH_1):PAGE97_I177@PURE_QUANTA.SCONN288_DDR506112002KQ(CHIPS)':
 'VSS108': CDS_PINID='VSS108';
NODE_NAME     J24 251
 '@T6G_MB_LIB.T6G(SCH_1):PAGE97_I177@PURE_QUANTA.SCONN288_DDR506112002KQ(CHIPS)':
 'VSS109': CDS_PINID='VSS109';
NODE_NAME     J24 253
 '@T6G_MB_LIB.T6G(SCH_1):PAGE97_I177@PURE_QUANTA.SCONN288_DDR506112002KQ(CHIPS)':
 'VSS110': CDS_PINID='VSS110';
NODE_NAME     J24 255
 '@T6G_MB_LIB.T6G(SCH_1):PAGE97_I177@PURE_QUANTA.SCONN288_DDR506112002KQ(CHIPS)':
 'VSS111': CDS_PINID='VSS111';
NODE_NAME     J24 257
 '@T6G_MB_LIB.T6G(SCH_1):PAGE97_I177@PURE_QUANTA.SCONN288_DDR506112002KQ(CHIPS)':
 'VSS112': CDS_PINID='VSS112';
NODE_NAME     J24 259
 '@T6G_MB_LIB.T6G(SCH_1):PAGE97_I177@PURE_QUANTA.SCONN288_DDR506112002KQ(CHIPS)':
 'VSS113': CDS_PINID='VSS113';
NODE_NAME     J24 262
 '@T6G_MB_LIB.T6G(SCH_1):PAGE97_I177@PURE_QUANTA.SCONN288_DDR506112002KQ(CHIPS)':
 'VSS114': CDS_PINID='VSS114';
NODE_NAME     J24 264
 '@T6G_MB_LIB.T6G(SCH_1):PAGE97_I177@PURE_QUANTA.SCONN288_DDR506112002KQ(CHIPS)':
 'VSS115': CDS_PINID='VSS115';
NODE_NAME     J24 266
 '@T6G_MB_LIB.T6G(SCH_1):PAGE97_I177@PURE_QUANTA.SCONN288_DDR506112002KQ(CHIPS)':
 'VSS116': CDS_PINID='VSS116';
NODE_NAME     J24 268
 '@T6G_MB_LIB.T6G(SCH_1):PAGE97_I177@PURE_QUANTA.SCONN288_DDR506112002KQ(CHIPS)':
 'VSS117': CDS_PINID='VSS117';
NODE_NAME     J24 270
 '@T6G_MB_LIB.T6G(SCH_1):PAGE97_I177@PURE_QUANTA.SCONN288_DDR506112002KQ(CHIPS)':
 'VSS118': CDS_PINID='VSS118';
NODE_NAME     J24 273
 '@T6G_MB_LIB.T6G(SCH_1):PAGE97_I177@PURE_QUANTA.SCONN288_DDR506112002KQ(CHIPS)':
 'VSS119': CDS_PINID='VSS119';
NODE_NAME     J24 275
 '@T6G_MB_LIB.T6G(SCH_1):PAGE97_I177@PURE_QUANTA.SCONN288_DDR506112002KQ(CHIPS)':
 'VSS120': CDS_PINID='VSS120';
NODE_NAME     J24 277
 '@T6G_MB_LIB.T6G(SCH_1):PAGE97_I177@PURE_QUANTA.SCONN288_DDR506112002KQ(CHIPS)':
 'VSS121': CDS_PINID='VSS121';
NODE_NAME     J24 279
 '@T6G_MB_LIB.T6G(SCH_1):PAGE97_I177@PURE_QUANTA.SCONN288_DDR506112002KQ(CHIPS)':
 'VSS122': CDS_PINID='VSS122';
NODE_NAME     J24 281
 '@T6G_MB_LIB.T6G(SCH_1):PAGE97_I177@PURE_QUANTA.SCONN288_DDR506112002KQ(CHIPS)':
 'VSS123': CDS_PINID='VSS123';
NODE_NAME     J24 284
 '@T6G_MB_LIB.T6G(SCH_1):PAGE97_I177@PURE_QUANTA.SCONN288_DDR506112002KQ(CHIPS)':
 'VSS124': CDS_PINID='VSS124';
NODE_NAME     J24 286
 '@T6G_MB_LIB.T6G(SCH_1):PAGE97_I177@PURE_QUANTA.SCONN288_DDR506112002KQ(CHIPS)':
 'VSS125': CDS_PINID='VSS125';
NODE_NAME     J24 288
 '@T6G_MB_LIB.T6G(SCH_1):PAGE97_I177@PURE_QUANTA.SCONN288_DDR506112002KQ(CHIPS)':
 'VSS126': CDS_PINID='VSS126';
NODE_NAME     C136 2
 '@T6G_MB_LIB.T6G(SCH_1):PAGE97_I185@PURE_QUANTA.Q_CAP(CHIPS)':
 'B': CDS_PINID='B';
NODE_NAME     C173 2
 '@T6G_MB_LIB.T6G(SCH_1):PAGE97_I240@PURE_QUANTA.Q_CAP(CHIPS)':
 'B': CDS_PINID='B';
NODE_NAME     C174 2
 '@T6G_MB_LIB.T6G(SCH_1):PAGE97_I241@PURE_QUANTA.Q_CAP(CHIPS)':
 'B': CDS_PINID='B';
NODE_NAME     R770 2
 '@T6G_MB_LIB.T6G(SCH_1):PAGE98_I127@PURE_QUANTA.Q_RES(CHIPS)':
 'B': CDS_PINID='B';
NODE_NAME     J26 G1
 '@T6G_MB_LIB.T6G(SCH_1):PAGE98_I160@PURE_QUANTA.SCONN288_DDR506112002KQ(CHIPS)':
 'G1': CDS_PINID='G1';
NODE_NAME     J26 G2
 '@T6G_MB_LIB.T6G(SCH_1):PAGE98_I160@PURE_QUANTA.SCONN288_DDR506112002KQ(CHIPS)':
 'G2': CDS_PINID='G2';
NODE_NAME     J26 G3
 '@T6G_MB_LIB.T6G(SCH_1):PAGE98_I160@PURE_QUANTA.SCONN288_DDR506112002KQ(CHIPS)':
 'G3': CDS_PINID='G3';
NODE_NAME     J26 6
 '@T6G_MB_LIB.T6G(SCH_1):PAGE98_I160@PURE_QUANTA.SCONN288_DDR506112002KQ(CHIPS)':
 'VSS0': CDS_PINID='VSS0';
NODE_NAME     J26 8
 '@T6G_MB_LIB.T6G(SCH_1):PAGE98_I160@PURE_QUANTA.SCONN288_DDR506112002KQ(CHIPS)':
 'VSS1': CDS_PINID='VSS1';
NODE_NAME     J26 10
 '@T6G_MB_LIB.T6G(SCH_1):PAGE98_I160@PURE_QUANTA.SCONN288_DDR506112002KQ(CHIPS)':
 'VSS2': CDS_PINID='VSS2';
NODE_NAME     J26 13
 '@T6G_MB_LIB.T6G(SCH_1):PAGE98_I160@PURE_QUANTA.SCONN288_DDR506112002KQ(CHIPS)':
 'VSS3': CDS_PINID='VSS3';
NODE_NAME     J26 15
 '@T6G_MB_LIB.T6G(SCH_1):PAGE98_I160@PURE_QUANTA.SCONN288_DDR506112002KQ(CHIPS)':
 'VSS4': CDS_PINID='VSS4';
NODE_NAME     J26 17
 '@T6G_MB_LIB.T6G(SCH_1):PAGE98_I160@PURE_QUANTA.SCONN288_DDR506112002KQ(CHIPS)':
 'VSS5': CDS_PINID='VSS5';
NODE_NAME     J26 19
 '@T6G_MB_LIB.T6G(SCH_1):PAGE98_I160@PURE_QUANTA.SCONN288_DDR506112002KQ(CHIPS)':
 'VSS6': CDS_PINID='VSS6';
NODE_NAME     J26 21
 '@T6G_MB_LIB.T6G(SCH_1):PAGE98_I160@PURE_QUANTA.SCONN288_DDR506112002KQ(CHIPS)':
 'VSS7': CDS_PINID='VSS7';
NODE_NAME     J26 24
 '@T6G_MB_LIB.T6G(SCH_1):PAGE98_I160@PURE_QUANTA.SCONN288_DDR506112002KQ(CHIPS)':
 'VSS8': CDS_PINID='VSS8';
NODE_NAME     J26 26
 '@T6G_MB_LIB.T6G(SCH_1):PAGE98_I160@PURE_QUANTA.SCONN288_DDR506112002KQ(CHIPS)':
 'VSS9': CDS_PINID='VSS9';
NODE_NAME     J26 28
 '@T6G_MB_LIB.T6G(SCH_1):PAGE98_I160@PURE_QUANTA.SCONN288_DDR506112002KQ(CHIPS)':
 'VSS10': CDS_PINID='VSS10';
NODE_NAME     J26 30
 '@T6G_MB_LIB.T6G(SCH_1):PAGE98_I160@PURE_QUANTA.SCONN288_DDR506112002KQ(CHIPS)':
 'VSS11': CDS_PINID='VSS11';
NODE_NAME     J26 32
 '@T6G_MB_LIB.T6G(SCH_1):PAGE98_I160@PURE_QUANTA.SCONN288_DDR506112002KQ(CHIPS)':
 'VSS12': CDS_PINID='VSS12';
NODE_NAME     J26 35
 '@T6G_MB_LIB.T6G(SCH_1):PAGE98_I160@PURE_QUANTA.SCONN288_DDR506112002KQ(CHIPS)':
 'VSS13': CDS_PINID='VSS13';
NODE_NAME     J26 37
 '@T6G_MB_LIB.T6G(SCH_1):PAGE98_I160@PURE_QUANTA.SCONN288_DDR506112002KQ(CHIPS)':
 'VSS14': CDS_PINID='VSS14';
NODE_NAME     J26 39
 '@T6G_MB_LIB.T6G(SCH_1):PAGE98_I160@PURE_QUANTA.SCONN288_DDR506112002KQ(CHIPS)':
 'VSS15': CDS_PINID='VSS15';
NODE_NAME     J26 41
 '@T6G_MB_LIB.T6G(SCH_1):PAGE98_I160@PURE_QUANTA.SCONN288_DDR506112002KQ(CHIPS)':
 'VSS16': CDS_PINID='VSS16';
NODE_NAME     J26 43
 '@T6G_MB_LIB.T6G(SCH_1):PAGE98_I160@PURE_QUANTA.SCONN288_DDR506112002KQ(CHIPS)':
 'VSS17': CDS_PINID='VSS17';
NODE_NAME     J26 46
 '@T6G_MB_LIB.T6G(SCH_1):PAGE98_I160@PURE_QUANTA.SCONN288_DDR506112002KQ(CHIPS)':
 'VSS18': CDS_PINID='VSS18';
NODE_NAME     J26 48
 '@T6G_MB_LIB.T6G(SCH_1):PAGE98_I160@PURE_QUANTA.SCONN288_DDR506112002KQ(CHIPS)':
 'VSS19': CDS_PINID='VSS19';
NODE_NAME     J26 50
 '@T6G_MB_LIB.T6G(SCH_1):PAGE98_I160@PURE_QUANTA.SCONN288_DDR506112002KQ(CHIPS)':
 'VSS20': CDS_PINID='VSS20';
NODE_NAME     J26 52
 '@T6G_MB_LIB.T6G(SCH_1):PAGE98_I160@PURE_QUANTA.SCONN288_DDR506112002KQ(CHIPS)':
 'VSS21': CDS_PINID='VSS21';
NODE_NAME     J26 54
 '@T6G_MB_LIB.T6G(SCH_1):PAGE98_I160@PURE_QUANTA.SCONN288_DDR506112002KQ(CHIPS)':
 'VSS22': CDS_PINID='VSS22';
NODE_NAME     J26 57
 '@T6G_MB_LIB.T6G(SCH_1):PAGE98_I160@PURE_QUANTA.SCONN288_DDR506112002KQ(CHIPS)':
 'VSS23': CDS_PINID='VSS23';
NODE_NAME     J26 59
 '@T6G_MB_LIB.T6G(SCH_1):PAGE98_I160@PURE_QUANTA.SCONN288_DDR506112002KQ(CHIPS)':
 'VSS24': CDS_PINID='VSS24';
NODE_NAME     J26 61
 '@T6G_MB_LIB.T6G(SCH_1):PAGE98_I160@PURE_QUANTA.SCONN288_DDR506112002KQ(CHIPS)':
 'VSS25': CDS_PINID='VSS25';
NODE_NAME     J26 63
 '@T6G_MB_LIB.T6G(SCH_1):PAGE98_I160@PURE_QUANTA.SCONN288_DDR506112002KQ(CHIPS)':
 'VSS26': CDS_PINID='VSS26';
NODE_NAME     J26 65
 '@T6G_MB_LIB.T6G(SCH_1):PAGE98_I160@PURE_QUANTA.SCONN288_DDR506112002KQ(CHIPS)':
 'VSS27': CDS_PINID='VSS27';
NODE_NAME     J26 67
 '@T6G_MB_LIB.T6G(SCH_1):PAGE98_I160@PURE_QUANTA.SCONN288_DDR506112002KQ(CHIPS)':
 'VSS28': CDS_PINID='VSS28';
NODE_NAME     J26 69
 '@T6G_MB_LIB.T6G(SCH_1):PAGE98_I160@PURE_QUANTA.SCONN288_DDR506112002KQ(CHIPS)':
 'VSS29': CDS_PINID='VSS29';
NODE_NAME     J26 71
 '@T6G_MB_LIB.T6G(SCH_1):PAGE98_I160@PURE_QUANTA.SCONN288_DDR506112002KQ(CHIPS)':
 'VSS30': CDS_PINID='VSS30';
NODE_NAME     J26 73
 '@T6G_MB_LIB.T6G(SCH_1):PAGE98_I160@PURE_QUANTA.SCONN288_DDR506112002KQ(CHIPS)':
 'VSS31': CDS_PINID='VSS31';
NODE_NAME     J26 75
 '@T6G_MB_LIB.T6G(SCH_1):PAGE98_I160@PURE_QUANTA.SCONN288_DDR506112002KQ(CHIPS)':
 'VSS32': CDS_PINID='VSS32';
NODE_NAME     J26 77
 '@T6G_MB_LIB.T6G(SCH_1):PAGE98_I160@PURE_QUANTA.SCONN288_DDR506112002KQ(CHIPS)':
 'VSS33': CDS_PINID='VSS33';
NODE_NAME     J26 79
 '@T6G_MB_LIB.T6G(SCH_1):PAGE98_I160@PURE_QUANTA.SCONN288_DDR506112002KQ(CHIPS)':
 'VSS34': CDS_PINID='VSS34';
NODE_NAME     J26 81
 '@T6G_MB_LIB.T6G(SCH_1):PAGE98_I160@PURE_QUANTA.SCONN288_DDR506112002KQ(CHIPS)':
 'VSS35': CDS_PINID='VSS35';
NODE_NAME     J26 83
 '@T6G_MB_LIB.T6G(SCH_1):PAGE98_I160@PURE_QUANTA.SCONN288_DDR506112002KQ(CHIPS)':
 'VSS36': CDS_PINID='VSS36';
NODE_NAME     J26 85
 '@T6G_MB_LIB.T6G(SCH_1):PAGE98_I160@PURE_QUANTA.SCONN288_DDR506112002KQ(CHIPS)':
 'VSS37': CDS_PINID='VSS37';
NODE_NAME     J26 88
 '@T6G_MB_LIB.T6G(SCH_1):PAGE98_I160@PURE_QUANTA.SCONN288_DDR506112002KQ(CHIPS)':
 'VSS38': CDS_PINID='VSS38';
NODE_NAME     J26 90
 '@T6G_MB_LIB.T6G(SCH_1):PAGE98_I160@PURE_QUANTA.SCONN288_DDR506112002KQ(CHIPS)':
 'VSS39': CDS_PINID='VSS39';
NODE_NAME     J26 92
 '@T6G_MB_LIB.T6G(SCH_1):PAGE98_I160@PURE_QUANTA.SCONN288_DDR506112002KQ(CHIPS)':
 'VSS40': CDS_PINID='VSS40';
NODE_NAME     J26 95
 '@T6G_MB_LIB.T6G(SCH_1):PAGE98_I160@PURE_QUANTA.SCONN288_DDR506112002KQ(CHIPS)':
 'VSS41': CDS_PINID='VSS41';
NODE_NAME     J26 97
 '@T6G_MB_LIB.T6G(SCH_1):PAGE98_I160@PURE_QUANTA.SCONN288_DDR506112002KQ(CHIPS)':
 'VSS42': CDS_PINID='VSS42';
NODE_NAME     J26 99
 '@T6G_MB_LIB.T6G(SCH_1):PAGE98_I160@PURE_QUANTA.SCONN288_DDR506112002KQ(CHIPS)':
 'VSS43': CDS_PINID='VSS43';
NODE_NAME     J26 101
 '@T6G_MB_LIB.T6G(SCH_1):PAGE98_I160@PURE_QUANTA.SCONN288_DDR506112002KQ(CHIPS)':
 'VSS44': CDS_PINID='VSS44';
NODE_NAME     J26 103
 '@T6G_MB_LIB.T6G(SCH_1):PAGE98_I160@PURE_QUANTA.SCONN288_DDR506112002KQ(CHIPS)':
 'VSS45': CDS_PINID='VSS45';
NODE_NAME     J26 106
 '@T6G_MB_LIB.T6G(SCH_1):PAGE98_I160@PURE_QUANTA.SCONN288_DDR506112002KQ(CHIPS)':
 'VSS46': CDS_PINID='VSS46';
NODE_NAME     J26 108
 '@T6G_MB_LIB.T6G(SCH_1):PAGE98_I160@PURE_QUANTA.SCONN288_DDR506112002KQ(CHIPS)':
 'VSS47': CDS_PINID='VSS47';
NODE_NAME     J26 110
 '@T6G_MB_LIB.T6G(SCH_1):PAGE98_I160@PURE_QUANTA.SCONN288_DDR506112002KQ(CHIPS)':
 'VSS48': CDS_PINID='VSS48';
NODE_NAME     J26 112
 '@T6G_MB_LIB.T6G(SCH_1):PAGE98_I160@PURE_QUANTA.SCONN288_DDR506112002KQ(CHIPS)':
 'VSS49': CDS_PINID='VSS49';
NODE_NAME     J26 114
 '@T6G_MB_LIB.T6G(SCH_1):PAGE98_I160@PURE_QUANTA.SCONN288_DDR506112002KQ(CHIPS)':
 'VSS50': CDS_PINID='VSS50';
NODE_NAME     J26 117
 '@T6G_MB_LIB.T6G(SCH_1):PAGE98_I160@PURE_QUANTA.SCONN288_DDR506112002KQ(CHIPS)':
 'VSS51': CDS_PINID='VSS51';
NODE_NAME     J26 119
 '@T6G_MB_LIB.T6G(SCH_1):PAGE98_I160@PURE_QUANTA.SCONN288_DDR506112002KQ(CHIPS)':
 'VSS52': CDS_PINID='VSS52';
NODE_NAME     J26 121
 '@T6G_MB_LIB.T6G(SCH_1):PAGE98_I160@PURE_QUANTA.SCONN288_DDR506112002KQ(CHIPS)':
 'VSS53': CDS_PINID='VSS53';
NODE_NAME     J26 123
 '@T6G_MB_LIB.T6G(SCH_1):PAGE98_I160@PURE_QUANTA.SCONN288_DDR506112002KQ(CHIPS)':
 'VSS54': CDS_PINID='VSS54';
NODE_NAME     J26 125
 '@T6G_MB_LIB.T6G(SCH_1):PAGE98_I160@PURE_QUANTA.SCONN288_DDR506112002KQ(CHIPS)':
 'VSS55': CDS_PINID='VSS55';
NODE_NAME     J26 128
 '@T6G_MB_LIB.T6G(SCH_1):PAGE98_I160@PURE_QUANTA.SCONN288_DDR506112002KQ(CHIPS)':
 'VSS56': CDS_PINID='VSS56';
NODE_NAME     J26 130
 '@T6G_MB_LIB.T6G(SCH_1):PAGE98_I160@PURE_QUANTA.SCONN288_DDR506112002KQ(CHIPS)':
 'VSS57': CDS_PINID='VSS57';
NODE_NAME     J26 132
 '@T6G_MB_LIB.T6G(SCH_1):PAGE98_I160@PURE_QUANTA.SCONN288_DDR506112002KQ(CHIPS)':
 'VSS58': CDS_PINID='VSS58';
NODE_NAME     J26 134
 '@T6G_MB_LIB.T6G(SCH_1):PAGE98_I160@PURE_QUANTA.SCONN288_DDR506112002KQ(CHIPS)':
 'VSS59': CDS_PINID='VSS59';
NODE_NAME     J26 136
 '@T6G_MB_LIB.T6G(SCH_1):PAGE98_I160@PURE_QUANTA.SCONN288_DDR506112002KQ(CHIPS)':
 'VSS60': CDS_PINID='VSS60';
NODE_NAME     J26 139
 '@T6G_MB_LIB.T6G(SCH_1):PAGE98_I160@PURE_QUANTA.SCONN288_DDR506112002KQ(CHIPS)':
 'VSS61': CDS_PINID='VSS61';
NODE_NAME     J26 141
 '@T6G_MB_LIB.T6G(SCH_1):PAGE98_I160@PURE_QUANTA.SCONN288_DDR506112002KQ(CHIPS)':
 'VSS62': CDS_PINID='VSS62';
NODE_NAME     J26 143
 '@T6G_MB_LIB.T6G(SCH_1):PAGE98_I160@PURE_QUANTA.SCONN288_DDR506112002KQ(CHIPS)':
 'VSS63': CDS_PINID='VSS63';
NODE_NAME     J26 151
 '@T6G_MB_LIB.T6G(SCH_1):PAGE98_I160@PURE_QUANTA.SCONN288_DDR506112002KQ(CHIPS)':
 'VSS64': CDS_PINID='VSS64';
NODE_NAME     J26 153
 '@T6G_MB_LIB.T6G(SCH_1):PAGE98_I160@PURE_QUANTA.SCONN288_DDR506112002KQ(CHIPS)':
 'VSS65': CDS_PINID='VSS65';
NODE_NAME     J26 155
 '@T6G_MB_LIB.T6G(SCH_1):PAGE98_I160@PURE_QUANTA.SCONN288_DDR506112002KQ(CHIPS)':
 'VSS66': CDS_PINID='VSS66';
NODE_NAME     J26 158
 '@T6G_MB_LIB.T6G(SCH_1):PAGE98_I160@PURE_QUANTA.SCONN288_DDR506112002KQ(CHIPS)':
 'VSS67': CDS_PINID='VSS67';
NODE_NAME     J26 160
 '@T6G_MB_LIB.T6G(SCH_1):PAGE98_I160@PURE_QUANTA.SCONN288_DDR506112002KQ(CHIPS)':
 'VSS68': CDS_PINID='VSS68';
NODE_NAME     J26 162
 '@T6G_MB_LIB.T6G(SCH_1):PAGE98_I160@PURE_QUANTA.SCONN288_DDR506112002KQ(CHIPS)':
 'VSS69': CDS_PINID='VSS69';
NODE_NAME     J26 164
 '@T6G_MB_LIB.T6G(SCH_1):PAGE98_I160@PURE_QUANTA.SCONN288_DDR506112002KQ(CHIPS)':
 'VSS70': CDS_PINID='VSS70';
NODE_NAME     J26 166
 '@T6G_MB_LIB.T6G(SCH_1):PAGE98_I160@PURE_QUANTA.SCONN288_DDR506112002KQ(CHIPS)':
 'VSS71': CDS_PINID='VSS71';
NODE_NAME     J26 169
 '@T6G_MB_LIB.T6G(SCH_1):PAGE98_I160@PURE_QUANTA.SCONN288_DDR506112002KQ(CHIPS)':
 'VSS72': CDS_PINID='VSS72';
NODE_NAME     J26 171
 '@T6G_MB_LIB.T6G(SCH_1):PAGE98_I160@PURE_QUANTA.SCONN288_DDR506112002KQ(CHIPS)':
 'VSS73': CDS_PINID='VSS73';
NODE_NAME     J26 173
 '@T6G_MB_LIB.T6G(SCH_1):PAGE98_I160@PURE_QUANTA.SCONN288_DDR506112002KQ(CHIPS)':
 'VSS74': CDS_PINID='VSS74';
NODE_NAME     J26 175
 '@T6G_MB_LIB.T6G(SCH_1):PAGE98_I160@PURE_QUANTA.SCONN288_DDR506112002KQ(CHIPS)':
 'VSS75': CDS_PINID='VSS75';
NODE_NAME     J26 177
 '@T6G_MB_LIB.T6G(SCH_1):PAGE98_I160@PURE_QUANTA.SCONN288_DDR506112002KQ(CHIPS)':
 'VSS76': CDS_PINID='VSS76';
NODE_NAME     J26 180
 '@T6G_MB_LIB.T6G(SCH_1):PAGE98_I160@PURE_QUANTA.SCONN288_DDR506112002KQ(CHIPS)':
 'VSS77': CDS_PINID='VSS77';
NODE_NAME     J26 182
 '@T6G_MB_LIB.T6G(SCH_1):PAGE98_I160@PURE_QUANTA.SCONN288_DDR506112002KQ(CHIPS)':
 'VSS78': CDS_PINID='VSS78';
NODE_NAME     J26 184
 '@T6G_MB_LIB.T6G(SCH_1):PAGE98_I160@PURE_QUANTA.SCONN288_DDR506112002KQ(CHIPS)':
 'VSS79': CDS_PINID='VSS79';
NODE_NAME     J26 186
 '@T6G_MB_LIB.T6G(SCH_1):PAGE98_I160@PURE_QUANTA.SCONN288_DDR506112002KQ(CHIPS)':
 'VSS80': CDS_PINID='VSS80';
NODE_NAME     J26 188
 '@T6G_MB_LIB.T6G(SCH_1):PAGE98_I160@PURE_QUANTA.SCONN288_DDR506112002KQ(CHIPS)':
 'VSS81': CDS_PINID='VSS81';
NODE_NAME     J26 191
 '@T6G_MB_LIB.T6G(SCH_1):PAGE98_I160@PURE_QUANTA.SCONN288_DDR506112002KQ(CHIPS)':
 'VSS82': CDS_PINID='VSS82';
NODE_NAME     J26 193
 '@T6G_MB_LIB.T6G(SCH_1):PAGE98_I160@PURE_QUANTA.SCONN288_DDR506112002KQ(CHIPS)':
 'VSS83': CDS_PINID='VSS83';
NODE_NAME     J26 195
 '@T6G_MB_LIB.T6G(SCH_1):PAGE98_I160@PURE_QUANTA.SCONN288_DDR506112002KQ(CHIPS)':
 'VSS84': CDS_PINID='VSS84';
NODE_NAME     J26 197
 '@T6G_MB_LIB.T6G(SCH_1):PAGE98_I160@PURE_QUANTA.SCONN288_DDR506112002KQ(CHIPS)':
 'VSS85': CDS_PINID='VSS85';
NODE_NAME     J26 199
 '@T6G_MB_LIB.T6G(SCH_1):PAGE98_I160@PURE_QUANTA.SCONN288_DDR506112002KQ(CHIPS)':
 'VSS86': CDS_PINID='VSS86';
NODE_NAME     J26 202
 '@T6G_MB_LIB.T6G(SCH_1):PAGE98_I160@PURE_QUANTA.SCONN288_DDR506112002KQ(CHIPS)':
 'VSS87': CDS_PINID='VSS87';
NODE_NAME     J26 204
 '@T6G_MB_LIB.T6G(SCH_1):PAGE98_I160@PURE_QUANTA.SCONN288_DDR506112002KQ(CHIPS)':
 'VSS88': CDS_PINID='VSS88';
NODE_NAME     J26 206
 '@T6G_MB_LIB.T6G(SCH_1):PAGE98_I160@PURE_QUANTA.SCONN288_DDR506112002KQ(CHIPS)':
 'VSS89': CDS_PINID='VSS89';
NODE_NAME     J26 208
 '@T6G_MB_LIB.T6G(SCH_1):PAGE98_I160@PURE_QUANTA.SCONN288_DDR506112002KQ(CHIPS)':
 'VSS90': CDS_PINID='VSS90';
NODE_NAME     J26 210
 '@T6G_MB_LIB.T6G(SCH_1):PAGE98_I160@PURE_QUANTA.SCONN288_DDR506112002KQ(CHIPS)':
 'VSS91': CDS_PINID='VSS91';
NODE_NAME     J26 212
 '@T6G_MB_LIB.T6G(SCH_1):PAGE98_I160@PURE_QUANTA.SCONN288_DDR506112002KQ(CHIPS)':
 'VSS92': CDS_PINID='VSS92';
NODE_NAME     J26 214
 '@T6G_MB_LIB.T6G(SCH_1):PAGE98_I160@PURE_QUANTA.SCONN288_DDR506112002KQ(CHIPS)':
 'VSS93': CDS_PINID='VSS93';
NODE_NAME     J26 216
 '@T6G_MB_LIB.T6G(SCH_1):PAGE98_I160@PURE_QUANTA.SCONN288_DDR506112002KQ(CHIPS)':
 'VSS94': CDS_PINID='VSS94';
NODE_NAME     J26 219
 '@T6G_MB_LIB.T6G(SCH_1):PAGE98_I160@PURE_QUANTA.SCONN288_DDR506112002KQ(CHIPS)':
 'VSS95': CDS_PINID='VSS95';
NODE_NAME     J26 222
 '@T6G_MB_LIB.T6G(SCH_1):PAGE98_I160@PURE_QUANTA.SCONN288_DDR506112002KQ(CHIPS)':
 'VSS96': CDS_PINID='VSS96';
NODE_NAME     J26 224
 '@T6G_MB_LIB.T6G(SCH_1):PAGE98_I160@PURE_QUANTA.SCONN288_DDR506112002KQ(CHIPS)':
 'VSS97': CDS_PINID='VSS97';
NODE_NAME     J26 226
 '@T6G_MB_LIB.T6G(SCH_1):PAGE98_I160@PURE_QUANTA.SCONN288_DDR506112002KQ(CHIPS)':
 'VSS98': CDS_PINID='VSS98';
NODE_NAME     J26 228
 '@T6G_MB_LIB.T6G(SCH_1):PAGE98_I160@PURE_QUANTA.SCONN288_DDR506112002KQ(CHIPS)':
 'VSS99': CDS_PINID='VSS99';
NODE_NAME     J26 230
 '@T6G_MB_LIB.T6G(SCH_1):PAGE98_I160@PURE_QUANTA.SCONN288_DDR506112002KQ(CHIPS)':
 'VSS100': CDS_PINID='VSS100';
NODE_NAME     J26 233
 '@T6G_MB_LIB.T6G(SCH_1):PAGE98_I160@PURE_QUANTA.SCONN288_DDR506112002KQ(CHIPS)':
 'VSS101': CDS_PINID='VSS101';
NODE_NAME     J26 235
 '@T6G_MB_LIB.T6G(SCH_1):PAGE98_I160@PURE_QUANTA.SCONN288_DDR506112002KQ(CHIPS)':
 'VSS102': CDS_PINID='VSS102';
NODE_NAME     J26 237
 '@T6G_MB_LIB.T6G(SCH_1):PAGE98_I160@PURE_QUANTA.SCONN288_DDR506112002KQ(CHIPS)':
 'VSS103': CDS_PINID='VSS103';
NODE_NAME     J26 240
 '@T6G_MB_LIB.T6G(SCH_1):PAGE98_I160@PURE_QUANTA.SCONN288_DDR506112002KQ(CHIPS)':
 'VSS104': CDS_PINID='VSS104';
NODE_NAME     J26 242
 '@T6G_MB_LIB.T6G(SCH_1):PAGE98_I160@PURE_QUANTA.SCONN288_DDR506112002KQ(CHIPS)':
 'VSS105': CDS_PINID='VSS105';
NODE_NAME     J26 244
 '@T6G_MB_LIB.T6G(SCH_1):PAGE98_I160@PURE_QUANTA.SCONN288_DDR506112002KQ(CHIPS)':
 'VSS106': CDS_PINID='VSS106';
NODE_NAME     J26 246
 '@T6G_MB_LIB.T6G(SCH_1):PAGE98_I160@PURE_QUANTA.SCONN288_DDR506112002KQ(CHIPS)':
 'VSS107': CDS_PINID='VSS107';
NODE_NAME     J26 248
 '@T6G_MB_LIB.T6G(SCH_1):PAGE98_I160@PURE_QUANTA.SCONN288_DDR506112002KQ(CHIPS)':
 'VSS108': CDS_PINID='VSS108';
NODE_NAME     J26 251
 '@T6G_MB_LIB.T6G(SCH_1):PAGE98_I160@PURE_QUANTA.SCONN288_DDR506112002KQ(CHIPS)':
 'VSS109': CDS_PINID='VSS109';
NODE_NAME     J26 253
 '@T6G_MB_LIB.T6G(SCH_1):PAGE98_I160@PURE_QUANTA.SCONN288_DDR506112002KQ(CHIPS)':
 'VSS110': CDS_PINID='VSS110';
NODE_NAME     J26 255
 '@T6G_MB_LIB.T6G(SCH_1):PAGE98_I160@PURE_QUANTA.SCONN288_DDR506112002KQ(CHIPS)':
 'VSS111': CDS_PINID='VSS111';
NODE_NAME     J26 257
 '@T6G_MB_LIB.T6G(SCH_1):PAGE98_I160@PURE_QUANTA.SCONN288_DDR506112002KQ(CHIPS)':
 'VSS112': CDS_PINID='VSS112';
NODE_NAME     J26 259
 '@T6G_MB_LIB.T6G(SCH_1):PAGE98_I160@PURE_QUANTA.SCONN288_DDR506112002KQ(CHIPS)':
 'VSS113': CDS_PINID='VSS113';
NODE_NAME     J26 262
 '@T6G_MB_LIB.T6G(SCH_1):PAGE98_I160@PURE_QUANTA.SCONN288_DDR506112002KQ(CHIPS)':
 'VSS114': CDS_PINID='VSS114';
NODE_NAME     J26 264
 '@T6G_MB_LIB.T6G(SCH_1):PAGE98_I160@PURE_QUANTA.SCONN288_DDR506112002KQ(CHIPS)':
 'VSS115': CDS_PINID='VSS115';
NODE_NAME     J26 266
 '@T6G_MB_LIB.T6G(SCH_1):PAGE98_I160@PURE_QUANTA.SCONN288_DDR506112002KQ(CHIPS)':
 'VSS116': CDS_PINID='VSS116';
NODE_NAME     J26 268
 '@T6G_MB_LIB.T6G(SCH_1):PAGE98_I160@PURE_QUANTA.SCONN288_DDR506112002KQ(CHIPS)':
 'VSS117': CDS_PINID='VSS117';
NODE_NAME     J26 270
 '@T6G_MB_LIB.T6G(SCH_1):PAGE98_I160@PURE_QUANTA.SCONN288_DDR506112002KQ(CHIPS)':
 'VSS118': CDS_PINID='VSS118';
NODE_NAME     J26 273
 '@T6G_MB_LIB.T6G(SCH_1):PAGE98_I160@PURE_QUANTA.SCONN288_DDR506112002KQ(CHIPS)':
 'VSS119': CDS_PINID='VSS119';
NODE_NAME     J26 275
 '@T6G_MB_LIB.T6G(SCH_1):PAGE98_I160@PURE_QUANTA.SCONN288_DDR506112002KQ(CHIPS)':
 'VSS120': CDS_PINID='VSS120';
NODE_NAME     J26 277
 '@T6G_MB_LIB.T6G(SCH_1):PAGE98_I160@PURE_QUANTA.SCONN288_DDR506112002KQ(CHIPS)':
 'VSS121': CDS_PINID='VSS121';
NODE_NAME     J26 279
 '@T6G_MB_LIB.T6G(SCH_1):PAGE98_I160@PURE_QUANTA.SCONN288_DDR506112002KQ(CHIPS)':
 'VSS122': CDS_PINID='VSS122';
NODE_NAME     J26 281
 '@T6G_MB_LIB.T6G(SCH_1):PAGE98_I160@PURE_QUANTA.SCONN288_DDR506112002KQ(CHIPS)':
 'VSS123': CDS_PINID='VSS123';
NODE_NAME     J26 284
 '@T6G_MB_LIB.T6G(SCH_1):PAGE98_I160@PURE_QUANTA.SCONN288_DDR506112002KQ(CHIPS)':
 'VSS124': CDS_PINID='VSS124';
NODE_NAME     J26 286
 '@T6G_MB_LIB.T6G(SCH_1):PAGE98_I160@PURE_QUANTA.SCONN288_DDR506112002KQ(CHIPS)':
 'VSS125': CDS_PINID='VSS125';
NODE_NAME     J26 288
 '@T6G_MB_LIB.T6G(SCH_1):PAGE98_I160@PURE_QUANTA.SCONN288_DDR506112002KQ(CHIPS)':
 'VSS126': CDS_PINID='VSS126';
NODE_NAME     C140 2
 '@T6G_MB_LIB.T6G(SCH_1):PAGE98_I185@PURE_QUANTA.Q_CAP(CHIPS)':
 'B': CDS_PINID='B';
NODE_NAME     C175 2
 '@T6G_MB_LIB.T6G(SCH_1):PAGE98_I238@PURE_QUANTA.Q_CAP(CHIPS)':
 'B': CDS_PINID='B';
NODE_NAME     C177 2
 '@T6G_MB_LIB.T6G(SCH_1):PAGE98_I239@PURE_QUANTA.Q_CAP(CHIPS)':
 'B': CDS_PINID='B';
NODE_NAME     R771 2
 '@T6G_MB_LIB.T6G(SCH_1):PAGE99_I148@PURE_QUANTA.Q_RES(CHIPS)':
 'B': CDS_PINID='B';
NODE_NAME     J28 G1
 '@T6G_MB_LIB.T6G(SCH_1):PAGE99_I155@PURE_QUANTA.SCONN288_DDR506112002KQ(CHIPS)':
 'G1': CDS_PINID='G1';
NODE_NAME     J28 G2
 '@T6G_MB_LIB.T6G(SCH_1):PAGE99_I155@PURE_QUANTA.SCONN288_DDR506112002KQ(CHIPS)':
 'G2': CDS_PINID='G2';
NODE_NAME     J28 G3
 '@T6G_MB_LIB.T6G(SCH_1):PAGE99_I155@PURE_QUANTA.SCONN288_DDR506112002KQ(CHIPS)':
 'G3': CDS_PINID='G3';
NODE_NAME     J28 6
 '@T6G_MB_LIB.T6G(SCH_1):PAGE99_I155@PURE_QUANTA.SCONN288_DDR506112002KQ(CHIPS)':
 'VSS0': CDS_PINID='VSS0';
NODE_NAME     J28 8
 '@T6G_MB_LIB.T6G(SCH_1):PAGE99_I155@PURE_QUANTA.SCONN288_DDR506112002KQ(CHIPS)':
 'VSS1': CDS_PINID='VSS1';
NODE_NAME     J28 10
 '@T6G_MB_LIB.T6G(SCH_1):PAGE99_I155@PURE_QUANTA.SCONN288_DDR506112002KQ(CHIPS)':
 'VSS2': CDS_PINID='VSS2';
NODE_NAME     J28 13
 '@T6G_MB_LIB.T6G(SCH_1):PAGE99_I155@PURE_QUANTA.SCONN288_DDR506112002KQ(CHIPS)':
 'VSS3': CDS_PINID='VSS3';
NODE_NAME     J28 15
 '@T6G_MB_LIB.T6G(SCH_1):PAGE99_I155@PURE_QUANTA.SCONN288_DDR506112002KQ(CHIPS)':
 'VSS4': CDS_PINID='VSS4';
NODE_NAME     J28 17
 '@T6G_MB_LIB.T6G(SCH_1):PAGE99_I155@PURE_QUANTA.SCONN288_DDR506112002KQ(CHIPS)':
 'VSS5': CDS_PINID='VSS5';
NODE_NAME     J28 19
 '@T6G_MB_LIB.T6G(SCH_1):PAGE99_I155@PURE_QUANTA.SCONN288_DDR506112002KQ(CHIPS)':
 'VSS6': CDS_PINID='VSS6';
NODE_NAME     J28 21
 '@T6G_MB_LIB.T6G(SCH_1):PAGE99_I155@PURE_QUANTA.SCONN288_DDR506112002KQ(CHIPS)':
 'VSS7': CDS_PINID='VSS7';
NODE_NAME     J28 24
 '@T6G_MB_LIB.T6G(SCH_1):PAGE99_I155@PURE_QUANTA.SCONN288_DDR506112002KQ(CHIPS)':
 'VSS8': CDS_PINID='VSS8';
NODE_NAME     J28 26
 '@T6G_MB_LIB.T6G(SCH_1):PAGE99_I155@PURE_QUANTA.SCONN288_DDR506112002KQ(CHIPS)':
 'VSS9': CDS_PINID='VSS9';
NODE_NAME     J28 28
 '@T6G_MB_LIB.T6G(SCH_1):PAGE99_I155@PURE_QUANTA.SCONN288_DDR506112002KQ(CHIPS)':
 'VSS10': CDS_PINID='VSS10';
NODE_NAME     J28 30
 '@T6G_MB_LIB.T6G(SCH_1):PAGE99_I155@PURE_QUANTA.SCONN288_DDR506112002KQ(CHIPS)':
 'VSS11': CDS_PINID='VSS11';
NODE_NAME     J28 32
 '@T6G_MB_LIB.T6G(SCH_1):PAGE99_I155@PURE_QUANTA.SCONN288_DDR506112002KQ(CHIPS)':
 'VSS12': CDS_PINID='VSS12';
NODE_NAME     J28 35
 '@T6G_MB_LIB.T6G(SCH_1):PAGE99_I155@PURE_QUANTA.SCONN288_DDR506112002KQ(CHIPS)':
 'VSS13': CDS_PINID='VSS13';
NODE_NAME     J28 37
 '@T6G_MB_LIB.T6G(SCH_1):PAGE99_I155@PURE_QUANTA.SCONN288_DDR506112002KQ(CHIPS)':
 'VSS14': CDS_PINID='VSS14';
NODE_NAME     J28 39
 '@T6G_MB_LIB.T6G(SCH_1):PAGE99_I155@PURE_QUANTA.SCONN288_DDR506112002KQ(CHIPS)':
 'VSS15': CDS_PINID='VSS15';
NODE_NAME     J28 41
 '@T6G_MB_LIB.T6G(SCH_1):PAGE99_I155@PURE_QUANTA.SCONN288_DDR506112002KQ(CHIPS)':
 'VSS16': CDS_PINID='VSS16';
NODE_NAME     J28 43
 '@T6G_MB_LIB.T6G(SCH_1):PAGE99_I155@PURE_QUANTA.SCONN288_DDR506112002KQ(CHIPS)':
 'VSS17': CDS_PINID='VSS17';
NODE_NAME     J28 46
 '@T6G_MB_LIB.T6G(SCH_1):PAGE99_I155@PURE_QUANTA.SCONN288_DDR506112002KQ(CHIPS)':
 'VSS18': CDS_PINID='VSS18';
NODE_NAME     J28 48
 '@T6G_MB_LIB.T6G(SCH_1):PAGE99_I155@PURE_QUANTA.SCONN288_DDR506112002KQ(CHIPS)':
 'VSS19': CDS_PINID='VSS19';
NODE_NAME     J28 50
 '@T6G_MB_LIB.T6G(SCH_1):PAGE99_I155@PURE_QUANTA.SCONN288_DDR506112002KQ(CHIPS)':
 'VSS20': CDS_PINID='VSS20';
NODE_NAME     J28 52
 '@T6G_MB_LIB.T6G(SCH_1):PAGE99_I155@PURE_QUANTA.SCONN288_DDR506112002KQ(CHIPS)':
 'VSS21': CDS_PINID='VSS21';
NODE_NAME     J28 54
 '@T6G_MB_LIB.T6G(SCH_1):PAGE99_I155@PURE_QUANTA.SCONN288_DDR506112002KQ(CHIPS)':
 'VSS22': CDS_PINID='VSS22';
NODE_NAME     J28 57
 '@T6G_MB_LIB.T6G(SCH_1):PAGE99_I155@PURE_QUANTA.SCONN288_DDR506112002KQ(CHIPS)':
 'VSS23': CDS_PINID='VSS23';
NODE_NAME     J28 59
 '@T6G_MB_LIB.T6G(SCH_1):PAGE99_I155@PURE_QUANTA.SCONN288_DDR506112002KQ(CHIPS)':
 'VSS24': CDS_PINID='VSS24';
NODE_NAME     J28 61
 '@T6G_MB_LIB.T6G(SCH_1):PAGE99_I155@PURE_QUANTA.SCONN288_DDR506112002KQ(CHIPS)':
 'VSS25': CDS_PINID='VSS25';
NODE_NAME     J28 63
 '@T6G_MB_LIB.T6G(SCH_1):PAGE99_I155@PURE_QUANTA.SCONN288_DDR506112002KQ(CHIPS)':
 'VSS26': CDS_PINID='VSS26';
NODE_NAME     J28 65
 '@T6G_MB_LIB.T6G(SCH_1):PAGE99_I155@PURE_QUANTA.SCONN288_DDR506112002KQ(CHIPS)':
 'VSS27': CDS_PINID='VSS27';
NODE_NAME     J28 67
 '@T6G_MB_LIB.T6G(SCH_1):PAGE99_I155@PURE_QUANTA.SCONN288_DDR506112002KQ(CHIPS)':
 'VSS28': CDS_PINID='VSS28';
NODE_NAME     J28 69
 '@T6G_MB_LIB.T6G(SCH_1):PAGE99_I155@PURE_QUANTA.SCONN288_DDR506112002KQ(CHIPS)':
 'VSS29': CDS_PINID='VSS29';
NODE_NAME     J28 71
 '@T6G_MB_LIB.T6G(SCH_1):PAGE99_I155@PURE_QUANTA.SCONN288_DDR506112002KQ(CHIPS)':
 'VSS30': CDS_PINID='VSS30';
NODE_NAME     J28 73
 '@T6G_MB_LIB.T6G(SCH_1):PAGE99_I155@PURE_QUANTA.SCONN288_DDR506112002KQ(CHIPS)':
 'VSS31': CDS_PINID='VSS31';
NODE_NAME     J28 75
 '@T6G_MB_LIB.T6G(SCH_1):PAGE99_I155@PURE_QUANTA.SCONN288_DDR506112002KQ(CHIPS)':
 'VSS32': CDS_PINID='VSS32';
NODE_NAME     J28 77
 '@T6G_MB_LIB.T6G(SCH_1):PAGE99_I155@PURE_QUANTA.SCONN288_DDR506112002KQ(CHIPS)':
 'VSS33': CDS_PINID='VSS33';
NODE_NAME     J28 79
 '@T6G_MB_LIB.T6G(SCH_1):PAGE99_I155@PURE_QUANTA.SCONN288_DDR506112002KQ(CHIPS)':
 'VSS34': CDS_PINID='VSS34';
NODE_NAME     J28 81
 '@T6G_MB_LIB.T6G(SCH_1):PAGE99_I155@PURE_QUANTA.SCONN288_DDR506112002KQ(CHIPS)':
 'VSS35': CDS_PINID='VSS35';
NODE_NAME     J28 83
 '@T6G_MB_LIB.T6G(SCH_1):PAGE99_I155@PURE_QUANTA.SCONN288_DDR506112002KQ(CHIPS)':
 'VSS36': CDS_PINID='VSS36';
NODE_NAME     J28 85
 '@T6G_MB_LIB.T6G(SCH_1):PAGE99_I155@PURE_QUANTA.SCONN288_DDR506112002KQ(CHIPS)':
 'VSS37': CDS_PINID='VSS37';
NODE_NAME     J28 88
 '@T6G_MB_LIB.T6G(SCH_1):PAGE99_I155@PURE_QUANTA.SCONN288_DDR506112002KQ(CHIPS)':
 'VSS38': CDS_PINID='VSS38';
NODE_NAME     J28 90
 '@T6G_MB_LIB.T6G(SCH_1):PAGE99_I155@PURE_QUANTA.SCONN288_DDR506112002KQ(CHIPS)':
 'VSS39': CDS_PINID='VSS39';
NODE_NAME     J28 92
 '@T6G_MB_LIB.T6G(SCH_1):PAGE99_I155@PURE_QUANTA.SCONN288_DDR506112002KQ(CHIPS)':
 'VSS40': CDS_PINID='VSS40';
NODE_NAME     J28 95
 '@T6G_MB_LIB.T6G(SCH_1):PAGE99_I155@PURE_QUANTA.SCONN288_DDR506112002KQ(CHIPS)':
 'VSS41': CDS_PINID='VSS41';
NODE_NAME     J28 97
 '@T6G_MB_LIB.T6G(SCH_1):PAGE99_I155@PURE_QUANTA.SCONN288_DDR506112002KQ(CHIPS)':
 'VSS42': CDS_PINID='VSS42';
NODE_NAME     J28 99
 '@T6G_MB_LIB.T6G(SCH_1):PAGE99_I155@PURE_QUANTA.SCONN288_DDR506112002KQ(CHIPS)':
 'VSS43': CDS_PINID='VSS43';
NODE_NAME     J28 101
 '@T6G_MB_LIB.T6G(SCH_1):PAGE99_I155@PURE_QUANTA.SCONN288_DDR506112002KQ(CHIPS)':
 'VSS44': CDS_PINID='VSS44';
NODE_NAME     J28 103
 '@T6G_MB_LIB.T6G(SCH_1):PAGE99_I155@PURE_QUANTA.SCONN288_DDR506112002KQ(CHIPS)':
 'VSS45': CDS_PINID='VSS45';
NODE_NAME     J28 106
 '@T6G_MB_LIB.T6G(SCH_1):PAGE99_I155@PURE_QUANTA.SCONN288_DDR506112002KQ(CHIPS)':
 'VSS46': CDS_PINID='VSS46';
NODE_NAME     J28 108
 '@T6G_MB_LIB.T6G(SCH_1):PAGE99_I155@PURE_QUANTA.SCONN288_DDR506112002KQ(CHIPS)':
 'VSS47': CDS_PINID='VSS47';
NODE_NAME     J28 110
 '@T6G_MB_LIB.T6G(SCH_1):PAGE99_I155@PURE_QUANTA.SCONN288_DDR506112002KQ(CHIPS)':
 'VSS48': CDS_PINID='VSS48';
NODE_NAME     J28 112
 '@T6G_MB_LIB.T6G(SCH_1):PAGE99_I155@PURE_QUANTA.SCONN288_DDR506112002KQ(CHIPS)':
 'VSS49': CDS_PINID='VSS49';
NODE_NAME     J28 114
 '@T6G_MB_LIB.T6G(SCH_1):PAGE99_I155@PURE_QUANTA.SCONN288_DDR506112002KQ(CHIPS)':
 'VSS50': CDS_PINID='VSS50';
NODE_NAME     J28 117
 '@T6G_MB_LIB.T6G(SCH_1):PAGE99_I155@PURE_QUANTA.SCONN288_DDR506112002KQ(CHIPS)':
 'VSS51': CDS_PINID='VSS51';
NODE_NAME     J28 119
 '@T6G_MB_LIB.T6G(SCH_1):PAGE99_I155@PURE_QUANTA.SCONN288_DDR506112002KQ(CHIPS)':
 'VSS52': CDS_PINID='VSS52';
NODE_NAME     J28 121
 '@T6G_MB_LIB.T6G(SCH_1):PAGE99_I155@PURE_QUANTA.SCONN288_DDR506112002KQ(CHIPS)':
 'VSS53': CDS_PINID='VSS53';
NODE_NAME     J28 123
 '@T6G_MB_LIB.T6G(SCH_1):PAGE99_I155@PURE_QUANTA.SCONN288_DDR506112002KQ(CHIPS)':
 'VSS54': CDS_PINID='VSS54';
NODE_NAME     J28 125
 '@T6G_MB_LIB.T6G(SCH_1):PAGE99_I155@PURE_QUANTA.SCONN288_DDR506112002KQ(CHIPS)':
 'VSS55': CDS_PINID='VSS55';
NODE_NAME     J28 128
 '@T6G_MB_LIB.T6G(SCH_1):PAGE99_I155@PURE_QUANTA.SCONN288_DDR506112002KQ(CHIPS)':
 'VSS56': CDS_PINID='VSS56';
NODE_NAME     J28 130
 '@T6G_MB_LIB.T6G(SCH_1):PAGE99_I155@PURE_QUANTA.SCONN288_DDR506112002KQ(CHIPS)':
 'VSS57': CDS_PINID='VSS57';
NODE_NAME     J28 132
 '@T6G_MB_LIB.T6G(SCH_1):PAGE99_I155@PURE_QUANTA.SCONN288_DDR506112002KQ(CHIPS)':
 'VSS58': CDS_PINID='VSS58';
NODE_NAME     J28 134
 '@T6G_MB_LIB.T6G(SCH_1):PAGE99_I155@PURE_QUANTA.SCONN288_DDR506112002KQ(CHIPS)':
 'VSS59': CDS_PINID='VSS59';
NODE_NAME     J28 136
 '@T6G_MB_LIB.T6G(SCH_1):PAGE99_I155@PURE_QUANTA.SCONN288_DDR506112002KQ(CHIPS)':
 'VSS60': CDS_PINID='VSS60';
NODE_NAME     J28 139
 '@T6G_MB_LIB.T6G(SCH_1):PAGE99_I155@PURE_QUANTA.SCONN288_DDR506112002KQ(CHIPS)':
 'VSS61': CDS_PINID='VSS61';
NODE_NAME     J28 141
 '@T6G_MB_LIB.T6G(SCH_1):PAGE99_I155@PURE_QUANTA.SCONN288_DDR506112002KQ(CHIPS)':
 'VSS62': CDS_PINID='VSS62';
NODE_NAME     J28 143
 '@T6G_MB_LIB.T6G(SCH_1):PAGE99_I155@PURE_QUANTA.SCONN288_DDR506112002KQ(CHIPS)':
 'VSS63': CDS_PINID='VSS63';
NODE_NAME     J28 151
 '@T6G_MB_LIB.T6G(SCH_1):PAGE99_I155@PURE_QUANTA.SCONN288_DDR506112002KQ(CHIPS)':
 'VSS64': CDS_PINID='VSS64';
NODE_NAME     J28 153
 '@T6G_MB_LIB.T6G(SCH_1):PAGE99_I155@PURE_QUANTA.SCONN288_DDR506112002KQ(CHIPS)':
 'VSS65': CDS_PINID='VSS65';
NODE_NAME     J28 155
 '@T6G_MB_LIB.T6G(SCH_1):PAGE99_I155@PURE_QUANTA.SCONN288_DDR506112002KQ(CHIPS)':
 'VSS66': CDS_PINID='VSS66';
NODE_NAME     J28 158
 '@T6G_MB_LIB.T6G(SCH_1):PAGE99_I155@PURE_QUANTA.SCONN288_DDR506112002KQ(CHIPS)':
 'VSS67': CDS_PINID='VSS67';
NODE_NAME     J28 160
 '@T6G_MB_LIB.T6G(SCH_1):PAGE99_I155@PURE_QUANTA.SCONN288_DDR506112002KQ(CHIPS)':
 'VSS68': CDS_PINID='VSS68';
NODE_NAME     J28 162
 '@T6G_MB_LIB.T6G(SCH_1):PAGE99_I155@PURE_QUANTA.SCONN288_DDR506112002KQ(CHIPS)':
 'VSS69': CDS_PINID='VSS69';
NODE_NAME     J28 164
 '@T6G_MB_LIB.T6G(SCH_1):PAGE99_I155@PURE_QUANTA.SCONN288_DDR506112002KQ(CHIPS)':
 'VSS70': CDS_PINID='VSS70';
NODE_NAME     J28 166
 '@T6G_MB_LIB.T6G(SCH_1):PAGE99_I155@PURE_QUANTA.SCONN288_DDR506112002KQ(CHIPS)':
 'VSS71': CDS_PINID='VSS71';
NODE_NAME     J28 169
 '@T6G_MB_LIB.T6G(SCH_1):PAGE99_I155@PURE_QUANTA.SCONN288_DDR506112002KQ(CHIPS)':
 'VSS72': CDS_PINID='VSS72';
NODE_NAME     J28 171
 '@T6G_MB_LIB.T6G(SCH_1):PAGE99_I155@PURE_QUANTA.SCONN288_DDR506112002KQ(CHIPS)':
 'VSS73': CDS_PINID='VSS73';
NODE_NAME     J28 173
 '@T6G_MB_LIB.T6G(SCH_1):PAGE99_I155@PURE_QUANTA.SCONN288_DDR506112002KQ(CHIPS)':
 'VSS74': CDS_PINID='VSS74';
NODE_NAME     J28 175
 '@T6G_MB_LIB.T6G(SCH_1):PAGE99_I155@PURE_QUANTA.SCONN288_DDR506112002KQ(CHIPS)':
 'VSS75': CDS_PINID='VSS75';
NODE_NAME     J28 177
 '@T6G_MB_LIB.T6G(SCH_1):PAGE99_I155@PURE_QUANTA.SCONN288_DDR506112002KQ(CHIPS)':
 'VSS76': CDS_PINID='VSS76';
NODE_NAME     J28 180
 '@T6G_MB_LIB.T6G(SCH_1):PAGE99_I155@PURE_QUANTA.SCONN288_DDR506112002KQ(CHIPS)':
 'VSS77': CDS_PINID='VSS77';
NODE_NAME     J28 182
 '@T6G_MB_LIB.T6G(SCH_1):PAGE99_I155@PURE_QUANTA.SCONN288_DDR506112002KQ(CHIPS)':
 'VSS78': CDS_PINID='VSS78';
NODE_NAME     J28 184
 '@T6G_MB_LIB.T6G(SCH_1):PAGE99_I155@PURE_QUANTA.SCONN288_DDR506112002KQ(CHIPS)':
 'VSS79': CDS_PINID='VSS79';
NODE_NAME     J28 186
 '@T6G_MB_LIB.T6G(SCH_1):PAGE99_I155@PURE_QUANTA.SCONN288_DDR506112002KQ(CHIPS)':
 'VSS80': CDS_PINID='VSS80';
NODE_NAME     J28 188
 '@T6G_MB_LIB.T6G(SCH_1):PAGE99_I155@PURE_QUANTA.SCONN288_DDR506112002KQ(CHIPS)':
 'VSS81': CDS_PINID='VSS81';
NODE_NAME     J28 191
 '@T6G_MB_LIB.T6G(SCH_1):PAGE99_I155@PURE_QUANTA.SCONN288_DDR506112002KQ(CHIPS)':
 'VSS82': CDS_PINID='VSS82';
NODE_NAME     J28 193
 '@T6G_MB_LIB.T6G(SCH_1):PAGE99_I155@PURE_QUANTA.SCONN288_DDR506112002KQ(CHIPS)':
 'VSS83': CDS_PINID='VSS83';
NODE_NAME     J28 195
 '@T6G_MB_LIB.T6G(SCH_1):PAGE99_I155@PURE_QUANTA.SCONN288_DDR506112002KQ(CHIPS)':
 'VSS84': CDS_PINID='VSS84';
NODE_NAME     J28 197
 '@T6G_MB_LIB.T6G(SCH_1):PAGE99_I155@PURE_QUANTA.SCONN288_DDR506112002KQ(CHIPS)':
 'VSS85': CDS_PINID='VSS85';
NODE_NAME     J28 199
 '@T6G_MB_LIB.T6G(SCH_1):PAGE99_I155@PURE_QUANTA.SCONN288_DDR506112002KQ(CHIPS)':
 'VSS86': CDS_PINID='VSS86';
NODE_NAME     J28 202
 '@T6G_MB_LIB.T6G(SCH_1):PAGE99_I155@PURE_QUANTA.SCONN288_DDR506112002KQ(CHIPS)':
 'VSS87': CDS_PINID='VSS87';
NODE_NAME     J28 204
 '@T6G_MB_LIB.T6G(SCH_1):PAGE99_I155@PURE_QUANTA.SCONN288_DDR506112002KQ(CHIPS)':
 'VSS88': CDS_PINID='VSS88';
NODE_NAME     J28 206
 '@T6G_MB_LIB.T6G(SCH_1):PAGE99_I155@PURE_QUANTA.SCONN288_DDR506112002KQ(CHIPS)':
 'VSS89': CDS_PINID='VSS89';
NODE_NAME     J28 208
 '@T6G_MB_LIB.T6G(SCH_1):PAGE99_I155@PURE_QUANTA.SCONN288_DDR506112002KQ(CHIPS)':
 'VSS90': CDS_PINID='VSS90';
NODE_NAME     J28 210
 '@T6G_MB_LIB.T6G(SCH_1):PAGE99_I155@PURE_QUANTA.SCONN288_DDR506112002KQ(CHIPS)':
 'VSS91': CDS_PINID='VSS91';
NODE_NAME     J28 212
 '@T6G_MB_LIB.T6G(SCH_1):PAGE99_I155@PURE_QUANTA.SCONN288_DDR506112002KQ(CHIPS)':
 'VSS92': CDS_PINID='VSS92';
NODE_NAME     J28 214
 '@T6G_MB_LIB.T6G(SCH_1):PAGE99_I155@PURE_QUANTA.SCONN288_DDR506112002KQ(CHIPS)':
 'VSS93': CDS_PINID='VSS93';
NODE_NAME     J28 216
 '@T6G_MB_LIB.T6G(SCH_1):PAGE99_I155@PURE_QUANTA.SCONN288_DDR506112002KQ(CHIPS)':
 'VSS94': CDS_PINID='VSS94';
NODE_NAME     J28 219
 '@T6G_MB_LIB.T6G(SCH_1):PAGE99_I155@PURE_QUANTA.SCONN288_DDR506112002KQ(CHIPS)':
 'VSS95': CDS_PINID='VSS95';
NODE_NAME     J28 222
 '@T6G_MB_LIB.T6G(SCH_1):PAGE99_I155@PURE_QUANTA.SCONN288_DDR506112002KQ(CHIPS)':
 'VSS96': CDS_PINID='VSS96';
NODE_NAME     J28 224
 '@T6G_MB_LIB.T6G(SCH_1):PAGE99_I155@PURE_QUANTA.SCONN288_DDR506112002KQ(CHIPS)':
 'VSS97': CDS_PINID='VSS97';
NODE_NAME     J28 226
 '@T6G_MB_LIB.T6G(SCH_1):PAGE99_I155@PURE_QUANTA.SCONN288_DDR506112002KQ(CHIPS)':
 'VSS98': CDS_PINID='VSS98';
NODE_NAME     J28 228
 '@T6G_MB_LIB.T6G(SCH_1):PAGE99_I155@PURE_QUANTA.SCONN288_DDR506112002KQ(CHIPS)':
 'VSS99': CDS_PINID='VSS99';
NODE_NAME     J28 230
 '@T6G_MB_LIB.T6G(SCH_1):PAGE99_I155@PURE_QUANTA.SCONN288_DDR506112002KQ(CHIPS)':
 'VSS100': CDS_PINID='VSS100';
NODE_NAME     J28 233
 '@T6G_MB_LIB.T6G(SCH_1):PAGE99_I155@PURE_QUANTA.SCONN288_DDR506112002KQ(CHIPS)':
 'VSS101': CDS_PINID='VSS101';
NODE_NAME     J28 235
 '@T6G_MB_LIB.T6G(SCH_1):PAGE99_I155@PURE_QUANTA.SCONN288_DDR506112002KQ(CHIPS)':
 'VSS102': CDS_PINID='VSS102';
NODE_NAME     J28 237
 '@T6G_MB_LIB.T6G(SCH_1):PAGE99_I155@PURE_QUANTA.SCONN288_DDR506112002KQ(CHIPS)':
 'VSS103': CDS_PINID='VSS103';
NODE_NAME     J28 240
 '@T6G_MB_LIB.T6G(SCH_1):PAGE99_I155@PURE_QUANTA.SCONN288_DDR506112002KQ(CHIPS)':
 'VSS104': CDS_PINID='VSS104';
NODE_NAME     J28 242
 '@T6G_MB_LIB.T6G(SCH_1):PAGE99_I155@PURE_QUANTA.SCONN288_DDR506112002KQ(CHIPS)':
 'VSS105': CDS_PINID='VSS105';
NODE_NAME     J28 244
 '@T6G_MB_LIB.T6G(SCH_1):PAGE99_I155@PURE_QUANTA.SCONN288_DDR506112002KQ(CHIPS)':
 'VSS106': CDS_PINID='VSS106';
NODE_NAME     J28 246
 '@T6G_MB_LIB.T6G(SCH_1):PAGE99_I155@PURE_QUANTA.SCONN288_DDR506112002KQ(CHIPS)':
 'VSS107': CDS_PINID='VSS107';
NODE_NAME     J28 248
 '@T6G_MB_LIB.T6G(SCH_1):PAGE99_I155@PURE_QUANTA.SCONN288_DDR506112002KQ(CHIPS)':
 'VSS108': CDS_PINID='VSS108';
NODE_NAME     J28 251
 '@T6G_MB_LIB.T6G(SCH_1):PAGE99_I155@PURE_QUANTA.SCONN288_DDR506112002KQ(CHIPS)':
 'VSS109': CDS_PINID='VSS109';
NODE_NAME     J28 253
 '@T6G_MB_LIB.T6G(SCH_1):PAGE99_I155@PURE_QUANTA.SCONN288_DDR506112002KQ(CHIPS)':
 'VSS110': CDS_PINID='VSS110';
NODE_NAME     J28 255
 '@T6G_MB_LIB.T6G(SCH_1):PAGE99_I155@PURE_QUANTA.SCONN288_DDR506112002KQ(CHIPS)':
 'VSS111': CDS_PINID='VSS111';
NODE_NAME     J28 257
 '@T6G_MB_LIB.T6G(SCH_1):PAGE99_I155@PURE_QUANTA.SCONN288_DDR506112002KQ(CHIPS)':
 'VSS112': CDS_PINID='VSS112';
NODE_NAME     J28 259
 '@T6G_MB_LIB.T6G(SCH_1):PAGE99_I155@PURE_QUANTA.SCONN288_DDR506112002KQ(CHIPS)':
 'VSS113': CDS_PINID='VSS113';
NODE_NAME     J28 262
 '@T6G_MB_LIB.T6G(SCH_1):PAGE99_I155@PURE_QUANTA.SCONN288_DDR506112002KQ(CHIPS)':
 'VSS114': CDS_PINID='VSS114';
NODE_NAME     J28 264
 '@T6G_MB_LIB.T6G(SCH_1):PAGE99_I155@PURE_QUANTA.SCONN288_DDR506112002KQ(CHIPS)':
 'VSS115': CDS_PINID='VSS115';
NODE_NAME     J28 266
 '@T6G_MB_LIB.T6G(SCH_1):PAGE99_I155@PURE_QUANTA.SCONN288_DDR506112002KQ(CHIPS)':
 'VSS116': CDS_PINID='VSS116';
NODE_NAME     J28 268
 '@T6G_MB_LIB.T6G(SCH_1):PAGE99_I155@PURE_QUANTA.SCONN288_DDR506112002KQ(CHIPS)':
 'VSS117': CDS_PINID='VSS117';
NODE_NAME     J28 270
 '@T6G_MB_LIB.T6G(SCH_1):PAGE99_I155@PURE_QUANTA.SCONN288_DDR506112002KQ(CHIPS)':
 'VSS118': CDS_PINID='VSS118';
NODE_NAME     J28 273
 '@T6G_MB_LIB.T6G(SCH_1):PAGE99_I155@PURE_QUANTA.SCONN288_DDR506112002KQ(CHIPS)':
 'VSS119': CDS_PINID='VSS119';
NODE_NAME     J28 275
 '@T6G_MB_LIB.T6G(SCH_1):PAGE99_I155@PURE_QUANTA.SCONN288_DDR506112002KQ(CHIPS)':
 'VSS120': CDS_PINID='VSS120';
NODE_NAME     J28 277
 '@T6G_MB_LIB.T6G(SCH_1):PAGE99_I155@PURE_QUANTA.SCONN288_DDR506112002KQ(CHIPS)':
 'VSS121': CDS_PINID='VSS121';
NODE_NAME     J28 279
 '@T6G_MB_LIB.T6G(SCH_1):PAGE99_I155@PURE_QUANTA.SCONN288_DDR506112002KQ(CHIPS)':
 'VSS122': CDS_PINID='VSS122';
NODE_NAME     J28 281
 '@T6G_MB_LIB.T6G(SCH_1):PAGE99_I155@PURE_QUANTA.SCONN288_DDR506112002KQ(CHIPS)':
 'VSS123': CDS_PINID='VSS123';
NODE_NAME     J28 284
 '@T6G_MB_LIB.T6G(SCH_1):PAGE99_I155@PURE_QUANTA.SCONN288_DDR506112002KQ(CHIPS)':
 'VSS124': CDS_PINID='VSS124';
NODE_NAME     J28 286
 '@T6G_MB_LIB.T6G(SCH_1):PAGE99_I155@PURE_QUANTA.SCONN288_DDR506112002KQ(CHIPS)':
 'VSS125': CDS_PINID='VSS125';
NODE_NAME     J28 288
 '@T6G_MB_LIB.T6G(SCH_1):PAGE99_I155@PURE_QUANTA.SCONN288_DDR506112002KQ(CHIPS)':
 'VSS126': CDS_PINID='VSS126';
NODE_NAME     C144 2
 '@T6G_MB_LIB.T6G(SCH_1):PAGE99_I185@PURE_QUANTA.Q_CAP(CHIPS)':
 'B': CDS_PINID='B';
NODE_NAME     C178 2
 '@T6G_MB_LIB.T6G(SCH_1):PAGE99_I238@PURE_QUANTA.Q_CAP(CHIPS)':
 'B': CDS_PINID='B';
NODE_NAME     C179 2
 '@T6G_MB_LIB.T6G(SCH_1):PAGE99_I239@PURE_QUANTA.Q_CAP(CHIPS)':
 'B': CDS_PINID='B';
NODE_NAME     R772 2
 '@T6G_MB_LIB.T6G(SCH_1):PAGE100_I146@PURE_QUANTA.Q_RES(CHIPS)':
 'B': CDS_PINID='B';
NODE_NAME     J30 G1
 '@T6G_MB_LIB.T6G(SCH_1):PAGE100_I161@PURE_QUANTA.SCONN288_DDR506112002KQ(CHIPS)':
 'G1': CDS_PINID='G1';
NODE_NAME     J30 G2
 '@T6G_MB_LIB.T6G(SCH_1):PAGE100_I161@PURE_QUANTA.SCONN288_DDR506112002KQ(CHIPS)':
 'G2': CDS_PINID='G2';
NODE_NAME     J30 G3
 '@T6G_MB_LIB.T6G(SCH_1):PAGE100_I161@PURE_QUANTA.SCONN288_DDR506112002KQ(CHIPS)':
 'G3': CDS_PINID='G3';
NODE_NAME     J30 6
 '@T6G_MB_LIB.T6G(SCH_1):PAGE100_I161@PURE_QUANTA.SCONN288_DDR506112002KQ(CHIPS)':
 'VSS0': CDS_PINID='VSS0';
NODE_NAME     J30 8
 '@T6G_MB_LIB.T6G(SCH_1):PAGE100_I161@PURE_QUANTA.SCONN288_DDR506112002KQ(CHIPS)':
 'VSS1': CDS_PINID='VSS1';
NODE_NAME     J30 10
 '@T6G_MB_LIB.T6G(SCH_1):PAGE100_I161@PURE_QUANTA.SCONN288_DDR506112002KQ(CHIPS)':
 'VSS2': CDS_PINID='VSS2';
NODE_NAME     J30 13
 '@T6G_MB_LIB.T6G(SCH_1):PAGE100_I161@PURE_QUANTA.SCONN288_DDR506112002KQ(CHIPS)':
 'VSS3': CDS_PINID='VSS3';
NODE_NAME     J30 15
 '@T6G_MB_LIB.T6G(SCH_1):PAGE100_I161@PURE_QUANTA.SCONN288_DDR506112002KQ(CHIPS)':
 'VSS4': CDS_PINID='VSS4';
NODE_NAME     J30 17
 '@T6G_MB_LIB.T6G(SCH_1):PAGE100_I161@PURE_QUANTA.SCONN288_DDR506112002KQ(CHIPS)':
 'VSS5': CDS_PINID='VSS5';
NODE_NAME     J30 19
 '@T6G_MB_LIB.T6G(SCH_1):PAGE100_I161@PURE_QUANTA.SCONN288_DDR506112002KQ(CHIPS)':
 'VSS6': CDS_PINID='VSS6';
NODE_NAME     J30 21
 '@T6G_MB_LIB.T6G(SCH_1):PAGE100_I161@PURE_QUANTA.SCONN288_DDR506112002KQ(CHIPS)':
 'VSS7': CDS_PINID='VSS7';
NODE_NAME     J30 24
 '@T6G_MB_LIB.T6G(SCH_1):PAGE100_I161@PURE_QUANTA.SCONN288_DDR506112002KQ(CHIPS)':
 'VSS8': CDS_PINID='VSS8';
NODE_NAME     J30 26
 '@T6G_MB_LIB.T6G(SCH_1):PAGE100_I161@PURE_QUANTA.SCONN288_DDR506112002KQ(CHIPS)':
 'VSS9': CDS_PINID='VSS9';
NODE_NAME     J30 28
 '@T6G_MB_LIB.T6G(SCH_1):PAGE100_I161@PURE_QUANTA.SCONN288_DDR506112002KQ(CHIPS)':
 'VSS10': CDS_PINID='VSS10';
NODE_NAME     J30 30
 '@T6G_MB_LIB.T6G(SCH_1):PAGE100_I161@PURE_QUANTA.SCONN288_DDR506112002KQ(CHIPS)':
 'VSS11': CDS_PINID='VSS11';
NODE_NAME     J30 32
 '@T6G_MB_LIB.T6G(SCH_1):PAGE100_I161@PURE_QUANTA.SCONN288_DDR506112002KQ(CHIPS)':
 'VSS12': CDS_PINID='VSS12';
NODE_NAME     J30 35
 '@T6G_MB_LIB.T6G(SCH_1):PAGE100_I161@PURE_QUANTA.SCONN288_DDR506112002KQ(CHIPS)':
 'VSS13': CDS_PINID='VSS13';
NODE_NAME     J30 37
 '@T6G_MB_LIB.T6G(SCH_1):PAGE100_I161@PURE_QUANTA.SCONN288_DDR506112002KQ(CHIPS)':
 'VSS14': CDS_PINID='VSS14';
NODE_NAME     J30 39
 '@T6G_MB_LIB.T6G(SCH_1):PAGE100_I161@PURE_QUANTA.SCONN288_DDR506112002KQ(CHIPS)':
 'VSS15': CDS_PINID='VSS15';
NODE_NAME     J30 41
 '@T6G_MB_LIB.T6G(SCH_1):PAGE100_I161@PURE_QUANTA.SCONN288_DDR506112002KQ(CHIPS)':
 'VSS16': CDS_PINID='VSS16';
NODE_NAME     J30 43
 '@T6G_MB_LIB.T6G(SCH_1):PAGE100_I161@PURE_QUANTA.SCONN288_DDR506112002KQ(CHIPS)':
 'VSS17': CDS_PINID='VSS17';
NODE_NAME     J30 46
 '@T6G_MB_LIB.T6G(SCH_1):PAGE100_I161@PURE_QUANTA.SCONN288_DDR506112002KQ(CHIPS)':
 'VSS18': CDS_PINID='VSS18';
NODE_NAME     J30 48
 '@T6G_MB_LIB.T6G(SCH_1):PAGE100_I161@PURE_QUANTA.SCONN288_DDR506112002KQ(CHIPS)':
 'VSS19': CDS_PINID='VSS19';
NODE_NAME     J30 50
 '@T6G_MB_LIB.T6G(SCH_1):PAGE100_I161@PURE_QUANTA.SCONN288_DDR506112002KQ(CHIPS)':
 'VSS20': CDS_PINID='VSS20';
NODE_NAME     J30 52
 '@T6G_MB_LIB.T6G(SCH_1):PAGE100_I161@PURE_QUANTA.SCONN288_DDR506112002KQ(CHIPS)':
 'VSS21': CDS_PINID='VSS21';
NODE_NAME     J30 54
 '@T6G_MB_LIB.T6G(SCH_1):PAGE100_I161@PURE_QUANTA.SCONN288_DDR506112002KQ(CHIPS)':
 'VSS22': CDS_PINID='VSS22';
NODE_NAME     J30 57
 '@T6G_MB_LIB.T6G(SCH_1):PAGE100_I161@PURE_QUANTA.SCONN288_DDR506112002KQ(CHIPS)':
 'VSS23': CDS_PINID='VSS23';
NODE_NAME     J30 59
 '@T6G_MB_LIB.T6G(SCH_1):PAGE100_I161@PURE_QUANTA.SCONN288_DDR506112002KQ(CHIPS)':
 'VSS24': CDS_PINID='VSS24';
NODE_NAME     J30 61
 '@T6G_MB_LIB.T6G(SCH_1):PAGE100_I161@PURE_QUANTA.SCONN288_DDR506112002KQ(CHIPS)':
 'VSS25': CDS_PINID='VSS25';
NODE_NAME     J30 63
 '@T6G_MB_LIB.T6G(SCH_1):PAGE100_I161@PURE_QUANTA.SCONN288_DDR506112002KQ(CHIPS)':
 'VSS26': CDS_PINID='VSS26';
NODE_NAME     J30 65
 '@T6G_MB_LIB.T6G(SCH_1):PAGE100_I161@PURE_QUANTA.SCONN288_DDR506112002KQ(CHIPS)':
 'VSS27': CDS_PINID='VSS27';
NODE_NAME     J30 67
 '@T6G_MB_LIB.T6G(SCH_1):PAGE100_I161@PURE_QUANTA.SCONN288_DDR506112002KQ(CHIPS)':
 'VSS28': CDS_PINID='VSS28';
NODE_NAME     J30 69
 '@T6G_MB_LIB.T6G(SCH_1):PAGE100_I161@PURE_QUANTA.SCONN288_DDR506112002KQ(CHIPS)':
 'VSS29': CDS_PINID='VSS29';
NODE_NAME     J30 71
 '@T6G_MB_LIB.T6G(SCH_1):PAGE100_I161@PURE_QUANTA.SCONN288_DDR506112002KQ(CHIPS)':
 'VSS30': CDS_PINID='VSS30';
NODE_NAME     J30 73
 '@T6G_MB_LIB.T6G(SCH_1):PAGE100_I161@PURE_QUANTA.SCONN288_DDR506112002KQ(CHIPS)':
 'VSS31': CDS_PINID='VSS31';
NODE_NAME     J30 75
 '@T6G_MB_LIB.T6G(SCH_1):PAGE100_I161@PURE_QUANTA.SCONN288_DDR506112002KQ(CHIPS)':
 'VSS32': CDS_PINID='VSS32';
NODE_NAME     J30 77
 '@T6G_MB_LIB.T6G(SCH_1):PAGE100_I161@PURE_QUANTA.SCONN288_DDR506112002KQ(CHIPS)':
 'VSS33': CDS_PINID='VSS33';
NODE_NAME     J30 79
 '@T6G_MB_LIB.T6G(SCH_1):PAGE100_I161@PURE_QUANTA.SCONN288_DDR506112002KQ(CHIPS)':
 'VSS34': CDS_PINID='VSS34';
NODE_NAME     J30 81
 '@T6G_MB_LIB.T6G(SCH_1):PAGE100_I161@PURE_QUANTA.SCONN288_DDR506112002KQ(CHIPS)':
 'VSS35': CDS_PINID='VSS35';
NODE_NAME     J30 83
 '@T6G_MB_LIB.T6G(SCH_1):PAGE100_I161@PURE_QUANTA.SCONN288_DDR506112002KQ(CHIPS)':
 'VSS36': CDS_PINID='VSS36';
NODE_NAME     J30 85
 '@T6G_MB_LIB.T6G(SCH_1):PAGE100_I161@PURE_QUANTA.SCONN288_DDR506112002KQ(CHIPS)':
 'VSS37': CDS_PINID='VSS37';
NODE_NAME     J30 88
 '@T6G_MB_LIB.T6G(SCH_1):PAGE100_I161@PURE_QUANTA.SCONN288_DDR506112002KQ(CHIPS)':
 'VSS38': CDS_PINID='VSS38';
NODE_NAME     J30 90
 '@T6G_MB_LIB.T6G(SCH_1):PAGE100_I161@PURE_QUANTA.SCONN288_DDR506112002KQ(CHIPS)':
 'VSS39': CDS_PINID='VSS39';
NODE_NAME     J30 92
 '@T6G_MB_LIB.T6G(SCH_1):PAGE100_I161@PURE_QUANTA.SCONN288_DDR506112002KQ(CHIPS)':
 'VSS40': CDS_PINID='VSS40';
NODE_NAME     J30 95
 '@T6G_MB_LIB.T6G(SCH_1):PAGE100_I161@PURE_QUANTA.SCONN288_DDR506112002KQ(CHIPS)':
 'VSS41': CDS_PINID='VSS41';
NODE_NAME     J30 97
 '@T6G_MB_LIB.T6G(SCH_1):PAGE100_I161@PURE_QUANTA.SCONN288_DDR506112002KQ(CHIPS)':
 'VSS42': CDS_PINID='VSS42';
NODE_NAME     J30 99
 '@T6G_MB_LIB.T6G(SCH_1):PAGE100_I161@PURE_QUANTA.SCONN288_DDR506112002KQ(CHIPS)':
 'VSS43': CDS_PINID='VSS43';
NODE_NAME     J30 101
 '@T6G_MB_LIB.T6G(SCH_1):PAGE100_I161@PURE_QUANTA.SCONN288_DDR506112002KQ(CHIPS)':
 'VSS44': CDS_PINID='VSS44';
NODE_NAME     J30 103
 '@T6G_MB_LIB.T6G(SCH_1):PAGE100_I161@PURE_QUANTA.SCONN288_DDR506112002KQ(CHIPS)':
 'VSS45': CDS_PINID='VSS45';
NODE_NAME     J30 106
 '@T6G_MB_LIB.T6G(SCH_1):PAGE100_I161@PURE_QUANTA.SCONN288_DDR506112002KQ(CHIPS)':
 'VSS46': CDS_PINID='VSS46';
NODE_NAME     J30 108
 '@T6G_MB_LIB.T6G(SCH_1):PAGE100_I161@PURE_QUANTA.SCONN288_DDR506112002KQ(CHIPS)':
 'VSS47': CDS_PINID='VSS47';
NODE_NAME     J30 110
 '@T6G_MB_LIB.T6G(SCH_1):PAGE100_I161@PURE_QUANTA.SCONN288_DDR506112002KQ(CHIPS)':
 'VSS48': CDS_PINID='VSS48';
NODE_NAME     J30 112
 '@T6G_MB_LIB.T6G(SCH_1):PAGE100_I161@PURE_QUANTA.SCONN288_DDR506112002KQ(CHIPS)':
 'VSS49': CDS_PINID='VSS49';
NODE_NAME     J30 114
 '@T6G_MB_LIB.T6G(SCH_1):PAGE100_I161@PURE_QUANTA.SCONN288_DDR506112002KQ(CHIPS)':
 'VSS50': CDS_PINID='VSS50';
NODE_NAME     J30 117
 '@T6G_MB_LIB.T6G(SCH_1):PAGE100_I161@PURE_QUANTA.SCONN288_DDR506112002KQ(CHIPS)':
 'VSS51': CDS_PINID='VSS51';
NODE_NAME     J30 119
 '@T6G_MB_LIB.T6G(SCH_1):PAGE100_I161@PURE_QUANTA.SCONN288_DDR506112002KQ(CHIPS)':
 'VSS52': CDS_PINID='VSS52';
NODE_NAME     J30 121
 '@T6G_MB_LIB.T6G(SCH_1):PAGE100_I161@PURE_QUANTA.SCONN288_DDR506112002KQ(CHIPS)':
 'VSS53': CDS_PINID='VSS53';
NODE_NAME     J30 123
 '@T6G_MB_LIB.T6G(SCH_1):PAGE100_I161@PURE_QUANTA.SCONN288_DDR506112002KQ(CHIPS)':
 'VSS54': CDS_PINID='VSS54';
NODE_NAME     J30 125
 '@T6G_MB_LIB.T6G(SCH_1):PAGE100_I161@PURE_QUANTA.SCONN288_DDR506112002KQ(CHIPS)':
 'VSS55': CDS_PINID='VSS55';
NODE_NAME     J30 128
 '@T6G_MB_LIB.T6G(SCH_1):PAGE100_I161@PURE_QUANTA.SCONN288_DDR506112002KQ(CHIPS)':
 'VSS56': CDS_PINID='VSS56';
NODE_NAME     J30 130
 '@T6G_MB_LIB.T6G(SCH_1):PAGE100_I161@PURE_QUANTA.SCONN288_DDR506112002KQ(CHIPS)':
 'VSS57': CDS_PINID='VSS57';
NODE_NAME     J30 132
 '@T6G_MB_LIB.T6G(SCH_1):PAGE100_I161@PURE_QUANTA.SCONN288_DDR506112002KQ(CHIPS)':
 'VSS58': CDS_PINID='VSS58';
NODE_NAME     J30 134
 '@T6G_MB_LIB.T6G(SCH_1):PAGE100_I161@PURE_QUANTA.SCONN288_DDR506112002KQ(CHIPS)':
 'VSS59': CDS_PINID='VSS59';
NODE_NAME     J30 136
 '@T6G_MB_LIB.T6G(SCH_1):PAGE100_I161@PURE_QUANTA.SCONN288_DDR506112002KQ(CHIPS)':
 'VSS60': CDS_PINID='VSS60';
NODE_NAME     J30 139
 '@T6G_MB_LIB.T6G(SCH_1):PAGE100_I161@PURE_QUANTA.SCONN288_DDR506112002KQ(CHIPS)':
 'VSS61': CDS_PINID='VSS61';
NODE_NAME     J30 141
 '@T6G_MB_LIB.T6G(SCH_1):PAGE100_I161@PURE_QUANTA.SCONN288_DDR506112002KQ(CHIPS)':
 'VSS62': CDS_PINID='VSS62';
NODE_NAME     J30 143
 '@T6G_MB_LIB.T6G(SCH_1):PAGE100_I161@PURE_QUANTA.SCONN288_DDR506112002KQ(CHIPS)':
 'VSS63': CDS_PINID='VSS63';
NODE_NAME     J30 151
 '@T6G_MB_LIB.T6G(SCH_1):PAGE100_I161@PURE_QUANTA.SCONN288_DDR506112002KQ(CHIPS)':
 'VSS64': CDS_PINID='VSS64';
NODE_NAME     J30 153
 '@T6G_MB_LIB.T6G(SCH_1):PAGE100_I161@PURE_QUANTA.SCONN288_DDR506112002KQ(CHIPS)':
 'VSS65': CDS_PINID='VSS65';
NODE_NAME     J30 155
 '@T6G_MB_LIB.T6G(SCH_1):PAGE100_I161@PURE_QUANTA.SCONN288_DDR506112002KQ(CHIPS)':
 'VSS66': CDS_PINID='VSS66';
NODE_NAME     J30 158
 '@T6G_MB_LIB.T6G(SCH_1):PAGE100_I161@PURE_QUANTA.SCONN288_DDR506112002KQ(CHIPS)':
 'VSS67': CDS_PINID='VSS67';
NODE_NAME     J30 160
 '@T6G_MB_LIB.T6G(SCH_1):PAGE100_I161@PURE_QUANTA.SCONN288_DDR506112002KQ(CHIPS)':
 'VSS68': CDS_PINID='VSS68';
NODE_NAME     J30 162
 '@T6G_MB_LIB.T6G(SCH_1):PAGE100_I161@PURE_QUANTA.SCONN288_DDR506112002KQ(CHIPS)':
 'VSS69': CDS_PINID='VSS69';
NODE_NAME     J30 164
 '@T6G_MB_LIB.T6G(SCH_1):PAGE100_I161@PURE_QUANTA.SCONN288_DDR506112002KQ(CHIPS)':
 'VSS70': CDS_PINID='VSS70';
NODE_NAME     J30 166
 '@T6G_MB_LIB.T6G(SCH_1):PAGE100_I161@PURE_QUANTA.SCONN288_DDR506112002KQ(CHIPS)':
 'VSS71': CDS_PINID='VSS71';
NODE_NAME     J30 169
 '@T6G_MB_LIB.T6G(SCH_1):PAGE100_I161@PURE_QUANTA.SCONN288_DDR506112002KQ(CHIPS)':
 'VSS72': CDS_PINID='VSS72';
NODE_NAME     J30 171
 '@T6G_MB_LIB.T6G(SCH_1):PAGE100_I161@PURE_QUANTA.SCONN288_DDR506112002KQ(CHIPS)':
 'VSS73': CDS_PINID='VSS73';
NODE_NAME     J30 173
 '@T6G_MB_LIB.T6G(SCH_1):PAGE100_I161@PURE_QUANTA.SCONN288_DDR506112002KQ(CHIPS)':
 'VSS74': CDS_PINID='VSS74';
NODE_NAME     J30 175
 '@T6G_MB_LIB.T6G(SCH_1):PAGE100_I161@PURE_QUANTA.SCONN288_DDR506112002KQ(CHIPS)':
 'VSS75': CDS_PINID='VSS75';
NODE_NAME     J30 177
 '@T6G_MB_LIB.T6G(SCH_1):PAGE100_I161@PURE_QUANTA.SCONN288_DDR506112002KQ(CHIPS)':
 'VSS76': CDS_PINID='VSS76';
NODE_NAME     J30 180
 '@T6G_MB_LIB.T6G(SCH_1):PAGE100_I161@PURE_QUANTA.SCONN288_DDR506112002KQ(CHIPS)':
 'VSS77': CDS_PINID='VSS77';
NODE_NAME     J30 182
 '@T6G_MB_LIB.T6G(SCH_1):PAGE100_I161@PURE_QUANTA.SCONN288_DDR506112002KQ(CHIPS)':
 'VSS78': CDS_PINID='VSS78';
NODE_NAME     J30 184
 '@T6G_MB_LIB.T6G(SCH_1):PAGE100_I161@PURE_QUANTA.SCONN288_DDR506112002KQ(CHIPS)':
 'VSS79': CDS_PINID='VSS79';
NODE_NAME     J30 186
 '@T6G_MB_LIB.T6G(SCH_1):PAGE100_I161@PURE_QUANTA.SCONN288_DDR506112002KQ(CHIPS)':
 'VSS80': CDS_PINID='VSS80';
NODE_NAME     J30 188
 '@T6G_MB_LIB.T6G(SCH_1):PAGE100_I161@PURE_QUANTA.SCONN288_DDR506112002KQ(CHIPS)':
 'VSS81': CDS_PINID='VSS81';
NODE_NAME     J30 191
 '@T6G_MB_LIB.T6G(SCH_1):PAGE100_I161@PURE_QUANTA.SCONN288_DDR506112002KQ(CHIPS)':
 'VSS82': CDS_PINID='VSS82';
NODE_NAME     J30 193
 '@T6G_MB_LIB.T6G(SCH_1):PAGE100_I161@PURE_QUANTA.SCONN288_DDR506112002KQ(CHIPS)':
 'VSS83': CDS_PINID='VSS83';
NODE_NAME     J30 195
 '@T6G_MB_LIB.T6G(SCH_1):PAGE100_I161@PURE_QUANTA.SCONN288_DDR506112002KQ(CHIPS)':
 'VSS84': CDS_PINID='VSS84';
NODE_NAME     J30 197
 '@T6G_MB_LIB.T6G(SCH_1):PAGE100_I161@PURE_QUANTA.SCONN288_DDR506112002KQ(CHIPS)':
 'VSS85': CDS_PINID='VSS85';
NODE_NAME     J30 199
 '@T6G_MB_LIB.T6G(SCH_1):PAGE100_I161@PURE_QUANTA.SCONN288_DDR506112002KQ(CHIPS)':
 'VSS86': CDS_PINID='VSS86';
NODE_NAME     J30 202
 '@T6G_MB_LIB.T6G(SCH_1):PAGE100_I161@PURE_QUANTA.SCONN288_DDR506112002KQ(CHIPS)':
 'VSS87': CDS_PINID='VSS87';
NODE_NAME     J30 204
 '@T6G_MB_LIB.T6G(SCH_1):PAGE100_I161@PURE_QUANTA.SCONN288_DDR506112002KQ(CHIPS)':
 'VSS88': CDS_PINID='VSS88';
NODE_NAME     J30 206
 '@T6G_MB_LIB.T6G(SCH_1):PAGE100_I161@PURE_QUANTA.SCONN288_DDR506112002KQ(CHIPS)':
 'VSS89': CDS_PINID='VSS89';
NODE_NAME     J30 208
 '@T6G_MB_LIB.T6G(SCH_1):PAGE100_I161@PURE_QUANTA.SCONN288_DDR506112002KQ(CHIPS)':
 'VSS90': CDS_PINID='VSS90';
NODE_NAME     J30 210
 '@T6G_MB_LIB.T6G(SCH_1):PAGE100_I161@PURE_QUANTA.SCONN288_DDR506112002KQ(CHIPS)':
 'VSS91': CDS_PINID='VSS91';
NODE_NAME     J30 212
 '@T6G_MB_LIB.T6G(SCH_1):PAGE100_I161@PURE_QUANTA.SCONN288_DDR506112002KQ(CHIPS)':
 'VSS92': CDS_PINID='VSS92';
NODE_NAME     J30 214
 '@T6G_MB_LIB.T6G(SCH_1):PAGE100_I161@PURE_QUANTA.SCONN288_DDR506112002KQ(CHIPS)':
 'VSS93': CDS_PINID='VSS93';
NODE_NAME     J30 216
 '@T6G_MB_LIB.T6G(SCH_1):PAGE100_I161@PURE_QUANTA.SCONN288_DDR506112002KQ(CHIPS)':
 'VSS94': CDS_PINID='VSS94';
NODE_NAME     J30 219
 '@T6G_MB_LIB.T6G(SCH_1):PAGE100_I161@PURE_QUANTA.SCONN288_DDR506112002KQ(CHIPS)':
 'VSS95': CDS_PINID='VSS95';
NODE_NAME     J30 222
 '@T6G_MB_LIB.T6G(SCH_1):PAGE100_I161@PURE_QUANTA.SCONN288_DDR506112002KQ(CHIPS)':
 'VSS96': CDS_PINID='VSS96';
NODE_NAME     J30 224
 '@T6G_MB_LIB.T6G(SCH_1):PAGE100_I161@PURE_QUANTA.SCONN288_DDR506112002KQ(CHIPS)':
 'VSS97': CDS_PINID='VSS97';
NODE_NAME     J30 226
 '@T6G_MB_LIB.T6G(SCH_1):PAGE100_I161@PURE_QUANTA.SCONN288_DDR506112002KQ(CHIPS)':
 'VSS98': CDS_PINID='VSS98';
NODE_NAME     J30 228
 '@T6G_MB_LIB.T6G(SCH_1):PAGE100_I161@PURE_QUANTA.SCONN288_DDR506112002KQ(CHIPS)':
 'VSS99': CDS_PINID='VSS99';
NODE_NAME     J30 230
 '@T6G_MB_LIB.T6G(SCH_1):PAGE100_I161@PURE_QUANTA.SCONN288_DDR506112002KQ(CHIPS)':
 'VSS100': CDS_PINID='VSS100';
NODE_NAME     J30 233
 '@T6G_MB_LIB.T6G(SCH_1):PAGE100_I161@PURE_QUANTA.SCONN288_DDR506112002KQ(CHIPS)':
 'VSS101': CDS_PINID='VSS101';
NODE_NAME     J30 235
 '@T6G_MB_LIB.T6G(SCH_1):PAGE100_I161@PURE_QUANTA.SCONN288_DDR506112002KQ(CHIPS)':
 'VSS102': CDS_PINID='VSS102';
NODE_NAME     J30 237
 '@T6G_MB_LIB.T6G(SCH_1):PAGE100_I161@PURE_QUANTA.SCONN288_DDR506112002KQ(CHIPS)':
 'VSS103': CDS_PINID='VSS103';
NODE_NAME     J30 240
 '@T6G_MB_LIB.T6G(SCH_1):PAGE100_I161@PURE_QUANTA.SCONN288_DDR506112002KQ(CHIPS)':
 'VSS104': CDS_PINID='VSS104';
NODE_NAME     J30 242
 '@T6G_MB_LIB.T6G(SCH_1):PAGE100_I161@PURE_QUANTA.SCONN288_DDR506112002KQ(CHIPS)':
 'VSS105': CDS_PINID='VSS105';
NODE_NAME     J30 244
 '@T6G_MB_LIB.T6G(SCH_1):PAGE100_I161@PURE_QUANTA.SCONN288_DDR506112002KQ(CHIPS)':
 'VSS106': CDS_PINID='VSS106';
NODE_NAME     J30 246
 '@T6G_MB_LIB.T6G(SCH_1):PAGE100_I161@PURE_QUANTA.SCONN288_DDR506112002KQ(CHIPS)':
 'VSS107': CDS_PINID='VSS107';
NODE_NAME     J30 248
 '@T6G_MB_LIB.T6G(SCH_1):PAGE100_I161@PURE_QUANTA.SCONN288_DDR506112002KQ(CHIPS)':
 'VSS108': CDS_PINID='VSS108';
NODE_NAME     J30 251
 '@T6G_MB_LIB.T6G(SCH_1):PAGE100_I161@PURE_QUANTA.SCONN288_DDR506112002KQ(CHIPS)':
 'VSS109': CDS_PINID='VSS109';
NODE_NAME     J30 253
 '@T6G_MB_LIB.T6G(SCH_1):PAGE100_I161@PURE_QUANTA.SCONN288_DDR506112002KQ(CHIPS)':
 'VSS110': CDS_PINID='VSS110';
NODE_NAME     J30 255
 '@T6G_MB_LIB.T6G(SCH_1):PAGE100_I161@PURE_QUANTA.SCONN288_DDR506112002KQ(CHIPS)':
 'VSS111': CDS_PINID='VSS111';
NODE_NAME     J30 257
 '@T6G_MB_LIB.T6G(SCH_1):PAGE100_I161@PURE_QUANTA.SCONN288_DDR506112002KQ(CHIPS)':
 'VSS112': CDS_PINID='VSS112';
NODE_NAME     J30 259
 '@T6G_MB_LIB.T6G(SCH_1):PAGE100_I161@PURE_QUANTA.SCONN288_DDR506112002KQ(CHIPS)':
 'VSS113': CDS_PINID='VSS113';
NODE_NAME     J30 262
 '@T6G_MB_LIB.T6G(SCH_1):PAGE100_I161@PURE_QUANTA.SCONN288_DDR506112002KQ(CHIPS)':
 'VSS114': CDS_PINID='VSS114';
NODE_NAME     J30 264
 '@T6G_MB_LIB.T6G(SCH_1):PAGE100_I161@PURE_QUANTA.SCONN288_DDR506112002KQ(CHIPS)':
 'VSS115': CDS_PINID='VSS115';
NODE_NAME     J30 266
 '@T6G_MB_LIB.T6G(SCH_1):PAGE100_I161@PURE_QUANTA.SCONN288_DDR506112002KQ(CHIPS)':
 'VSS116': CDS_PINID='VSS116';
NODE_NAME     J30 268
 '@T6G_MB_LIB.T6G(SCH_1):PAGE100_I161@PURE_QUANTA.SCONN288_DDR506112002KQ(CHIPS)':
 'VSS117': CDS_PINID='VSS117';
NODE_NAME     J30 270
 '@T6G_MB_LIB.T6G(SCH_1):PAGE100_I161@PURE_QUANTA.SCONN288_DDR506112002KQ(CHIPS)':
 'VSS118': CDS_PINID='VSS118';
NODE_NAME     J30 273
 '@T6G_MB_LIB.T6G(SCH_1):PAGE100_I161@PURE_QUANTA.SCONN288_DDR506112002KQ(CHIPS)':
 'VSS119': CDS_PINID='VSS119';
NODE_NAME     J30 275
 '@T6G_MB_LIB.T6G(SCH_1):PAGE100_I161@PURE_QUANTA.SCONN288_DDR506112002KQ(CHIPS)':
 'VSS120': CDS_PINID='VSS120';
NODE_NAME     J30 277
 '@T6G_MB_LIB.T6G(SCH_1):PAGE100_I161@PURE_QUANTA.SCONN288_DDR506112002KQ(CHIPS)':
 'VSS121': CDS_PINID='VSS121';
NODE_NAME     J30 279
 '@T6G_MB_LIB.T6G(SCH_1):PAGE100_I161@PURE_QUANTA.SCONN288_DDR506112002KQ(CHIPS)':
 'VSS122': CDS_PINID='VSS122';
NODE_NAME     J30 281
 '@T6G_MB_LIB.T6G(SCH_1):PAGE100_I161@PURE_QUANTA.SCONN288_DDR506112002KQ(CHIPS)':
 'VSS123': CDS_PINID='VSS123';
NODE_NAME     J30 284
 '@T6G_MB_LIB.T6G(SCH_1):PAGE100_I161@PURE_QUANTA.SCONN288_DDR506112002KQ(CHIPS)':
 'VSS124': CDS_PINID='VSS124';
NODE_NAME     J30 286
 '@T6G_MB_LIB.T6G(SCH_1):PAGE100_I161@PURE_QUANTA.SCONN288_DDR506112002KQ(CHIPS)':
 'VSS125': CDS_PINID='VSS125';
NODE_NAME     J30 288
 '@T6G_MB_LIB.T6G(SCH_1):PAGE100_I161@PURE_QUANTA.SCONN288_DDR506112002KQ(CHIPS)':
 'VSS126': CDS_PINID='VSS126';
NODE_NAME     C148 2
 '@T6G_MB_LIB.T6G(SCH_1):PAGE100_I185@PURE_QUANTA.Q_CAP(CHIPS)':
 'B': CDS_PINID='B';
NODE_NAME     C181 2
 '@T6G_MB_LIB.T6G(SCH_1):PAGE100_I238@PURE_QUANTA.Q_CAP(CHIPS)':
 'B': CDS_PINID='B';
NODE_NAME     C182 2
 '@T6G_MB_LIB.T6G(SCH_1):PAGE100_I239@PURE_QUANTA.Q_CAP(CHIPS)':
 'B': CDS_PINID='B';
NODE_NAME     R6 2
 '@T6G_MB_LIB.T6G(SCH_1):PAGE101_I127@PURE_QUANTA.Q_RES(CHIPS)':
 'B':XNET_PINS='2',
 CDS_PINID='B';
NODE_NAME     J32 G1
 '@T6G_MB_LIB.T6G(SCH_1):PAGE101_I175@PURE_QUANTA.SCONN288_DDR506112002KQ(CHIPS)':
 'G1': CDS_PINID='G1';
NODE_NAME     J32 G2
 '@T6G_MB_LIB.T6G(SCH_1):PAGE101_I175@PURE_QUANTA.SCONN288_DDR506112002KQ(CHIPS)':
 'G2': CDS_PINID='G2';
NODE_NAME     J32 G3
 '@T6G_MB_LIB.T6G(SCH_1):PAGE101_I175@PURE_QUANTA.SCONN288_DDR506112002KQ(CHIPS)':
 'G3': CDS_PINID='G3';
NODE_NAME     J32 6
 '@T6G_MB_LIB.T6G(SCH_1):PAGE101_I175@PURE_QUANTA.SCONN288_DDR506112002KQ(CHIPS)':
 'VSS0': CDS_PINID='VSS0';
NODE_NAME     J32 8
 '@T6G_MB_LIB.T6G(SCH_1):PAGE101_I175@PURE_QUANTA.SCONN288_DDR506112002KQ(CHIPS)':
 'VSS1': CDS_PINID='VSS1';
NODE_NAME     J32 10
 '@T6G_MB_LIB.T6G(SCH_1):PAGE101_I175@PURE_QUANTA.SCONN288_DDR506112002KQ(CHIPS)':
 'VSS2': CDS_PINID='VSS2';
NODE_NAME     J32 13
 '@T6G_MB_LIB.T6G(SCH_1):PAGE101_I175@PURE_QUANTA.SCONN288_DDR506112002KQ(CHIPS)':
 'VSS3': CDS_PINID='VSS3';
NODE_NAME     J32 15
 '@T6G_MB_LIB.T6G(SCH_1):PAGE101_I175@PURE_QUANTA.SCONN288_DDR506112002KQ(CHIPS)':
 'VSS4': CDS_PINID='VSS4';
NODE_NAME     J32 17
 '@T6G_MB_LIB.T6G(SCH_1):PAGE101_I175@PURE_QUANTA.SCONN288_DDR506112002KQ(CHIPS)':
 'VSS5': CDS_PINID='VSS5';
NODE_NAME     J32 19
 '@T6G_MB_LIB.T6G(SCH_1):PAGE101_I175@PURE_QUANTA.SCONN288_DDR506112002KQ(CHIPS)':
 'VSS6': CDS_PINID='VSS6';
NODE_NAME     J32 21
 '@T6G_MB_LIB.T6G(SCH_1):PAGE101_I175@PURE_QUANTA.SCONN288_DDR506112002KQ(CHIPS)':
 'VSS7': CDS_PINID='VSS7';
NODE_NAME     J32 24
 '@T6G_MB_LIB.T6G(SCH_1):PAGE101_I175@PURE_QUANTA.SCONN288_DDR506112002KQ(CHIPS)':
 'VSS8': CDS_PINID='VSS8';
NODE_NAME     J32 26
 '@T6G_MB_LIB.T6G(SCH_1):PAGE101_I175@PURE_QUANTA.SCONN288_DDR506112002KQ(CHIPS)':
 'VSS9': CDS_PINID='VSS9';
NODE_NAME     J32 28
 '@T6G_MB_LIB.T6G(SCH_1):PAGE101_I175@PURE_QUANTA.SCONN288_DDR506112002KQ(CHIPS)':
 'VSS10': CDS_PINID='VSS10';
NODE_NAME     J32 30
 '@T6G_MB_LIB.T6G(SCH_1):PAGE101_I175@PURE_QUANTA.SCONN288_DDR506112002KQ(CHIPS)':
 'VSS11': CDS_PINID='VSS11';
NODE_NAME     J32 32
 '@T6G_MB_LIB.T6G(SCH_1):PAGE101_I175@PURE_QUANTA.SCONN288_DDR506112002KQ(CHIPS)':
 'VSS12': CDS_PINID='VSS12';
NODE_NAME     J32 35
 '@T6G_MB_LIB.T6G(SCH_1):PAGE101_I175@PURE_QUANTA.SCONN288_DDR506112002KQ(CHIPS)':
 'VSS13': CDS_PINID='VSS13';
NODE_NAME     J32 37
 '@T6G_MB_LIB.T6G(SCH_1):PAGE101_I175@PURE_QUANTA.SCONN288_DDR506112002KQ(CHIPS)':
 'VSS14': CDS_PINID='VSS14';
NODE_NAME     J32 39
 '@T6G_MB_LIB.T6G(SCH_1):PAGE101_I175@PURE_QUANTA.SCONN288_DDR506112002KQ(CHIPS)':
 'VSS15': CDS_PINID='VSS15';
NODE_NAME     J32 41
 '@T6G_MB_LIB.T6G(SCH_1):PAGE101_I175@PURE_QUANTA.SCONN288_DDR506112002KQ(CHIPS)':
 'VSS16': CDS_PINID='VSS16';
NODE_NAME     J32 43
 '@T6G_MB_LIB.T6G(SCH_1):PAGE101_I175@PURE_QUANTA.SCONN288_DDR506112002KQ(CHIPS)':
 'VSS17': CDS_PINID='VSS17';
NODE_NAME     J32 46
 '@T6G_MB_LIB.T6G(SCH_1):PAGE101_I175@PURE_QUANTA.SCONN288_DDR506112002KQ(CHIPS)':
 'VSS18': CDS_PINID='VSS18';
NODE_NAME     J32 48
 '@T6G_MB_LIB.T6G(SCH_1):PAGE101_I175@PURE_QUANTA.SCONN288_DDR506112002KQ(CHIPS)':
 'VSS19': CDS_PINID='VSS19';
NODE_NAME     J32 50
 '@T6G_MB_LIB.T6G(SCH_1):PAGE101_I175@PURE_QUANTA.SCONN288_DDR506112002KQ(CHIPS)':
 'VSS20': CDS_PINID='VSS20';
NODE_NAME     J32 52
 '@T6G_MB_LIB.T6G(SCH_1):PAGE101_I175@PURE_QUANTA.SCONN288_DDR506112002KQ(CHIPS)':
 'VSS21': CDS_PINID='VSS21';
NODE_NAME     J32 54
 '@T6G_MB_LIB.T6G(SCH_1):PAGE101_I175@PURE_QUANTA.SCONN288_DDR506112002KQ(CHIPS)':
 'VSS22': CDS_PINID='VSS22';
NODE_NAME     J32 57
 '@T6G_MB_LIB.T6G(SCH_1):PAGE101_I175@PURE_QUANTA.SCONN288_DDR506112002KQ(CHIPS)':
 'VSS23': CDS_PINID='VSS23';
NODE_NAME     J32 59
 '@T6G_MB_LIB.T6G(SCH_1):PAGE101_I175@PURE_QUANTA.SCONN288_DDR506112002KQ(CHIPS)':
 'VSS24': CDS_PINID='VSS24';
NODE_NAME     J32 61
 '@T6G_MB_LIB.T6G(SCH_1):PAGE101_I175@PURE_QUANTA.SCONN288_DDR506112002KQ(CHIPS)':
 'VSS25': CDS_PINID='VSS25';
NODE_NAME     J32 63
 '@T6G_MB_LIB.T6G(SCH_1):PAGE101_I175@PURE_QUANTA.SCONN288_DDR506112002KQ(CHIPS)':
 'VSS26': CDS_PINID='VSS26';
NODE_NAME     J32 65
 '@T6G_MB_LIB.T6G(SCH_1):PAGE101_I175@PURE_QUANTA.SCONN288_DDR506112002KQ(CHIPS)':
 'VSS27': CDS_PINID='VSS27';
NODE_NAME     J32 67
 '@T6G_MB_LIB.T6G(SCH_1):PAGE101_I175@PURE_QUANTA.SCONN288_DDR506112002KQ(CHIPS)':
 'VSS28': CDS_PINID='VSS28';
NODE_NAME     J32 69
 '@T6G_MB_LIB.T6G(SCH_1):PAGE101_I175@PURE_QUANTA.SCONN288_DDR506112002KQ(CHIPS)':
 'VSS29': CDS_PINID='VSS29';
NODE_NAME     J32 71
 '@T6G_MB_LIB.T6G(SCH_1):PAGE101_I175@PURE_QUANTA.SCONN288_DDR506112002KQ(CHIPS)':
 'VSS30': CDS_PINID='VSS30';
NODE_NAME     J32 73
 '@T6G_MB_LIB.T6G(SCH_1):PAGE101_I175@PURE_QUANTA.SCONN288_DDR506112002KQ(CHIPS)':
 'VSS31': CDS_PINID='VSS31';
NODE_NAME     J32 75
 '@T6G_MB_LIB.T6G(SCH_1):PAGE101_I175@PURE_QUANTA.SCONN288_DDR506112002KQ(CHIPS)':
 'VSS32': CDS_PINID='VSS32';
NODE_NAME     J32 77
 '@T6G_MB_LIB.T6G(SCH_1):PAGE101_I175@PURE_QUANTA.SCONN288_DDR506112002KQ(CHIPS)':
 'VSS33': CDS_PINID='VSS33';
NODE_NAME     J32 79
 '@T6G_MB_LIB.T6G(SCH_1):PAGE101_I175@PURE_QUANTA.SCONN288_DDR506112002KQ(CHIPS)':
 'VSS34': CDS_PINID='VSS34';
NODE_NAME     J32 81
 '@T6G_MB_LIB.T6G(SCH_1):PAGE101_I175@PURE_QUANTA.SCONN288_DDR506112002KQ(CHIPS)':
 'VSS35': CDS_PINID='VSS35';
NODE_NAME     J32 83
 '@T6G_MB_LIB.T6G(SCH_1):PAGE101_I175@PURE_QUANTA.SCONN288_DDR506112002KQ(CHIPS)':
 'VSS36': CDS_PINID='VSS36';
NODE_NAME     J32 85
 '@T6G_MB_LIB.T6G(SCH_1):PAGE101_I175@PURE_QUANTA.SCONN288_DDR506112002KQ(CHIPS)':
 'VSS37': CDS_PINID='VSS37';
NODE_NAME     J32 88
 '@T6G_MB_LIB.T6G(SCH_1):PAGE101_I175@PURE_QUANTA.SCONN288_DDR506112002KQ(CHIPS)':
 'VSS38': CDS_PINID='VSS38';
NODE_NAME     J32 90
 '@T6G_MB_LIB.T6G(SCH_1):PAGE101_I175@PURE_QUANTA.SCONN288_DDR506112002KQ(CHIPS)':
 'VSS39': CDS_PINID='VSS39';
NODE_NAME     J32 92
 '@T6G_MB_LIB.T6G(SCH_1):PAGE101_I175@PURE_QUANTA.SCONN288_DDR506112002KQ(CHIPS)':
 'VSS40': CDS_PINID='VSS40';
NODE_NAME     J32 95
 '@T6G_MB_LIB.T6G(SCH_1):PAGE101_I175@PURE_QUANTA.SCONN288_DDR506112002KQ(CHIPS)':
 'VSS41': CDS_PINID='VSS41';
NODE_NAME     J32 97
 '@T6G_MB_LIB.T6G(SCH_1):PAGE101_I175@PURE_QUANTA.SCONN288_DDR506112002KQ(CHIPS)':
 'VSS42': CDS_PINID='VSS42';
NODE_NAME     J32 99
 '@T6G_MB_LIB.T6G(SCH_1):PAGE101_I175@PURE_QUANTA.SCONN288_DDR506112002KQ(CHIPS)':
 'VSS43': CDS_PINID='VSS43';
NODE_NAME     J32 101
 '@T6G_MB_LIB.T6G(SCH_1):PAGE101_I175@PURE_QUANTA.SCONN288_DDR506112002KQ(CHIPS)':
 'VSS44': CDS_PINID='VSS44';
NODE_NAME     J32 103
 '@T6G_MB_LIB.T6G(SCH_1):PAGE101_I175@PURE_QUANTA.SCONN288_DDR506112002KQ(CHIPS)':
 'VSS45': CDS_PINID='VSS45';
NODE_NAME     J32 106
 '@T6G_MB_LIB.T6G(SCH_1):PAGE101_I175@PURE_QUANTA.SCONN288_DDR506112002KQ(CHIPS)':
 'VSS46': CDS_PINID='VSS46';
NODE_NAME     J32 108
 '@T6G_MB_LIB.T6G(SCH_1):PAGE101_I175@PURE_QUANTA.SCONN288_DDR506112002KQ(CHIPS)':
 'VSS47': CDS_PINID='VSS47';
NODE_NAME     J32 110
 '@T6G_MB_LIB.T6G(SCH_1):PAGE101_I175@PURE_QUANTA.SCONN288_DDR506112002KQ(CHIPS)':
 'VSS48': CDS_PINID='VSS48';
NODE_NAME     J32 112
 '@T6G_MB_LIB.T6G(SCH_1):PAGE101_I175@PURE_QUANTA.SCONN288_DDR506112002KQ(CHIPS)':
 'VSS49': CDS_PINID='VSS49';
NODE_NAME     J32 114
 '@T6G_MB_LIB.T6G(SCH_1):PAGE101_I175@PURE_QUANTA.SCONN288_DDR506112002KQ(CHIPS)':
 'VSS50': CDS_PINID='VSS50';
NODE_NAME     J32 117
 '@T6G_MB_LIB.T6G(SCH_1):PAGE101_I175@PURE_QUANTA.SCONN288_DDR506112002KQ(CHIPS)':
 'VSS51': CDS_PINID='VSS51';
NODE_NAME     J32 119
 '@T6G_MB_LIB.T6G(SCH_1):PAGE101_I175@PURE_QUANTA.SCONN288_DDR506112002KQ(CHIPS)':
 'VSS52': CDS_PINID='VSS52';
NODE_NAME     J32 121
 '@T6G_MB_LIB.T6G(SCH_1):PAGE101_I175@PURE_QUANTA.SCONN288_DDR506112002KQ(CHIPS)':
 'VSS53': CDS_PINID='VSS53';
NODE_NAME     J32 123
 '@T6G_MB_LIB.T6G(SCH_1):PAGE101_I175@PURE_QUANTA.SCONN288_DDR506112002KQ(CHIPS)':
 'VSS54': CDS_PINID='VSS54';
NODE_NAME     J32 125
 '@T6G_MB_LIB.T6G(SCH_1):PAGE101_I175@PURE_QUANTA.SCONN288_DDR506112002KQ(CHIPS)':
 'VSS55': CDS_PINID='VSS55';
NODE_NAME     J32 128
 '@T6G_MB_LIB.T6G(SCH_1):PAGE101_I175@PURE_QUANTA.SCONN288_DDR506112002KQ(CHIPS)':
 'VSS56': CDS_PINID='VSS56';
NODE_NAME     J32 130
 '@T6G_MB_LIB.T6G(SCH_1):PAGE101_I175@PURE_QUANTA.SCONN288_DDR506112002KQ(CHIPS)':
 'VSS57': CDS_PINID='VSS57';
NODE_NAME     J32 132
 '@T6G_MB_LIB.T6G(SCH_1):PAGE101_I175@PURE_QUANTA.SCONN288_DDR506112002KQ(CHIPS)':
 'VSS58': CDS_PINID='VSS58';
NODE_NAME     J32 134
 '@T6G_MB_LIB.T6G(SCH_1):PAGE101_I175@PURE_QUANTA.SCONN288_DDR506112002KQ(CHIPS)':
 'VSS59': CDS_PINID='VSS59';
NODE_NAME     J32 136
 '@T6G_MB_LIB.T6G(SCH_1):PAGE101_I175@PURE_QUANTA.SCONN288_DDR506112002KQ(CHIPS)':
 'VSS60': CDS_PINID='VSS60';
NODE_NAME     J32 139
 '@T6G_MB_LIB.T6G(SCH_1):PAGE101_I175@PURE_QUANTA.SCONN288_DDR506112002KQ(CHIPS)':
 'VSS61': CDS_PINID='VSS61';
NODE_NAME     J32 141
 '@T6G_MB_LIB.T6G(SCH_1):PAGE101_I175@PURE_QUANTA.SCONN288_DDR506112002KQ(CHIPS)':
 'VSS62': CDS_PINID='VSS62';
NODE_NAME     J32 143
 '@T6G_MB_LIB.T6G(SCH_1):PAGE101_I175@PURE_QUANTA.SCONN288_DDR506112002KQ(CHIPS)':
 'VSS63': CDS_PINID='VSS63';
NODE_NAME     J32 151
 '@T6G_MB_LIB.T6G(SCH_1):PAGE101_I175@PURE_QUANTA.SCONN288_DDR506112002KQ(CHIPS)':
 'VSS64': CDS_PINID='VSS64';
NODE_NAME     J32 153
 '@T6G_MB_LIB.T6G(SCH_1):PAGE101_I175@PURE_QUANTA.SCONN288_DDR506112002KQ(CHIPS)':
 'VSS65': CDS_PINID='VSS65';
NODE_NAME     J32 155
 '@T6G_MB_LIB.T6G(SCH_1):PAGE101_I175@PURE_QUANTA.SCONN288_DDR506112002KQ(CHIPS)':
 'VSS66': CDS_PINID='VSS66';
NODE_NAME     J32 158
 '@T6G_MB_LIB.T6G(SCH_1):PAGE101_I175@PURE_QUANTA.SCONN288_DDR506112002KQ(CHIPS)':
 'VSS67': CDS_PINID='VSS67';
NODE_NAME     J32 160
 '@T6G_MB_LIB.T6G(SCH_1):PAGE101_I175@PURE_QUANTA.SCONN288_DDR506112002KQ(CHIPS)':
 'VSS68': CDS_PINID='VSS68';
NODE_NAME     J32 162
 '@T6G_MB_LIB.T6G(SCH_1):PAGE101_I175@PURE_QUANTA.SCONN288_DDR506112002KQ(CHIPS)':
 'VSS69': CDS_PINID='VSS69';
NODE_NAME     J32 164
 '@T6G_MB_LIB.T6G(SCH_1):PAGE101_I175@PURE_QUANTA.SCONN288_DDR506112002KQ(CHIPS)':
 'VSS70': CDS_PINID='VSS70';
NODE_NAME     J32 166
 '@T6G_MB_LIB.T6G(SCH_1):PAGE101_I175@PURE_QUANTA.SCONN288_DDR506112002KQ(CHIPS)':
 'VSS71': CDS_PINID='VSS71';
NODE_NAME     J32 169
 '@T6G_MB_LIB.T6G(SCH_1):PAGE101_I175@PURE_QUANTA.SCONN288_DDR506112002KQ(CHIPS)':
 'VSS72': CDS_PINID='VSS72';
NODE_NAME     J32 171
 '@T6G_MB_LIB.T6G(SCH_1):PAGE101_I175@PURE_QUANTA.SCONN288_DDR506112002KQ(CHIPS)':
 'VSS73': CDS_PINID='VSS73';
NODE_NAME     J32 173
 '@T6G_MB_LIB.T6G(SCH_1):PAGE101_I175@PURE_QUANTA.SCONN288_DDR506112002KQ(CHIPS)':
 'VSS74': CDS_PINID='VSS74';
NODE_NAME     J32 175
 '@T6G_MB_LIB.T6G(SCH_1):PAGE101_I175@PURE_QUANTA.SCONN288_DDR506112002KQ(CHIPS)':
 'VSS75': CDS_PINID='VSS75';
NODE_NAME     J32 177
 '@T6G_MB_LIB.T6G(SCH_1):PAGE101_I175@PURE_QUANTA.SCONN288_DDR506112002KQ(CHIPS)':
 'VSS76': CDS_PINID='VSS76';
NODE_NAME     J32 180
 '@T6G_MB_LIB.T6G(SCH_1):PAGE101_I175@PURE_QUANTA.SCONN288_DDR506112002KQ(CHIPS)':
 'VSS77': CDS_PINID='VSS77';
NODE_NAME     J32 182
 '@T6G_MB_LIB.T6G(SCH_1):PAGE101_I175@PURE_QUANTA.SCONN288_DDR506112002KQ(CHIPS)':
 'VSS78': CDS_PINID='VSS78';
NODE_NAME     J32 184
 '@T6G_MB_LIB.T6G(SCH_1):PAGE101_I175@PURE_QUANTA.SCONN288_DDR506112002KQ(CHIPS)':
 'VSS79': CDS_PINID='VSS79';
NODE_NAME     J32 186
 '@T6G_MB_LIB.T6G(SCH_1):PAGE101_I175@PURE_QUANTA.SCONN288_DDR506112002KQ(CHIPS)':
 'VSS80': CDS_PINID='VSS80';
NODE_NAME     J32 188
 '@T6G_MB_LIB.T6G(SCH_1):PAGE101_I175@PURE_QUANTA.SCONN288_DDR506112002KQ(CHIPS)':
 'VSS81': CDS_PINID='VSS81';
NODE_NAME     J32 191
 '@T6G_MB_LIB.T6G(SCH_1):PAGE101_I175@PURE_QUANTA.SCONN288_DDR506112002KQ(CHIPS)':
 'VSS82': CDS_PINID='VSS82';
NODE_NAME     J32 193
 '@T6G_MB_LIB.T6G(SCH_1):PAGE101_I175@PURE_QUANTA.SCONN288_DDR506112002KQ(CHIPS)':
 'VSS83': CDS_PINID='VSS83';
NODE_NAME     J32 195
 '@T6G_MB_LIB.T6G(SCH_1):PAGE101_I175@PURE_QUANTA.SCONN288_DDR506112002KQ(CHIPS)':
 'VSS84': CDS_PINID='VSS84';
NODE_NAME     J32 197
 '@T6G_MB_LIB.T6G(SCH_1):PAGE101_I175@PURE_QUANTA.SCONN288_DDR506112002KQ(CHIPS)':
 'VSS85': CDS_PINID='VSS85';
NODE_NAME     J32 199
 '@T6G_MB_LIB.T6G(SCH_1):PAGE101_I175@PURE_QUANTA.SCONN288_DDR506112002KQ(CHIPS)':
 'VSS86': CDS_PINID='VSS86';
NODE_NAME     J32 202
 '@T6G_MB_LIB.T6G(SCH_1):PAGE101_I175@PURE_QUANTA.SCONN288_DDR506112002KQ(CHIPS)':
 'VSS87': CDS_PINID='VSS87';
NODE_NAME     J32 204
 '@T6G_MB_LIB.T6G(SCH_1):PAGE101_I175@PURE_QUANTA.SCONN288_DDR506112002KQ(CHIPS)':
 'VSS88': CDS_PINID='VSS88';
NODE_NAME     J32 206
 '@T6G_MB_LIB.T6G(SCH_1):PAGE101_I175@PURE_QUANTA.SCONN288_DDR506112002KQ(CHIPS)':
 'VSS89': CDS_PINID='VSS89';
NODE_NAME     J32 208
 '@T6G_MB_LIB.T6G(SCH_1):PAGE101_I175@PURE_QUANTA.SCONN288_DDR506112002KQ(CHIPS)':
 'VSS90': CDS_PINID='VSS90';
NODE_NAME     J32 210
 '@T6G_MB_LIB.T6G(SCH_1):PAGE101_I175@PURE_QUANTA.SCONN288_DDR506112002KQ(CHIPS)':
 'VSS91': CDS_PINID='VSS91';
NODE_NAME     J32 212
 '@T6G_MB_LIB.T6G(SCH_1):PAGE101_I175@PURE_QUANTA.SCONN288_DDR506112002KQ(CHIPS)':
 'VSS92': CDS_PINID='VSS92';
NODE_NAME     J32 214
 '@T6G_MB_LIB.T6G(SCH_1):PAGE101_I175@PURE_QUANTA.SCONN288_DDR506112002KQ(CHIPS)':
 'VSS93': CDS_PINID='VSS93';
NODE_NAME     J32 216
 '@T6G_MB_LIB.T6G(SCH_1):PAGE101_I175@PURE_QUANTA.SCONN288_DDR506112002KQ(CHIPS)':
 'VSS94': CDS_PINID='VSS94';
NODE_NAME     J32 219
 '@T6G_MB_LIB.T6G(SCH_1):PAGE101_I175@PURE_QUANTA.SCONN288_DDR506112002KQ(CHIPS)':
 'VSS95': CDS_PINID='VSS95';
NODE_NAME     J32 222
 '@T6G_MB_LIB.T6G(SCH_1):PAGE101_I175@PURE_QUANTA.SCONN288_DDR506112002KQ(CHIPS)':
 'VSS96': CDS_PINID='VSS96';
NODE_NAME     J32 224
 '@T6G_MB_LIB.T6G(SCH_1):PAGE101_I175@PURE_QUANTA.SCONN288_DDR506112002KQ(CHIPS)':
 'VSS97': CDS_PINID='VSS97';
NODE_NAME     J32 226
 '@T6G_MB_LIB.T6G(SCH_1):PAGE101_I175@PURE_QUANTA.SCONN288_DDR506112002KQ(CHIPS)':
 'VSS98': CDS_PINID='VSS98';
NODE_NAME     J32 228
 '@T6G_MB_LIB.T6G(SCH_1):PAGE101_I175@PURE_QUANTA.SCONN288_DDR506112002KQ(CHIPS)':
 'VSS99': CDS_PINID='VSS99';
NODE_NAME     J32 230
 '@T6G_MB_LIB.T6G(SCH_1):PAGE101_I175@PURE_QUANTA.SCONN288_DDR506112002KQ(CHIPS)':
 'VSS100': CDS_PINID='VSS100';
NODE_NAME     J32 233
 '@T6G_MB_LIB.T6G(SCH_1):PAGE101_I175@PURE_QUANTA.SCONN288_DDR506112002KQ(CHIPS)':
 'VSS101': CDS_PINID='VSS101';
NODE_NAME     J32 235
 '@T6G_MB_LIB.T6G(SCH_1):PAGE101_I175@PURE_QUANTA.SCONN288_DDR506112002KQ(CHIPS)':
 'VSS102': CDS_PINID='VSS102';
NODE_NAME     J32 237
 '@T6G_MB_LIB.T6G(SCH_1):PAGE101_I175@PURE_QUANTA.SCONN288_DDR506112002KQ(CHIPS)':
 'VSS103': CDS_PINID='VSS103';
NODE_NAME     J32 240
 '@T6G_MB_LIB.T6G(SCH_1):PAGE101_I175@PURE_QUANTA.SCONN288_DDR506112002KQ(CHIPS)':
 'VSS104': CDS_PINID='VSS104';
NODE_NAME     J32 242
 '@T6G_MB_LIB.T6G(SCH_1):PAGE101_I175@PURE_QUANTA.SCONN288_DDR506112002KQ(CHIPS)':
 'VSS105': CDS_PINID='VSS105';
NODE_NAME     J32 244
 '@T6G_MB_LIB.T6G(SCH_1):PAGE101_I175@PURE_QUANTA.SCONN288_DDR506112002KQ(CHIPS)':
 'VSS106': CDS_PINID='VSS106';
NODE_NAME     J32 246
 '@T6G_MB_LIB.T6G(SCH_1):PAGE101_I175@PURE_QUANTA.SCONN288_DDR506112002KQ(CHIPS)':
 'VSS107': CDS_PINID='VSS107';
NODE_NAME     J32 248
 '@T6G_MB_LIB.T6G(SCH_1):PAGE101_I175@PURE_QUANTA.SCONN288_DDR506112002KQ(CHIPS)':
 'VSS108': CDS_PINID='VSS108';
NODE_NAME     J32 251
 '@T6G_MB_LIB.T6G(SCH_1):PAGE101_I175@PURE_QUANTA.SCONN288_DDR506112002KQ(CHIPS)':
 'VSS109': CDS_PINID='VSS109';
NODE_NAME     J32 253
 '@T6G_MB_LIB.T6G(SCH_1):PAGE101_I175@PURE_QUANTA.SCONN288_DDR506112002KQ(CHIPS)':
 'VSS110': CDS_PINID='VSS110';
NODE_NAME     J32 255
 '@T6G_MB_LIB.T6G(SCH_1):PAGE101_I175@PURE_QUANTA.SCONN288_DDR506112002KQ(CHIPS)':
 'VSS111': CDS_PINID='VSS111';
NODE_NAME     J32 257
 '@T6G_MB_LIB.T6G(SCH_1):PAGE101_I175@PURE_QUANTA.SCONN288_DDR506112002KQ(CHIPS)':
 'VSS112': CDS_PINID='VSS112';
NODE_NAME     J32 259
 '@T6G_MB_LIB.T6G(SCH_1):PAGE101_I175@PURE_QUANTA.SCONN288_DDR506112002KQ(CHIPS)':
 'VSS113': CDS_PINID='VSS113';
NODE_NAME     J32 262
 '@T6G_MB_LIB.T6G(SCH_1):PAGE101_I175@PURE_QUANTA.SCONN288_DDR506112002KQ(CHIPS)':
 'VSS114': CDS_PINID='VSS114';
NODE_NAME     J32 264
 '@T6G_MB_LIB.T6G(SCH_1):PAGE101_I175@PURE_QUANTA.SCONN288_DDR506112002KQ(CHIPS)':
 'VSS115': CDS_PINID='VSS115';
NODE_NAME     J32 266
 '@T6G_MB_LIB.T6G(SCH_1):PAGE101_I175@PURE_QUANTA.SCONN288_DDR506112002KQ(CHIPS)':
 'VSS116': CDS_PINID='VSS116';
NODE_NAME     J32 268
 '@T6G_MB_LIB.T6G(SCH_1):PAGE101_I175@PURE_QUANTA.SCONN288_DDR506112002KQ(CHIPS)':
 'VSS117': CDS_PINID='VSS117';
NODE_NAME     J32 270
 '@T6G_MB_LIB.T6G(SCH_1):PAGE101_I175@PURE_QUANTA.SCONN288_DDR506112002KQ(CHIPS)':
 'VSS118': CDS_PINID='VSS118';
NODE_NAME     J32 273
 '@T6G_MB_LIB.T6G(SCH_1):PAGE101_I175@PURE_QUANTA.SCONN288_DDR506112002KQ(CHIPS)':
 'VSS119': CDS_PINID='VSS119';
NODE_NAME     J32 275
 '@T6G_MB_LIB.T6G(SCH_1):PAGE101_I175@PURE_QUANTA.SCONN288_DDR506112002KQ(CHIPS)':
 'VSS120': CDS_PINID='VSS120';
NODE_NAME     J32 277
 '@T6G_MB_LIB.T6G(SCH_1):PAGE101_I175@PURE_QUANTA.SCONN288_DDR506112002KQ(CHIPS)':
 'VSS121': CDS_PINID='VSS121';
NODE_NAME     J32 279
 '@T6G_MB_LIB.T6G(SCH_1):PAGE101_I175@PURE_QUANTA.SCONN288_DDR506112002KQ(CHIPS)':
 'VSS122': CDS_PINID='VSS122';
NODE_NAME     J32 281
 '@T6G_MB_LIB.T6G(SCH_1):PAGE101_I175@PURE_QUANTA.SCONN288_DDR506112002KQ(CHIPS)':
 'VSS123': CDS_PINID='VSS123';
NODE_NAME     J32 284
 '@T6G_MB_LIB.T6G(SCH_1):PAGE101_I175@PURE_QUANTA.SCONN288_DDR506112002KQ(CHIPS)':
 'VSS124': CDS_PINID='VSS124';
NODE_NAME     J32 286
 '@T6G_MB_LIB.T6G(SCH_1):PAGE101_I175@PURE_QUANTA.SCONN288_DDR506112002KQ(CHIPS)':
 'VSS125': CDS_PINID='VSS125';
NODE_NAME     J32 288
 '@T6G_MB_LIB.T6G(SCH_1):PAGE101_I175@PURE_QUANTA.SCONN288_DDR506112002KQ(CHIPS)':
 'VSS126': CDS_PINID='VSS126';
NODE_NAME     C152 2
 '@T6G_MB_LIB.T6G(SCH_1):PAGE101_I185@PURE_QUANTA.Q_CAP(CHIPS)':
 'B': CDS_PINID='B';
NODE_NAME     C183 2
 '@T6G_MB_LIB.T6G(SCH_1):PAGE101_I238@PURE_QUANTA.Q_CAP(CHIPS)':
 'B': CDS_PINID='B';
NODE_NAME     C509 2
 '@T6G_MB_LIB.T6G(SCH_1):PAGE101_I239@PURE_QUANTA.Q_CAP(CHIPS)':
 'B': CDS_PINID='B';
NODE_NAME     R773 2
 '@T6G_MB_LIB.T6G(SCH_1):PAGE102_I129@PURE_QUANTA.Q_RES(CHIPS)':
 'B': CDS_PINID='B';
NODE_NAME     J33 G1
 '@T6G_MB_LIB.T6G(SCH_1):PAGE102_I142@PURE_QUANTA.SCONN288_DDR506112002KQ(CHIPS)':
 'G1': CDS_PINID='G1';
NODE_NAME     J33 G2
 '@T6G_MB_LIB.T6G(SCH_1):PAGE102_I142@PURE_QUANTA.SCONN288_DDR506112002KQ(CHIPS)':
 'G2': CDS_PINID='G2';
NODE_NAME     J33 G3
 '@T6G_MB_LIB.T6G(SCH_1):PAGE102_I142@PURE_QUANTA.SCONN288_DDR506112002KQ(CHIPS)':
 'G3': CDS_PINID='G3';
NODE_NAME     J33 6
 '@T6G_MB_LIB.T6G(SCH_1):PAGE102_I142@PURE_QUANTA.SCONN288_DDR506112002KQ(CHIPS)':
 'VSS0': CDS_PINID='VSS0';
NODE_NAME     J33 8
 '@T6G_MB_LIB.T6G(SCH_1):PAGE102_I142@PURE_QUANTA.SCONN288_DDR506112002KQ(CHIPS)':
 'VSS1': CDS_PINID='VSS1';
NODE_NAME     J33 10
 '@T6G_MB_LIB.T6G(SCH_1):PAGE102_I142@PURE_QUANTA.SCONN288_DDR506112002KQ(CHIPS)':
 'VSS2': CDS_PINID='VSS2';
NODE_NAME     J33 13
 '@T6G_MB_LIB.T6G(SCH_1):PAGE102_I142@PURE_QUANTA.SCONN288_DDR506112002KQ(CHIPS)':
 'VSS3': CDS_PINID='VSS3';
NODE_NAME     J33 15
 '@T6G_MB_LIB.T6G(SCH_1):PAGE102_I142@PURE_QUANTA.SCONN288_DDR506112002KQ(CHIPS)':
 'VSS4': CDS_PINID='VSS4';
NODE_NAME     J33 17
 '@T6G_MB_LIB.T6G(SCH_1):PAGE102_I142@PURE_QUANTA.SCONN288_DDR506112002KQ(CHIPS)':
 'VSS5': CDS_PINID='VSS5';
NODE_NAME     J33 19
 '@T6G_MB_LIB.T6G(SCH_1):PAGE102_I142@PURE_QUANTA.SCONN288_DDR506112002KQ(CHIPS)':
 'VSS6': CDS_PINID='VSS6';
NODE_NAME     J33 21
 '@T6G_MB_LIB.T6G(SCH_1):PAGE102_I142@PURE_QUANTA.SCONN288_DDR506112002KQ(CHIPS)':
 'VSS7': CDS_PINID='VSS7';
NODE_NAME     J33 24
 '@T6G_MB_LIB.T6G(SCH_1):PAGE102_I142@PURE_QUANTA.SCONN288_DDR506112002KQ(CHIPS)':
 'VSS8': CDS_PINID='VSS8';
NODE_NAME     J33 26
 '@T6G_MB_LIB.T6G(SCH_1):PAGE102_I142@PURE_QUANTA.SCONN288_DDR506112002KQ(CHIPS)':
 'VSS9': CDS_PINID='VSS9';
NODE_NAME     J33 28
 '@T6G_MB_LIB.T6G(SCH_1):PAGE102_I142@PURE_QUANTA.SCONN288_DDR506112002KQ(CHIPS)':
 'VSS10': CDS_PINID='VSS10';
NODE_NAME     J33 30
 '@T6G_MB_LIB.T6G(SCH_1):PAGE102_I142@PURE_QUANTA.SCONN288_DDR506112002KQ(CHIPS)':
 'VSS11': CDS_PINID='VSS11';
NODE_NAME     J33 32
 '@T6G_MB_LIB.T6G(SCH_1):PAGE102_I142@PURE_QUANTA.SCONN288_DDR506112002KQ(CHIPS)':
 'VSS12': CDS_PINID='VSS12';
NODE_NAME     J33 35
 '@T6G_MB_LIB.T6G(SCH_1):PAGE102_I142@PURE_QUANTA.SCONN288_DDR506112002KQ(CHIPS)':
 'VSS13': CDS_PINID='VSS13';
NODE_NAME     J33 37
 '@T6G_MB_LIB.T6G(SCH_1):PAGE102_I142@PURE_QUANTA.SCONN288_DDR506112002KQ(CHIPS)':
 'VSS14': CDS_PINID='VSS14';
NODE_NAME     J33 39
 '@T6G_MB_LIB.T6G(SCH_1):PAGE102_I142@PURE_QUANTA.SCONN288_DDR506112002KQ(CHIPS)':
 'VSS15': CDS_PINID='VSS15';
NODE_NAME     J33 41
 '@T6G_MB_LIB.T6G(SCH_1):PAGE102_I142@PURE_QUANTA.SCONN288_DDR506112002KQ(CHIPS)':
 'VSS16': CDS_PINID='VSS16';
NODE_NAME     J33 43
 '@T6G_MB_LIB.T6G(SCH_1):PAGE102_I142@PURE_QUANTA.SCONN288_DDR506112002KQ(CHIPS)':
 'VSS17': CDS_PINID='VSS17';
NODE_NAME     J33 46
 '@T6G_MB_LIB.T6G(SCH_1):PAGE102_I142@PURE_QUANTA.SCONN288_DDR506112002KQ(CHIPS)':
 'VSS18': CDS_PINID='VSS18';
NODE_NAME     J33 48
 '@T6G_MB_LIB.T6G(SCH_1):PAGE102_I142@PURE_QUANTA.SCONN288_DDR506112002KQ(CHIPS)':
 'VSS19': CDS_PINID='VSS19';
NODE_NAME     J33 50
 '@T6G_MB_LIB.T6G(SCH_1):PAGE102_I142@PURE_QUANTA.SCONN288_DDR506112002KQ(CHIPS)':
 'VSS20': CDS_PINID='VSS20';
NODE_NAME     J33 52
 '@T6G_MB_LIB.T6G(SCH_1):PAGE102_I142@PURE_QUANTA.SCONN288_DDR506112002KQ(CHIPS)':
 'VSS21': CDS_PINID='VSS21';
NODE_NAME     J33 54
 '@T6G_MB_LIB.T6G(SCH_1):PAGE102_I142@PURE_QUANTA.SCONN288_DDR506112002KQ(CHIPS)':
 'VSS22': CDS_PINID='VSS22';
NODE_NAME     J33 57
 '@T6G_MB_LIB.T6G(SCH_1):PAGE102_I142@PURE_QUANTA.SCONN288_DDR506112002KQ(CHIPS)':
 'VSS23': CDS_PINID='VSS23';
NODE_NAME     J33 59
 '@T6G_MB_LIB.T6G(SCH_1):PAGE102_I142@PURE_QUANTA.SCONN288_DDR506112002KQ(CHIPS)':
 'VSS24': CDS_PINID='VSS24';
NODE_NAME     J33 61
 '@T6G_MB_LIB.T6G(SCH_1):PAGE102_I142@PURE_QUANTA.SCONN288_DDR506112002KQ(CHIPS)':
 'VSS25': CDS_PINID='VSS25';
NODE_NAME     J33 63
 '@T6G_MB_LIB.T6G(SCH_1):PAGE102_I142@PURE_QUANTA.SCONN288_DDR506112002KQ(CHIPS)':
 'VSS26': CDS_PINID='VSS26';
NODE_NAME     J33 65
 '@T6G_MB_LIB.T6G(SCH_1):PAGE102_I142@PURE_QUANTA.SCONN288_DDR506112002KQ(CHIPS)':
 'VSS27': CDS_PINID='VSS27';
NODE_NAME     J33 67
 '@T6G_MB_LIB.T6G(SCH_1):PAGE102_I142@PURE_QUANTA.SCONN288_DDR506112002KQ(CHIPS)':
 'VSS28': CDS_PINID='VSS28';
NODE_NAME     J33 69
 '@T6G_MB_LIB.T6G(SCH_1):PAGE102_I142@PURE_QUANTA.SCONN288_DDR506112002KQ(CHIPS)':
 'VSS29': CDS_PINID='VSS29';
NODE_NAME     J33 71
 '@T6G_MB_LIB.T6G(SCH_1):PAGE102_I142@PURE_QUANTA.SCONN288_DDR506112002KQ(CHIPS)':
 'VSS30': CDS_PINID='VSS30';
NODE_NAME     J33 73
 '@T6G_MB_LIB.T6G(SCH_1):PAGE102_I142@PURE_QUANTA.SCONN288_DDR506112002KQ(CHIPS)':
 'VSS31': CDS_PINID='VSS31';
NODE_NAME     J33 75
 '@T6G_MB_LIB.T6G(SCH_1):PAGE102_I142@PURE_QUANTA.SCONN288_DDR506112002KQ(CHIPS)':
 'VSS32': CDS_PINID='VSS32';
NODE_NAME     J33 77
 '@T6G_MB_LIB.T6G(SCH_1):PAGE102_I142@PURE_QUANTA.SCONN288_DDR506112002KQ(CHIPS)':
 'VSS33': CDS_PINID='VSS33';
NODE_NAME     J33 79
 '@T6G_MB_LIB.T6G(SCH_1):PAGE102_I142@PURE_QUANTA.SCONN288_DDR506112002KQ(CHIPS)':
 'VSS34': CDS_PINID='VSS34';
NODE_NAME     J33 81
 '@T6G_MB_LIB.T6G(SCH_1):PAGE102_I142@PURE_QUANTA.SCONN288_DDR506112002KQ(CHIPS)':
 'VSS35': CDS_PINID='VSS35';
NODE_NAME     J33 83
 '@T6G_MB_LIB.T6G(SCH_1):PAGE102_I142@PURE_QUANTA.SCONN288_DDR506112002KQ(CHIPS)':
 'VSS36': CDS_PINID='VSS36';
NODE_NAME     J33 85
 '@T6G_MB_LIB.T6G(SCH_1):PAGE102_I142@PURE_QUANTA.SCONN288_DDR506112002KQ(CHIPS)':
 'VSS37': CDS_PINID='VSS37';
NODE_NAME     J33 88
 '@T6G_MB_LIB.T6G(SCH_1):PAGE102_I142@PURE_QUANTA.SCONN288_DDR506112002KQ(CHIPS)':
 'VSS38': CDS_PINID='VSS38';
NODE_NAME     J33 90
 '@T6G_MB_LIB.T6G(SCH_1):PAGE102_I142@PURE_QUANTA.SCONN288_DDR506112002KQ(CHIPS)':
 'VSS39': CDS_PINID='VSS39';
NODE_NAME     J33 92
 '@T6G_MB_LIB.T6G(SCH_1):PAGE102_I142@PURE_QUANTA.SCONN288_DDR506112002KQ(CHIPS)':
 'VSS40': CDS_PINID='VSS40';
NODE_NAME     J33 95
 '@T6G_MB_LIB.T6G(SCH_1):PAGE102_I142@PURE_QUANTA.SCONN288_DDR506112002KQ(CHIPS)':
 'VSS41': CDS_PINID='VSS41';
NODE_NAME     J33 97
 '@T6G_MB_LIB.T6G(SCH_1):PAGE102_I142@PURE_QUANTA.SCONN288_DDR506112002KQ(CHIPS)':
 'VSS42': CDS_PINID='VSS42';
NODE_NAME     J33 99
 '@T6G_MB_LIB.T6G(SCH_1):PAGE102_I142@PURE_QUANTA.SCONN288_DDR506112002KQ(CHIPS)':
 'VSS43': CDS_PINID='VSS43';
NODE_NAME     J33 101
 '@T6G_MB_LIB.T6G(SCH_1):PAGE102_I142@PURE_QUANTA.SCONN288_DDR506112002KQ(CHIPS)':
 'VSS44': CDS_PINID='VSS44';
NODE_NAME     J33 103
 '@T6G_MB_LIB.T6G(SCH_1):PAGE102_I142@PURE_QUANTA.SCONN288_DDR506112002KQ(CHIPS)':
 'VSS45': CDS_PINID='VSS45';
NODE_NAME     J33 106
 '@T6G_MB_LIB.T6G(SCH_1):PAGE102_I142@PURE_QUANTA.SCONN288_DDR506112002KQ(CHIPS)':
 'VSS46': CDS_PINID='VSS46';
NODE_NAME     J33 108
 '@T6G_MB_LIB.T6G(SCH_1):PAGE102_I142@PURE_QUANTA.SCONN288_DDR506112002KQ(CHIPS)':
 'VSS47': CDS_PINID='VSS47';
NODE_NAME     J33 110
 '@T6G_MB_LIB.T6G(SCH_1):PAGE102_I142@PURE_QUANTA.SCONN288_DDR506112002KQ(CHIPS)':
 'VSS48': CDS_PINID='VSS48';
NODE_NAME     J33 112
 '@T6G_MB_LIB.T6G(SCH_1):PAGE102_I142@PURE_QUANTA.SCONN288_DDR506112002KQ(CHIPS)':
 'VSS49': CDS_PINID='VSS49';
NODE_NAME     J33 114
 '@T6G_MB_LIB.T6G(SCH_1):PAGE102_I142@PURE_QUANTA.SCONN288_DDR506112002KQ(CHIPS)':
 'VSS50': CDS_PINID='VSS50';
NODE_NAME     J33 117
 '@T6G_MB_LIB.T6G(SCH_1):PAGE102_I142@PURE_QUANTA.SCONN288_DDR506112002KQ(CHIPS)':
 'VSS51': CDS_PINID='VSS51';
NODE_NAME     J33 119
 '@T6G_MB_LIB.T6G(SCH_1):PAGE102_I142@PURE_QUANTA.SCONN288_DDR506112002KQ(CHIPS)':
 'VSS52': CDS_PINID='VSS52';
NODE_NAME     J33 121
 '@T6G_MB_LIB.T6G(SCH_1):PAGE102_I142@PURE_QUANTA.SCONN288_DDR506112002KQ(CHIPS)':
 'VSS53': CDS_PINID='VSS53';
NODE_NAME     J33 123
 '@T6G_MB_LIB.T6G(SCH_1):PAGE102_I142@PURE_QUANTA.SCONN288_DDR506112002KQ(CHIPS)':
 'VSS54': CDS_PINID='VSS54';
NODE_NAME     J33 125
 '@T6G_MB_LIB.T6G(SCH_1):PAGE102_I142@PURE_QUANTA.SCONN288_DDR506112002KQ(CHIPS)':
 'VSS55': CDS_PINID='VSS55';
NODE_NAME     J33 128
 '@T6G_MB_LIB.T6G(SCH_1):PAGE102_I142@PURE_QUANTA.SCONN288_DDR506112002KQ(CHIPS)':
 'VSS56': CDS_PINID='VSS56';
NODE_NAME     J33 130
 '@T6G_MB_LIB.T6G(SCH_1):PAGE102_I142@PURE_QUANTA.SCONN288_DDR506112002KQ(CHIPS)':
 'VSS57': CDS_PINID='VSS57';
NODE_NAME     J33 132
 '@T6G_MB_LIB.T6G(SCH_1):PAGE102_I142@PURE_QUANTA.SCONN288_DDR506112002KQ(CHIPS)':
 'VSS58': CDS_PINID='VSS58';
NODE_NAME     J33 134
 '@T6G_MB_LIB.T6G(SCH_1):PAGE102_I142@PURE_QUANTA.SCONN288_DDR506112002KQ(CHIPS)':
 'VSS59': CDS_PINID='VSS59';
NODE_NAME     J33 136
 '@T6G_MB_LIB.T6G(SCH_1):PAGE102_I142@PURE_QUANTA.SCONN288_DDR506112002KQ(CHIPS)':
 'VSS60': CDS_PINID='VSS60';
NODE_NAME     J33 139
 '@T6G_MB_LIB.T6G(SCH_1):PAGE102_I142@PURE_QUANTA.SCONN288_DDR506112002KQ(CHIPS)':
 'VSS61': CDS_PINID='VSS61';
NODE_NAME     J33 141
 '@T6G_MB_LIB.T6G(SCH_1):PAGE102_I142@PURE_QUANTA.SCONN288_DDR506112002KQ(CHIPS)':
 'VSS62': CDS_PINID='VSS62';
NODE_NAME     J33 143
 '@T6G_MB_LIB.T6G(SCH_1):PAGE102_I142@PURE_QUANTA.SCONN288_DDR506112002KQ(CHIPS)':
 'VSS63': CDS_PINID='VSS63';
NODE_NAME     J33 151
 '@T6G_MB_LIB.T6G(SCH_1):PAGE102_I142@PURE_QUANTA.SCONN288_DDR506112002KQ(CHIPS)':
 'VSS64': CDS_PINID='VSS64';
NODE_NAME     J33 153
 '@T6G_MB_LIB.T6G(SCH_1):PAGE102_I142@PURE_QUANTA.SCONN288_DDR506112002KQ(CHIPS)':
 'VSS65': CDS_PINID='VSS65';
NODE_NAME     J33 155
 '@T6G_MB_LIB.T6G(SCH_1):PAGE102_I142@PURE_QUANTA.SCONN288_DDR506112002KQ(CHIPS)':
 'VSS66': CDS_PINID='VSS66';
NODE_NAME     J33 158
 '@T6G_MB_LIB.T6G(SCH_1):PAGE102_I142@PURE_QUANTA.SCONN288_DDR506112002KQ(CHIPS)':
 'VSS67': CDS_PINID='VSS67';
NODE_NAME     J33 160
 '@T6G_MB_LIB.T6G(SCH_1):PAGE102_I142@PURE_QUANTA.SCONN288_DDR506112002KQ(CHIPS)':
 'VSS68': CDS_PINID='VSS68';
NODE_NAME     J33 162
 '@T6G_MB_LIB.T6G(SCH_1):PAGE102_I142@PURE_QUANTA.SCONN288_DDR506112002KQ(CHIPS)':
 'VSS69': CDS_PINID='VSS69';
NODE_NAME     J33 164
 '@T6G_MB_LIB.T6G(SCH_1):PAGE102_I142@PURE_QUANTA.SCONN288_DDR506112002KQ(CHIPS)':
 'VSS70': CDS_PINID='VSS70';
NODE_NAME     J33 166
 '@T6G_MB_LIB.T6G(SCH_1):PAGE102_I142@PURE_QUANTA.SCONN288_DDR506112002KQ(CHIPS)':
 'VSS71': CDS_PINID='VSS71';
NODE_NAME     J33 169
 '@T6G_MB_LIB.T6G(SCH_1):PAGE102_I142@PURE_QUANTA.SCONN288_DDR506112002KQ(CHIPS)':
 'VSS72': CDS_PINID='VSS72';
NODE_NAME     J33 171
 '@T6G_MB_LIB.T6G(SCH_1):PAGE102_I142@PURE_QUANTA.SCONN288_DDR506112002KQ(CHIPS)':
 'VSS73': CDS_PINID='VSS73';
NODE_NAME     J33 173
 '@T6G_MB_LIB.T6G(SCH_1):PAGE102_I142@PURE_QUANTA.SCONN288_DDR506112002KQ(CHIPS)':
 'VSS74': CDS_PINID='VSS74';
NODE_NAME     J33 175
 '@T6G_MB_LIB.T6G(SCH_1):PAGE102_I142@PURE_QUANTA.SCONN288_DDR506112002KQ(CHIPS)':
 'VSS75': CDS_PINID='VSS75';
NODE_NAME     J33 177
 '@T6G_MB_LIB.T6G(SCH_1):PAGE102_I142@PURE_QUANTA.SCONN288_DDR506112002KQ(CHIPS)':
 'VSS76': CDS_PINID='VSS76';
NODE_NAME     J33 180
 '@T6G_MB_LIB.T6G(SCH_1):PAGE102_I142@PURE_QUANTA.SCONN288_DDR506112002KQ(CHIPS)':
 'VSS77': CDS_PINID='VSS77';
NODE_NAME     J33 182
 '@T6G_MB_LIB.T6G(SCH_1):PAGE102_I142@PURE_QUANTA.SCONN288_DDR506112002KQ(CHIPS)':
 'VSS78': CDS_PINID='VSS78';
NODE_NAME     J33 184
 '@T6G_MB_LIB.T6G(SCH_1):PAGE102_I142@PURE_QUANTA.SCONN288_DDR506112002KQ(CHIPS)':
 'VSS79': CDS_PINID='VSS79';
NODE_NAME     J33 186
 '@T6G_MB_LIB.T6G(SCH_1):PAGE102_I142@PURE_QUANTA.SCONN288_DDR506112002KQ(CHIPS)':
 'VSS80': CDS_PINID='VSS80';
NODE_NAME     J33 188
 '@T6G_MB_LIB.T6G(SCH_1):PAGE102_I142@PURE_QUANTA.SCONN288_DDR506112002KQ(CHIPS)':
 'VSS81': CDS_PINID='VSS81';
NODE_NAME     J33 191
 '@T6G_MB_LIB.T6G(SCH_1):PAGE102_I142@PURE_QUANTA.SCONN288_DDR506112002KQ(CHIPS)':
 'VSS82': CDS_PINID='VSS82';
NODE_NAME     J33 193
 '@T6G_MB_LIB.T6G(SCH_1):PAGE102_I142@PURE_QUANTA.SCONN288_DDR506112002KQ(CHIPS)':
 'VSS83': CDS_PINID='VSS83';
NODE_NAME     J33 195
 '@T6G_MB_LIB.T6G(SCH_1):PAGE102_I142@PURE_QUANTA.SCONN288_DDR506112002KQ(CHIPS)':
 'VSS84': CDS_PINID='VSS84';
NODE_NAME     J33 197
 '@T6G_MB_LIB.T6G(SCH_1):PAGE102_I142@PURE_QUANTA.SCONN288_DDR506112002KQ(CHIPS)':
 'VSS85': CDS_PINID='VSS85';
NODE_NAME     J33 199
 '@T6G_MB_LIB.T6G(SCH_1):PAGE102_I142@PURE_QUANTA.SCONN288_DDR506112002KQ(CHIPS)':
 'VSS86': CDS_PINID='VSS86';
NODE_NAME     J33 202
 '@T6G_MB_LIB.T6G(SCH_1):PAGE102_I142@PURE_QUANTA.SCONN288_DDR506112002KQ(CHIPS)':
 'VSS87': CDS_PINID='VSS87';
NODE_NAME     J33 204
 '@T6G_MB_LIB.T6G(SCH_1):PAGE102_I142@PURE_QUANTA.SCONN288_DDR506112002KQ(CHIPS)':
 'VSS88': CDS_PINID='VSS88';
NODE_NAME     J33 206
 '@T6G_MB_LIB.T6G(SCH_1):PAGE102_I142@PURE_QUANTA.SCONN288_DDR506112002KQ(CHIPS)':
 'VSS89': CDS_PINID='VSS89';
NODE_NAME     J33 208
 '@T6G_MB_LIB.T6G(SCH_1):PAGE102_I142@PURE_QUANTA.SCONN288_DDR506112002KQ(CHIPS)':
 'VSS90': CDS_PINID='VSS90';
NODE_NAME     J33 210
 '@T6G_MB_LIB.T6G(SCH_1):PAGE102_I142@PURE_QUANTA.SCONN288_DDR506112002KQ(CHIPS)':
 'VSS91': CDS_PINID='VSS91';
NODE_NAME     J33 212
 '@T6G_MB_LIB.T6G(SCH_1):PAGE102_I142@PURE_QUANTA.SCONN288_DDR506112002KQ(CHIPS)':
 'VSS92': CDS_PINID='VSS92';
NODE_NAME     J33 214
 '@T6G_MB_LIB.T6G(SCH_1):PAGE102_I142@PURE_QUANTA.SCONN288_DDR506112002KQ(CHIPS)':
 'VSS93': CDS_PINID='VSS93';
NODE_NAME     J33 216
 '@T6G_MB_LIB.T6G(SCH_1):PAGE102_I142@PURE_QUANTA.SCONN288_DDR506112002KQ(CHIPS)':
 'VSS94': CDS_PINID='VSS94';
NODE_NAME     J33 219
 '@T6G_MB_LIB.T6G(SCH_1):PAGE102_I142@PURE_QUANTA.SCONN288_DDR506112002KQ(CHIPS)':
 'VSS95': CDS_PINID='VSS95';
NODE_NAME     J33 222
 '@T6G_MB_LIB.T6G(SCH_1):PAGE102_I142@PURE_QUANTA.SCONN288_DDR506112002KQ(CHIPS)':
 'VSS96': CDS_PINID='VSS96';
NODE_NAME     J33 224
 '@T6G_MB_LIB.T6G(SCH_1):PAGE102_I142@PURE_QUANTA.SCONN288_DDR506112002KQ(CHIPS)':
 'VSS97': CDS_PINID='VSS97';
NODE_NAME     J33 226
 '@T6G_MB_LIB.T6G(SCH_1):PAGE102_I142@PURE_QUANTA.SCONN288_DDR506112002KQ(CHIPS)':
 'VSS98': CDS_PINID='VSS98';
NODE_NAME     J33 228
 '@T6G_MB_LIB.T6G(SCH_1):PAGE102_I142@PURE_QUANTA.SCONN288_DDR506112002KQ(CHIPS)':
 'VSS99': CDS_PINID='VSS99';
NODE_NAME     J33 230
 '@T6G_MB_LIB.T6G(SCH_1):PAGE102_I142@PURE_QUANTA.SCONN288_DDR506112002KQ(CHIPS)':
 'VSS100': CDS_PINID='VSS100';
NODE_NAME     J33 233
 '@T6G_MB_LIB.T6G(SCH_1):PAGE102_I142@PURE_QUANTA.SCONN288_DDR506112002KQ(CHIPS)':
 'VSS101': CDS_PINID='VSS101';
NODE_NAME     J33 235
 '@T6G_MB_LIB.T6G(SCH_1):PAGE102_I142@PURE_QUANTA.SCONN288_DDR506112002KQ(CHIPS)':
 'VSS102': CDS_PINID='VSS102';
NODE_NAME     J33 237
 '@T6G_MB_LIB.T6G(SCH_1):PAGE102_I142@PURE_QUANTA.SCONN288_DDR506112002KQ(CHIPS)':
 'VSS103': CDS_PINID='VSS103';
NODE_NAME     J33 240
 '@T6G_MB_LIB.T6G(SCH_1):PAGE102_I142@PURE_QUANTA.SCONN288_DDR506112002KQ(CHIPS)':
 'VSS104': CDS_PINID='VSS104';
NODE_NAME     J33 242
 '@T6G_MB_LIB.T6G(SCH_1):PAGE102_I142@PURE_QUANTA.SCONN288_DDR506112002KQ(CHIPS)':
 'VSS105': CDS_PINID='VSS105';
NODE_NAME     J33 244
 '@T6G_MB_LIB.T6G(SCH_1):PAGE102_I142@PURE_QUANTA.SCONN288_DDR506112002KQ(CHIPS)':
 'VSS106': CDS_PINID='VSS106';
NODE_NAME     J33 246
 '@T6G_MB_LIB.T6G(SCH_1):PAGE102_I142@PURE_QUANTA.SCONN288_DDR506112002KQ(CHIPS)':
 'VSS107': CDS_PINID='VSS107';
NODE_NAME     J33 248
 '@T6G_MB_LIB.T6G(SCH_1):PAGE102_I142@PURE_QUANTA.SCONN288_DDR506112002KQ(CHIPS)':
 'VSS108': CDS_PINID='VSS108';
NODE_NAME     J33 251
 '@T6G_MB_LIB.T6G(SCH_1):PAGE102_I142@PURE_QUANTA.SCONN288_DDR506112002KQ(CHIPS)':
 'VSS109': CDS_PINID='VSS109';
NODE_NAME     J33 253
 '@T6G_MB_LIB.T6G(SCH_1):PAGE102_I142@PURE_QUANTA.SCONN288_DDR506112002KQ(CHIPS)':
 'VSS110': CDS_PINID='VSS110';
NODE_NAME     J33 255
 '@T6G_MB_LIB.T6G(SCH_1):PAGE102_I142@PURE_QUANTA.SCONN288_DDR506112002KQ(CHIPS)':
 'VSS111': CDS_PINID='VSS111';
NODE_NAME     J33 257
 '@T6G_MB_LIB.T6G(SCH_1):PAGE102_I142@PURE_QUANTA.SCONN288_DDR506112002KQ(CHIPS)':
 'VSS112': CDS_PINID='VSS112';
NODE_NAME     J33 259
 '@T6G_MB_LIB.T6G(SCH_1):PAGE102_I142@PURE_QUANTA.SCONN288_DDR506112002KQ(CHIPS)':
 'VSS113': CDS_PINID='VSS113';
NODE_NAME     J33 262
 '@T6G_MB_LIB.T6G(SCH_1):PAGE102_I142@PURE_QUANTA.SCONN288_DDR506112002KQ(CHIPS)':
 'VSS114': CDS_PINID='VSS114';
NODE_NAME     J33 264
 '@T6G_MB_LIB.T6G(SCH_1):PAGE102_I142@PURE_QUANTA.SCONN288_DDR506112002KQ(CHIPS)':
 'VSS115': CDS_PINID='VSS115';
NODE_NAME     J33 266
 '@T6G_MB_LIB.T6G(SCH_1):PAGE102_I142@PURE_QUANTA.SCONN288_DDR506112002KQ(CHIPS)':
 'VSS116': CDS_PINID='VSS116';
NODE_NAME     J33 268
 '@T6G_MB_LIB.T6G(SCH_1):PAGE102_I142@PURE_QUANTA.SCONN288_DDR506112002KQ(CHIPS)':
 'VSS117': CDS_PINID='VSS117';
NODE_NAME     J33 270
 '@T6G_MB_LIB.T6G(SCH_1):PAGE102_I142@PURE_QUANTA.SCONN288_DDR506112002KQ(CHIPS)':
 'VSS118': CDS_PINID='VSS118';
NODE_NAME     J33 273
 '@T6G_MB_LIB.T6G(SCH_1):PAGE102_I142@PURE_QUANTA.SCONN288_DDR506112002KQ(CHIPS)':
 'VSS119': CDS_PINID='VSS119';
NODE_NAME     J33 275
 '@T6G_MB_LIB.T6G(SCH_1):PAGE102_I142@PURE_QUANTA.SCONN288_DDR506112002KQ(CHIPS)':
 'VSS120': CDS_PINID='VSS120';
NODE_NAME     J33 277
 '@T6G_MB_LIB.T6G(SCH_1):PAGE102_I142@PURE_QUANTA.SCONN288_DDR506112002KQ(CHIPS)':
 'VSS121': CDS_PINID='VSS121';
NODE_NAME     J33 279
 '@T6G_MB_LIB.T6G(SCH_1):PAGE102_I142@PURE_QUANTA.SCONN288_DDR506112002KQ(CHIPS)':
 'VSS122': CDS_PINID='VSS122';
NODE_NAME     J33 281
 '@T6G_MB_LIB.T6G(SCH_1):PAGE102_I142@PURE_QUANTA.SCONN288_DDR506112002KQ(CHIPS)':
 'VSS123': CDS_PINID='VSS123';
NODE_NAME     J33 284
 '@T6G_MB_LIB.T6G(SCH_1):PAGE102_I142@PURE_QUANTA.SCONN288_DDR506112002KQ(CHIPS)':
 'VSS124': CDS_PINID='VSS124';
NODE_NAME     J33 286
 '@T6G_MB_LIB.T6G(SCH_1):PAGE102_I142@PURE_QUANTA.SCONN288_DDR506112002KQ(CHIPS)':
 'VSS125': CDS_PINID='VSS125';
NODE_NAME     J33 288
 '@T6G_MB_LIB.T6G(SCH_1):PAGE102_I142@PURE_QUANTA.SCONN288_DDR506112002KQ(CHIPS)':
 'VSS126': CDS_PINID='VSS126';
NODE_NAME     C156 2
 '@T6G_MB_LIB.T6G(SCH_1):PAGE102_I185@PURE_QUANTA.Q_CAP(CHIPS)':
 'B': CDS_PINID='B';
NODE_NAME     C518 2
 '@T6G_MB_LIB.T6G(SCH_1):PAGE102_I238@PURE_QUANTA.Q_CAP(CHIPS)':
 'B': CDS_PINID='B';
NODE_NAME     C527 2
 '@T6G_MB_LIB.T6G(SCH_1):PAGE102_I239@PURE_QUANTA.Q_CAP(CHIPS)':
 'B': CDS_PINID='B';
NODE_NAME     R37 2
 '@T6G_MB_LIB.T6G(SCH_1):PAGE103_I129@PURE_QUANTA.Q_RES(CHIPS)':
 'B':XNET_PINS='2',
 CDS_PINID='B';
NODE_NAME     J102 G1
 '@T6G_MB_LIB.T6G(SCH_1):PAGE103_I142@PURE_QUANTA.SCONN288_DDR506112002KQ(CHIPS)':
 'G1': CDS_PINID='G1';
NODE_NAME     J102 G2
 '@T6G_MB_LIB.T6G(SCH_1):PAGE103_I142@PURE_QUANTA.SCONN288_DDR506112002KQ(CHIPS)':
 'G2': CDS_PINID='G2';
NODE_NAME     J102 G3
 '@T6G_MB_LIB.T6G(SCH_1):PAGE103_I142@PURE_QUANTA.SCONN288_DDR506112002KQ(CHIPS)':
 'G3': CDS_PINID='G3';
NODE_NAME     J102 6
 '@T6G_MB_LIB.T6G(SCH_1):PAGE103_I142@PURE_QUANTA.SCONN288_DDR506112002KQ(CHIPS)':
 'VSS0': CDS_PINID='VSS0';
NODE_NAME     J102 8
 '@T6G_MB_LIB.T6G(SCH_1):PAGE103_I142@PURE_QUANTA.SCONN288_DDR506112002KQ(CHIPS)':
 'VSS1': CDS_PINID='VSS1';
NODE_NAME     J102 10
 '@T6G_MB_LIB.T6G(SCH_1):PAGE103_I142@PURE_QUANTA.SCONN288_DDR506112002KQ(CHIPS)':
 'VSS2': CDS_PINID='VSS2';
NODE_NAME     J102 13
 '@T6G_MB_LIB.T6G(SCH_1):PAGE103_I142@PURE_QUANTA.SCONN288_DDR506112002KQ(CHIPS)':
 'VSS3': CDS_PINID='VSS3';
NODE_NAME     J102 15
 '@T6G_MB_LIB.T6G(SCH_1):PAGE103_I142@PURE_QUANTA.SCONN288_DDR506112002KQ(CHIPS)':
 'VSS4': CDS_PINID='VSS4';
NODE_NAME     J102 17
 '@T6G_MB_LIB.T6G(SCH_1):PAGE103_I142@PURE_QUANTA.SCONN288_DDR506112002KQ(CHIPS)':
 'VSS5': CDS_PINID='VSS5';
NODE_NAME     J102 19
 '@T6G_MB_LIB.T6G(SCH_1):PAGE103_I142@PURE_QUANTA.SCONN288_DDR506112002KQ(CHIPS)':
 'VSS6': CDS_PINID='VSS6';
NODE_NAME     J102 21
 '@T6G_MB_LIB.T6G(SCH_1):PAGE103_I142@PURE_QUANTA.SCONN288_DDR506112002KQ(CHIPS)':
 'VSS7': CDS_PINID='VSS7';
NODE_NAME     J102 24
 '@T6G_MB_LIB.T6G(SCH_1):PAGE103_I142@PURE_QUANTA.SCONN288_DDR506112002KQ(CHIPS)':
 'VSS8': CDS_PINID='VSS8';
NODE_NAME     J102 26
 '@T6G_MB_LIB.T6G(SCH_1):PAGE103_I142@PURE_QUANTA.SCONN288_DDR506112002KQ(CHIPS)':
 'VSS9': CDS_PINID='VSS9';
NODE_NAME     J102 28
 '@T6G_MB_LIB.T6G(SCH_1):PAGE103_I142@PURE_QUANTA.SCONN288_DDR506112002KQ(CHIPS)':
 'VSS10': CDS_PINID='VSS10';
NODE_NAME     J102 30
 '@T6G_MB_LIB.T6G(SCH_1):PAGE103_I142@PURE_QUANTA.SCONN288_DDR506112002KQ(CHIPS)':
 'VSS11': CDS_PINID='VSS11';
NODE_NAME     J102 32
 '@T6G_MB_LIB.T6G(SCH_1):PAGE103_I142@PURE_QUANTA.SCONN288_DDR506112002KQ(CHIPS)':
 'VSS12': CDS_PINID='VSS12';
NODE_NAME     J102 35
 '@T6G_MB_LIB.T6G(SCH_1):PAGE103_I142@PURE_QUANTA.SCONN288_DDR506112002KQ(CHIPS)':
 'VSS13': CDS_PINID='VSS13';
NODE_NAME     J102 37
 '@T6G_MB_LIB.T6G(SCH_1):PAGE103_I142@PURE_QUANTA.SCONN288_DDR506112002KQ(CHIPS)':
 'VSS14': CDS_PINID='VSS14';
NODE_NAME     J102 39
 '@T6G_MB_LIB.T6G(SCH_1):PAGE103_I142@PURE_QUANTA.SCONN288_DDR506112002KQ(CHIPS)':
 'VSS15': CDS_PINID='VSS15';
NODE_NAME     J102 41
 '@T6G_MB_LIB.T6G(SCH_1):PAGE103_I142@PURE_QUANTA.SCONN288_DDR506112002KQ(CHIPS)':
 'VSS16': CDS_PINID='VSS16';
NODE_NAME     J102 43
 '@T6G_MB_LIB.T6G(SCH_1):PAGE103_I142@PURE_QUANTA.SCONN288_DDR506112002KQ(CHIPS)':
 'VSS17': CDS_PINID='VSS17';
NODE_NAME     J102 46
 '@T6G_MB_LIB.T6G(SCH_1):PAGE103_I142@PURE_QUANTA.SCONN288_DDR506112002KQ(CHIPS)':
 'VSS18': CDS_PINID='VSS18';
NODE_NAME     J102 48
 '@T6G_MB_LIB.T6G(SCH_1):PAGE103_I142@PURE_QUANTA.SCONN288_DDR506112002KQ(CHIPS)':
 'VSS19': CDS_PINID='VSS19';
NODE_NAME     J102 50
 '@T6G_MB_LIB.T6G(SCH_1):PAGE103_I142@PURE_QUANTA.SCONN288_DDR506112002KQ(CHIPS)':
 'VSS20': CDS_PINID='VSS20';
NODE_NAME     J102 52
 '@T6G_MB_LIB.T6G(SCH_1):PAGE103_I142@PURE_QUANTA.SCONN288_DDR506112002KQ(CHIPS)':
 'VSS21': CDS_PINID='VSS21';
NODE_NAME     J102 54
 '@T6G_MB_LIB.T6G(SCH_1):PAGE103_I142@PURE_QUANTA.SCONN288_DDR506112002KQ(CHIPS)':
 'VSS22': CDS_PINID='VSS22';
NODE_NAME     J102 57
 '@T6G_MB_LIB.T6G(SCH_1):PAGE103_I142@PURE_QUANTA.SCONN288_DDR506112002KQ(CHIPS)':
 'VSS23': CDS_PINID='VSS23';
NODE_NAME     J102 59
 '@T6G_MB_LIB.T6G(SCH_1):PAGE103_I142@PURE_QUANTA.SCONN288_DDR506112002KQ(CHIPS)':
 'VSS24': CDS_PINID='VSS24';
NODE_NAME     J102 61
 '@T6G_MB_LIB.T6G(SCH_1):PAGE103_I142@PURE_QUANTA.SCONN288_DDR506112002KQ(CHIPS)':
 'VSS25': CDS_PINID='VSS25';
NODE_NAME     J102 63
 '@T6G_MB_LIB.T6G(SCH_1):PAGE103_I142@PURE_QUANTA.SCONN288_DDR506112002KQ(CHIPS)':
 'VSS26': CDS_PINID='VSS26';
NODE_NAME     J102 65
 '@T6G_MB_LIB.T6G(SCH_1):PAGE103_I142@PURE_QUANTA.SCONN288_DDR506112002KQ(CHIPS)':
 'VSS27': CDS_PINID='VSS27';
NODE_NAME     J102 67
 '@T6G_MB_LIB.T6G(SCH_1):PAGE103_I142@PURE_QUANTA.SCONN288_DDR506112002KQ(CHIPS)':
 'VSS28': CDS_PINID='VSS28';
NODE_NAME     J102 69
 '@T6G_MB_LIB.T6G(SCH_1):PAGE103_I142@PURE_QUANTA.SCONN288_DDR506112002KQ(CHIPS)':
 'VSS29': CDS_PINID='VSS29';
NODE_NAME     J102 71
 '@T6G_MB_LIB.T6G(SCH_1):PAGE103_I142@PURE_QUANTA.SCONN288_DDR506112002KQ(CHIPS)':
 'VSS30': CDS_PINID='VSS30';
NODE_NAME     J102 73
 '@T6G_MB_LIB.T6G(SCH_1):PAGE103_I142@PURE_QUANTA.SCONN288_DDR506112002KQ(CHIPS)':
 'VSS31': CDS_PINID='VSS31';
NODE_NAME     J102 75
 '@T6G_MB_LIB.T6G(SCH_1):PAGE103_I142@PURE_QUANTA.SCONN288_DDR506112002KQ(CHIPS)':
 'VSS32': CDS_PINID='VSS32';
NODE_NAME     J102 77
 '@T6G_MB_LIB.T6G(SCH_1):PAGE103_I142@PURE_QUANTA.SCONN288_DDR506112002KQ(CHIPS)':
 'VSS33': CDS_PINID='VSS33';
NODE_NAME     J102 79
 '@T6G_MB_LIB.T6G(SCH_1):PAGE103_I142@PURE_QUANTA.SCONN288_DDR506112002KQ(CHIPS)':
 'VSS34': CDS_PINID='VSS34';
NODE_NAME     J102 81
 '@T6G_MB_LIB.T6G(SCH_1):PAGE103_I142@PURE_QUANTA.SCONN288_DDR506112002KQ(CHIPS)':
 'VSS35': CDS_PINID='VSS35';
NODE_NAME     J102 83
 '@T6G_MB_LIB.T6G(SCH_1):PAGE103_I142@PURE_QUANTA.SCONN288_DDR506112002KQ(CHIPS)':
 'VSS36': CDS_PINID='VSS36';
NODE_NAME     J102 85
 '@T6G_MB_LIB.T6G(SCH_1):PAGE103_I142@PURE_QUANTA.SCONN288_DDR506112002KQ(CHIPS)':
 'VSS37': CDS_PINID='VSS37';
NODE_NAME     J102 88
 '@T6G_MB_LIB.T6G(SCH_1):PAGE103_I142@PURE_QUANTA.SCONN288_DDR506112002KQ(CHIPS)':
 'VSS38': CDS_PINID='VSS38';
NODE_NAME     J102 90
 '@T6G_MB_LIB.T6G(SCH_1):PAGE103_I142@PURE_QUANTA.SCONN288_DDR506112002KQ(CHIPS)':
 'VSS39': CDS_PINID='VSS39';
NODE_NAME     J102 92
 '@T6G_MB_LIB.T6G(SCH_1):PAGE103_I142@PURE_QUANTA.SCONN288_DDR506112002KQ(CHIPS)':
 'VSS40': CDS_PINID='VSS40';
NODE_NAME     J102 95
 '@T6G_MB_LIB.T6G(SCH_1):PAGE103_I142@PURE_QUANTA.SCONN288_DDR506112002KQ(CHIPS)':
 'VSS41': CDS_PINID='VSS41';
NODE_NAME     J102 97
 '@T6G_MB_LIB.T6G(SCH_1):PAGE103_I142@PURE_QUANTA.SCONN288_DDR506112002KQ(CHIPS)':
 'VSS42': CDS_PINID='VSS42';
NODE_NAME     J102 99
 '@T6G_MB_LIB.T6G(SCH_1):PAGE103_I142@PURE_QUANTA.SCONN288_DDR506112002KQ(CHIPS)':
 'VSS43': CDS_PINID='VSS43';
NODE_NAME     J102 101
 '@T6G_MB_LIB.T6G(SCH_1):PAGE103_I142@PURE_QUANTA.SCONN288_DDR506112002KQ(CHIPS)':
 'VSS44': CDS_PINID='VSS44';
NODE_NAME     J102 103
 '@T6G_MB_LIB.T6G(SCH_1):PAGE103_I142@PURE_QUANTA.SCONN288_DDR506112002KQ(CHIPS)':
 'VSS45': CDS_PINID='VSS45';
NODE_NAME     J102 106
 '@T6G_MB_LIB.T6G(SCH_1):PAGE103_I142@PURE_QUANTA.SCONN288_DDR506112002KQ(CHIPS)':
 'VSS46': CDS_PINID='VSS46';
NODE_NAME     J102 108
 '@T6G_MB_LIB.T6G(SCH_1):PAGE103_I142@PURE_QUANTA.SCONN288_DDR506112002KQ(CHIPS)':
 'VSS47': CDS_PINID='VSS47';
NODE_NAME     J102 110
 '@T6G_MB_LIB.T6G(SCH_1):PAGE103_I142@PURE_QUANTA.SCONN288_DDR506112002KQ(CHIPS)':
 'VSS48': CDS_PINID='VSS48';
NODE_NAME     J102 112
 '@T6G_MB_LIB.T6G(SCH_1):PAGE103_I142@PURE_QUANTA.SCONN288_DDR506112002KQ(CHIPS)':
 'VSS49': CDS_PINID='VSS49';
NODE_NAME     J102 114
 '@T6G_MB_LIB.T6G(SCH_1):PAGE103_I142@PURE_QUANTA.SCONN288_DDR506112002KQ(CHIPS)':
 'VSS50': CDS_PINID='VSS50';
NODE_NAME     J102 117
 '@T6G_MB_LIB.T6G(SCH_1):PAGE103_I142@PURE_QUANTA.SCONN288_DDR506112002KQ(CHIPS)':
 'VSS51': CDS_PINID='VSS51';
NODE_NAME     J102 119
 '@T6G_MB_LIB.T6G(SCH_1):PAGE103_I142@PURE_QUANTA.SCONN288_DDR506112002KQ(CHIPS)':
 'VSS52': CDS_PINID='VSS52';
NODE_NAME     J102 121
 '@T6G_MB_LIB.T6G(SCH_1):PAGE103_I142@PURE_QUANTA.SCONN288_DDR506112002KQ(CHIPS)':
 'VSS53': CDS_PINID='VSS53';
NODE_NAME     J102 123
 '@T6G_MB_LIB.T6G(SCH_1):PAGE103_I142@PURE_QUANTA.SCONN288_DDR506112002KQ(CHIPS)':
 'VSS54': CDS_PINID='VSS54';
NODE_NAME     J102 125
 '@T6G_MB_LIB.T6G(SCH_1):PAGE103_I142@PURE_QUANTA.SCONN288_DDR506112002KQ(CHIPS)':
 'VSS55': CDS_PINID='VSS55';
NODE_NAME     J102 128
 '@T6G_MB_LIB.T6G(SCH_1):PAGE103_I142@PURE_QUANTA.SCONN288_DDR506112002KQ(CHIPS)':
 'VSS56': CDS_PINID='VSS56';
NODE_NAME     J102 130
 '@T6G_MB_LIB.T6G(SCH_1):PAGE103_I142@PURE_QUANTA.SCONN288_DDR506112002KQ(CHIPS)':
 'VSS57': CDS_PINID='VSS57';
NODE_NAME     J102 132
 '@T6G_MB_LIB.T6G(SCH_1):PAGE103_I142@PURE_QUANTA.SCONN288_DDR506112002KQ(CHIPS)':
 'VSS58': CDS_PINID='VSS58';
NODE_NAME     J102 134
 '@T6G_MB_LIB.T6G(SCH_1):PAGE103_I142@PURE_QUANTA.SCONN288_DDR506112002KQ(CHIPS)':
 'VSS59': CDS_PINID='VSS59';
NODE_NAME     J102 136
 '@T6G_MB_LIB.T6G(SCH_1):PAGE103_I142@PURE_QUANTA.SCONN288_DDR506112002KQ(CHIPS)':
 'VSS60': CDS_PINID='VSS60';
NODE_NAME     J102 139
 '@T6G_MB_LIB.T6G(SCH_1):PAGE103_I142@PURE_QUANTA.SCONN288_DDR506112002KQ(CHIPS)':
 'VSS61': CDS_PINID='VSS61';
NODE_NAME     J102 141
 '@T6G_MB_LIB.T6G(SCH_1):PAGE103_I142@PURE_QUANTA.SCONN288_DDR506112002KQ(CHIPS)':
 'VSS62': CDS_PINID='VSS62';
NODE_NAME     J102 143
 '@T6G_MB_LIB.T6G(SCH_1):PAGE103_I142@PURE_QUANTA.SCONN288_DDR506112002KQ(CHIPS)':
 'VSS63': CDS_PINID='VSS63';
NODE_NAME     J102 151
 '@T6G_MB_LIB.T6G(SCH_1):PAGE103_I142@PURE_QUANTA.SCONN288_DDR506112002KQ(CHIPS)':
 'VSS64': CDS_PINID='VSS64';
NODE_NAME     J102 153
 '@T6G_MB_LIB.T6G(SCH_1):PAGE103_I142@PURE_QUANTA.SCONN288_DDR506112002KQ(CHIPS)':
 'VSS65': CDS_PINID='VSS65';
NODE_NAME     J102 155
 '@T6G_MB_LIB.T6G(SCH_1):PAGE103_I142@PURE_QUANTA.SCONN288_DDR506112002KQ(CHIPS)':
 'VSS66': CDS_PINID='VSS66';
NODE_NAME     J102 158
 '@T6G_MB_LIB.T6G(SCH_1):PAGE103_I142@PURE_QUANTA.SCONN288_DDR506112002KQ(CHIPS)':
 'VSS67': CDS_PINID='VSS67';
NODE_NAME     J102 160
 '@T6G_MB_LIB.T6G(SCH_1):PAGE103_I142@PURE_QUANTA.SCONN288_DDR506112002KQ(CHIPS)':
 'VSS68': CDS_PINID='VSS68';
NODE_NAME     J102 162
 '@T6G_MB_LIB.T6G(SCH_1):PAGE103_I142@PURE_QUANTA.SCONN288_DDR506112002KQ(CHIPS)':
 'VSS69': CDS_PINID='VSS69';
NODE_NAME     J102 164
 '@T6G_MB_LIB.T6G(SCH_1):PAGE103_I142@PURE_QUANTA.SCONN288_DDR506112002KQ(CHIPS)':
 'VSS70': CDS_PINID='VSS70';
NODE_NAME     J102 166
 '@T6G_MB_LIB.T6G(SCH_1):PAGE103_I142@PURE_QUANTA.SCONN288_DDR506112002KQ(CHIPS)':
 'VSS71': CDS_PINID='VSS71';
NODE_NAME     J102 169
 '@T6G_MB_LIB.T6G(SCH_1):PAGE103_I142@PURE_QUANTA.SCONN288_DDR506112002KQ(CHIPS)':
 'VSS72': CDS_PINID='VSS72';
NODE_NAME     J102 171
 '@T6G_MB_LIB.T6G(SCH_1):PAGE103_I142@PURE_QUANTA.SCONN288_DDR506112002KQ(CHIPS)':
 'VSS73': CDS_PINID='VSS73';
NODE_NAME     J102 173
 '@T6G_MB_LIB.T6G(SCH_1):PAGE103_I142@PURE_QUANTA.SCONN288_DDR506112002KQ(CHIPS)':
 'VSS74': CDS_PINID='VSS74';
NODE_NAME     J102 175
 '@T6G_MB_LIB.T6G(SCH_1):PAGE103_I142@PURE_QUANTA.SCONN288_DDR506112002KQ(CHIPS)':
 'VSS75': CDS_PINID='VSS75';
NODE_NAME     J102 177
 '@T6G_MB_LIB.T6G(SCH_1):PAGE103_I142@PURE_QUANTA.SCONN288_DDR506112002KQ(CHIPS)':
 'VSS76': CDS_PINID='VSS76';
NODE_NAME     J102 180
 '@T6G_MB_LIB.T6G(SCH_1):PAGE103_I142@PURE_QUANTA.SCONN288_DDR506112002KQ(CHIPS)':
 'VSS77': CDS_PINID='VSS77';
NODE_NAME     J102 182
 '@T6G_MB_LIB.T6G(SCH_1):PAGE103_I142@PURE_QUANTA.SCONN288_DDR506112002KQ(CHIPS)':
 'VSS78': CDS_PINID='VSS78';
NODE_NAME     J102 184
 '@T6G_MB_LIB.T6G(SCH_1):PAGE103_I142@PURE_QUANTA.SCONN288_DDR506112002KQ(CHIPS)':
 'VSS79': CDS_PINID='VSS79';
NODE_NAME     J102 186
 '@T6G_MB_LIB.T6G(SCH_1):PAGE103_I142@PURE_QUANTA.SCONN288_DDR506112002KQ(CHIPS)':
 'VSS80': CDS_PINID='VSS80';
NODE_NAME     J102 188
 '@T6G_MB_LIB.T6G(SCH_1):PAGE103_I142@PURE_QUANTA.SCONN288_DDR506112002KQ(CHIPS)':
 'VSS81': CDS_PINID='VSS81';
NODE_NAME     J102 191
 '@T6G_MB_LIB.T6G(SCH_1):PAGE103_I142@PURE_QUANTA.SCONN288_DDR506112002KQ(CHIPS)':
 'VSS82': CDS_PINID='VSS82';
NODE_NAME     J102 193
 '@T6G_MB_LIB.T6G(SCH_1):PAGE103_I142@PURE_QUANTA.SCONN288_DDR506112002KQ(CHIPS)':
 'VSS83': CDS_PINID='VSS83';
NODE_NAME     J102 195
 '@T6G_MB_LIB.T6G(SCH_1):PAGE103_I142@PURE_QUANTA.SCONN288_DDR506112002KQ(CHIPS)':
 'VSS84': CDS_PINID='VSS84';
NODE_NAME     J102 197
 '@T6G_MB_LIB.T6G(SCH_1):PAGE103_I142@PURE_QUANTA.SCONN288_DDR506112002KQ(CHIPS)':
 'VSS85': CDS_PINID='VSS85';
NODE_NAME     J102 199
 '@T6G_MB_LIB.T6G(SCH_1):PAGE103_I142@PURE_QUANTA.SCONN288_DDR506112002KQ(CHIPS)':
 'VSS86': CDS_PINID='VSS86';
NODE_NAME     J102 202
 '@T6G_MB_LIB.T6G(SCH_1):PAGE103_I142@PURE_QUANTA.SCONN288_DDR506112002KQ(CHIPS)':
 'VSS87': CDS_PINID='VSS87';
NODE_NAME     J102 204
 '@T6G_MB_LIB.T6G(SCH_1):PAGE103_I142@PURE_QUANTA.SCONN288_DDR506112002KQ(CHIPS)':
 'VSS88': CDS_PINID='VSS88';
NODE_NAME     J102 206
 '@T6G_MB_LIB.T6G(SCH_1):PAGE103_I142@PURE_QUANTA.SCONN288_DDR506112002KQ(CHIPS)':
 'VSS89': CDS_PINID='VSS89';
NODE_NAME     J102 208
 '@T6G_MB_LIB.T6G(SCH_1):PAGE103_I142@PURE_QUANTA.SCONN288_DDR506112002KQ(CHIPS)':
 'VSS90': CDS_PINID='VSS90';
NODE_NAME     J102 210
 '@T6G_MB_LIB.T6G(SCH_1):PAGE103_I142@PURE_QUANTA.SCONN288_DDR506112002KQ(CHIPS)':
 'VSS91': CDS_PINID='VSS91';
NODE_NAME     J102 212
 '@T6G_MB_LIB.T6G(SCH_1):PAGE103_I142@PURE_QUANTA.SCONN288_DDR506112002KQ(CHIPS)':
 'VSS92': CDS_PINID='VSS92';
NODE_NAME     J102 214
 '@T6G_MB_LIB.T6G(SCH_1):PAGE103_I142@PURE_QUANTA.SCONN288_DDR506112002KQ(CHIPS)':
 'VSS93': CDS_PINID='VSS93';
NODE_NAME     J102 216
 '@T6G_MB_LIB.T6G(SCH_1):PAGE103_I142@PURE_QUANTA.SCONN288_DDR506112002KQ(CHIPS)':
 'VSS94': CDS_PINID='VSS94';
NODE_NAME     J102 219
 '@T6G_MB_LIB.T6G(SCH_1):PAGE103_I142@PURE_QUANTA.SCONN288_DDR506112002KQ(CHIPS)':
 'VSS95': CDS_PINID='VSS95';
NODE_NAME     J102 222
 '@T6G_MB_LIB.T6G(SCH_1):PAGE103_I142@PURE_QUANTA.SCONN288_DDR506112002KQ(CHIPS)':
 'VSS96': CDS_PINID='VSS96';
NODE_NAME     J102 224
 '@T6G_MB_LIB.T6G(SCH_1):PAGE103_I142@PURE_QUANTA.SCONN288_DDR506112002KQ(CHIPS)':
 'VSS97': CDS_PINID='VSS97';
NODE_NAME     J102 226
 '@T6G_MB_LIB.T6G(SCH_1):PAGE103_I142@PURE_QUANTA.SCONN288_DDR506112002KQ(CHIPS)':
 'VSS98': CDS_PINID='VSS98';
NODE_NAME     J102 228
 '@T6G_MB_LIB.T6G(SCH_1):PAGE103_I142@PURE_QUANTA.SCONN288_DDR506112002KQ(CHIPS)':
 'VSS99': CDS_PINID='VSS99';
NODE_NAME     J102 230
 '@T6G_MB_LIB.T6G(SCH_1):PAGE103_I142@PURE_QUANTA.SCONN288_DDR506112002KQ(CHIPS)':
 'VSS100': CDS_PINID='VSS100';
NODE_NAME     J102 233
 '@T6G_MB_LIB.T6G(SCH_1):PAGE103_I142@PURE_QUANTA.SCONN288_DDR506112002KQ(CHIPS)':
 'VSS101': CDS_PINID='VSS101';
NODE_NAME     J102 235
 '@T6G_MB_LIB.T6G(SCH_1):PAGE103_I142@PURE_QUANTA.SCONN288_DDR506112002KQ(CHIPS)':
 'VSS102': CDS_PINID='VSS102';
NODE_NAME     J102 237
 '@T6G_MB_LIB.T6G(SCH_1):PAGE103_I142@PURE_QUANTA.SCONN288_DDR506112002KQ(CHIPS)':
 'VSS103': CDS_PINID='VSS103';
NODE_NAME     J102 240
 '@T6G_MB_LIB.T6G(SCH_1):PAGE103_I142@PURE_QUANTA.SCONN288_DDR506112002KQ(CHIPS)':
 'VSS104': CDS_PINID='VSS104';
NODE_NAME     J102 242
 '@T6G_MB_LIB.T6G(SCH_1):PAGE103_I142@PURE_QUANTA.SCONN288_DDR506112002KQ(CHIPS)':
 'VSS105': CDS_PINID='VSS105';
NODE_NAME     J102 244
 '@T6G_MB_LIB.T6G(SCH_1):PAGE103_I142@PURE_QUANTA.SCONN288_DDR506112002KQ(CHIPS)':
 'VSS106': CDS_PINID='VSS106';
NODE_NAME     J102 246
 '@T6G_MB_LIB.T6G(SCH_1):PAGE103_I142@PURE_QUANTA.SCONN288_DDR506112002KQ(CHIPS)':
 'VSS107': CDS_PINID='VSS107';
NODE_NAME     J102 248
 '@T6G_MB_LIB.T6G(SCH_1):PAGE103_I142@PURE_QUANTA.SCONN288_DDR506112002KQ(CHIPS)':
 'VSS108': CDS_PINID='VSS108';
NODE_NAME     J102 251
 '@T6G_MB_LIB.T6G(SCH_1):PAGE103_I142@PURE_QUANTA.SCONN288_DDR506112002KQ(CHIPS)':
 'VSS109': CDS_PINID='VSS109';
NODE_NAME     J102 253
 '@T6G_MB_LIB.T6G(SCH_1):PAGE103_I142@PURE_QUANTA.SCONN288_DDR506112002KQ(CHIPS)':
 'VSS110': CDS_PINID='VSS110';
NODE_NAME     J102 255
 '@T6G_MB_LIB.T6G(SCH_1):PAGE103_I142@PURE_QUANTA.SCONN288_DDR506112002KQ(CHIPS)':
 'VSS111': CDS_PINID='VSS111';
NODE_NAME     J102 257
 '@T6G_MB_LIB.T6G(SCH_1):PAGE103_I142@PURE_QUANTA.SCONN288_DDR506112002KQ(CHIPS)':
 'VSS112': CDS_PINID='VSS112';
NODE_NAME     J102 259
 '@T6G_MB_LIB.T6G(SCH_1):PAGE103_I142@PURE_QUANTA.SCONN288_DDR506112002KQ(CHIPS)':
 'VSS113': CDS_PINID='VSS113';
NODE_NAME     J102 262
 '@T6G_MB_LIB.T6G(SCH_1):PAGE103_I142@PURE_QUANTA.SCONN288_DDR506112002KQ(CHIPS)':
 'VSS114': CDS_PINID='VSS114';
NODE_NAME     J102 264
 '@T6G_MB_LIB.T6G(SCH_1):PAGE103_I142@PURE_QUANTA.SCONN288_DDR506112002KQ(CHIPS)':
 'VSS115': CDS_PINID='VSS115';
NODE_NAME     J102 266
 '@T6G_MB_LIB.T6G(SCH_1):PAGE103_I142@PURE_QUANTA.SCONN288_DDR506112002KQ(CHIPS)':
 'VSS116': CDS_PINID='VSS116';
NODE_NAME     J102 268
 '@T6G_MB_LIB.T6G(SCH_1):PAGE103_I142@PURE_QUANTA.SCONN288_DDR506112002KQ(CHIPS)':
 'VSS117': CDS_PINID='VSS117';
NODE_NAME     J102 270
 '@T6G_MB_LIB.T6G(SCH_1):PAGE103_I142@PURE_QUANTA.SCONN288_DDR506112002KQ(CHIPS)':
 'VSS118': CDS_PINID='VSS118';
NODE_NAME     J102 273
 '@T6G_MB_LIB.T6G(SCH_1):PAGE103_I142@PURE_QUANTA.SCONN288_DDR506112002KQ(CHIPS)':
 'VSS119': CDS_PINID='VSS119';
NODE_NAME     J102 275
 '@T6G_MB_LIB.T6G(SCH_1):PAGE103_I142@PURE_QUANTA.SCONN288_DDR506112002KQ(CHIPS)':
 'VSS120': CDS_PINID='VSS120';
NODE_NAME     J102 277
 '@T6G_MB_LIB.T6G(SCH_1):PAGE103_I142@PURE_QUANTA.SCONN288_DDR506112002KQ(CHIPS)':
 'VSS121': CDS_PINID='VSS121';
NODE_NAME     J102 279
 '@T6G_MB_LIB.T6G(SCH_1):PAGE103_I142@PURE_QUANTA.SCONN288_DDR506112002KQ(CHIPS)':
 'VSS122': CDS_PINID='VSS122';
NODE_NAME     J102 281
 '@T6G_MB_LIB.T6G(SCH_1):PAGE103_I142@PURE_QUANTA.SCONN288_DDR506112002KQ(CHIPS)':
 'VSS123': CDS_PINID='VSS123';
NODE_NAME     J102 284
 '@T6G_MB_LIB.T6G(SCH_1):PAGE103_I142@PURE_QUANTA.SCONN288_DDR506112002KQ(CHIPS)':
 'VSS124': CDS_PINID='VSS124';
NODE_NAME     J102 286
 '@T6G_MB_LIB.T6G(SCH_1):PAGE103_I142@PURE_QUANTA.SCONN288_DDR506112002KQ(CHIPS)':
 'VSS125': CDS_PINID='VSS125';
NODE_NAME     J102 288
 '@T6G_MB_LIB.T6G(SCH_1):PAGE103_I142@PURE_QUANTA.SCONN288_DDR506112002KQ(CHIPS)':
 'VSS126': CDS_PINID='VSS126';
NODE_NAME     C160 2
 '@T6G_MB_LIB.T6G(SCH_1):PAGE103_I185@PURE_QUANTA.Q_CAP(CHIPS)':
 'B': CDS_PINID='B';
NODE_NAME     C530 2
 '@T6G_MB_LIB.T6G(SCH_1):PAGE103_I240@PURE_QUANTA.Q_CAP(CHIPS)':
 'B': CDS_PINID='B';
NODE_NAME     C531 2
 '@T6G_MB_LIB.T6G(SCH_1):PAGE103_I241@PURE_QUANTA.Q_CAP(CHIPS)':
 'B': CDS_PINID='B';
NODE_NAME     R774 2
 '@T6G_MB_LIB.T6G(SCH_1):PAGE104_I128@PURE_QUANTA.Q_RES(CHIPS)':
 'B': CDS_PINID='B';
NODE_NAME     J27 G1
 '@T6G_MB_LIB.T6G(SCH_1):PAGE104_I174@PURE_QUANTA.SCONN288_DDR506112002KQ(CHIPS)':
 'G1': CDS_PINID='G1';
NODE_NAME     J27 G2
 '@T6G_MB_LIB.T6G(SCH_1):PAGE104_I174@PURE_QUANTA.SCONN288_DDR506112002KQ(CHIPS)':
 'G2': CDS_PINID='G2';
NODE_NAME     J27 G3
 '@T6G_MB_LIB.T6G(SCH_1):PAGE104_I174@PURE_QUANTA.SCONN288_DDR506112002KQ(CHIPS)':
 'G3': CDS_PINID='G3';
NODE_NAME     J27 6
 '@T6G_MB_LIB.T6G(SCH_1):PAGE104_I174@PURE_QUANTA.SCONN288_DDR506112002KQ(CHIPS)':
 'VSS0': CDS_PINID='VSS0';
NODE_NAME     J27 8
 '@T6G_MB_LIB.T6G(SCH_1):PAGE104_I174@PURE_QUANTA.SCONN288_DDR506112002KQ(CHIPS)':
 'VSS1': CDS_PINID='VSS1';
NODE_NAME     J27 10
 '@T6G_MB_LIB.T6G(SCH_1):PAGE104_I174@PURE_QUANTA.SCONN288_DDR506112002KQ(CHIPS)':
 'VSS2': CDS_PINID='VSS2';
NODE_NAME     J27 13
 '@T6G_MB_LIB.T6G(SCH_1):PAGE104_I174@PURE_QUANTA.SCONN288_DDR506112002KQ(CHIPS)':
 'VSS3': CDS_PINID='VSS3';
NODE_NAME     J27 15
 '@T6G_MB_LIB.T6G(SCH_1):PAGE104_I174@PURE_QUANTA.SCONN288_DDR506112002KQ(CHIPS)':
 'VSS4': CDS_PINID='VSS4';
NODE_NAME     J27 17
 '@T6G_MB_LIB.T6G(SCH_1):PAGE104_I174@PURE_QUANTA.SCONN288_DDR506112002KQ(CHIPS)':
 'VSS5': CDS_PINID='VSS5';
NODE_NAME     J27 19
 '@T6G_MB_LIB.T6G(SCH_1):PAGE104_I174@PURE_QUANTA.SCONN288_DDR506112002KQ(CHIPS)':
 'VSS6': CDS_PINID='VSS6';
NODE_NAME     J27 21
 '@T6G_MB_LIB.T6G(SCH_1):PAGE104_I174@PURE_QUANTA.SCONN288_DDR506112002KQ(CHIPS)':
 'VSS7': CDS_PINID='VSS7';
NODE_NAME     J27 24
 '@T6G_MB_LIB.T6G(SCH_1):PAGE104_I174@PURE_QUANTA.SCONN288_DDR506112002KQ(CHIPS)':
 'VSS8': CDS_PINID='VSS8';
NODE_NAME     J27 26
 '@T6G_MB_LIB.T6G(SCH_1):PAGE104_I174@PURE_QUANTA.SCONN288_DDR506112002KQ(CHIPS)':
 'VSS9': CDS_PINID='VSS9';
NODE_NAME     J27 28
 '@T6G_MB_LIB.T6G(SCH_1):PAGE104_I174@PURE_QUANTA.SCONN288_DDR506112002KQ(CHIPS)':
 'VSS10': CDS_PINID='VSS10';
NODE_NAME     J27 30
 '@T6G_MB_LIB.T6G(SCH_1):PAGE104_I174@PURE_QUANTA.SCONN288_DDR506112002KQ(CHIPS)':
 'VSS11': CDS_PINID='VSS11';
NODE_NAME     J27 32
 '@T6G_MB_LIB.T6G(SCH_1):PAGE104_I174@PURE_QUANTA.SCONN288_DDR506112002KQ(CHIPS)':
 'VSS12': CDS_PINID='VSS12';
NODE_NAME     J27 35
 '@T6G_MB_LIB.T6G(SCH_1):PAGE104_I174@PURE_QUANTA.SCONN288_DDR506112002KQ(CHIPS)':
 'VSS13': CDS_PINID='VSS13';
NODE_NAME     J27 37
 '@T6G_MB_LIB.T6G(SCH_1):PAGE104_I174@PURE_QUANTA.SCONN288_DDR506112002KQ(CHIPS)':
 'VSS14': CDS_PINID='VSS14';
NODE_NAME     J27 39
 '@T6G_MB_LIB.T6G(SCH_1):PAGE104_I174@PURE_QUANTA.SCONN288_DDR506112002KQ(CHIPS)':
 'VSS15': CDS_PINID='VSS15';
NODE_NAME     J27 41
 '@T6G_MB_LIB.T6G(SCH_1):PAGE104_I174@PURE_QUANTA.SCONN288_DDR506112002KQ(CHIPS)':
 'VSS16': CDS_PINID='VSS16';
NODE_NAME     J27 43
 '@T6G_MB_LIB.T6G(SCH_1):PAGE104_I174@PURE_QUANTA.SCONN288_DDR506112002KQ(CHIPS)':
 'VSS17': CDS_PINID='VSS17';
NODE_NAME     J27 46
 '@T6G_MB_LIB.T6G(SCH_1):PAGE104_I174@PURE_QUANTA.SCONN288_DDR506112002KQ(CHIPS)':
 'VSS18': CDS_PINID='VSS18';
NODE_NAME     J27 48
 '@T6G_MB_LIB.T6G(SCH_1):PAGE104_I174@PURE_QUANTA.SCONN288_DDR506112002KQ(CHIPS)':
 'VSS19': CDS_PINID='VSS19';
NODE_NAME     J27 50
 '@T6G_MB_LIB.T6G(SCH_1):PAGE104_I174@PURE_QUANTA.SCONN288_DDR506112002KQ(CHIPS)':
 'VSS20': CDS_PINID='VSS20';
NODE_NAME     J27 52
 '@T6G_MB_LIB.T6G(SCH_1):PAGE104_I174@PURE_QUANTA.SCONN288_DDR506112002KQ(CHIPS)':
 'VSS21': CDS_PINID='VSS21';
NODE_NAME     J27 54
 '@T6G_MB_LIB.T6G(SCH_1):PAGE104_I174@PURE_QUANTA.SCONN288_DDR506112002KQ(CHIPS)':
 'VSS22': CDS_PINID='VSS22';
NODE_NAME     J27 57
 '@T6G_MB_LIB.T6G(SCH_1):PAGE104_I174@PURE_QUANTA.SCONN288_DDR506112002KQ(CHIPS)':
 'VSS23': CDS_PINID='VSS23';
NODE_NAME     J27 59
 '@T6G_MB_LIB.T6G(SCH_1):PAGE104_I174@PURE_QUANTA.SCONN288_DDR506112002KQ(CHIPS)':
 'VSS24': CDS_PINID='VSS24';
NODE_NAME     J27 61
 '@T6G_MB_LIB.T6G(SCH_1):PAGE104_I174@PURE_QUANTA.SCONN288_DDR506112002KQ(CHIPS)':
 'VSS25': CDS_PINID='VSS25';
NODE_NAME     J27 63
 '@T6G_MB_LIB.T6G(SCH_1):PAGE104_I174@PURE_QUANTA.SCONN288_DDR506112002KQ(CHIPS)':
 'VSS26': CDS_PINID='VSS26';
NODE_NAME     J27 65
 '@T6G_MB_LIB.T6G(SCH_1):PAGE104_I174@PURE_QUANTA.SCONN288_DDR506112002KQ(CHIPS)':
 'VSS27': CDS_PINID='VSS27';
NODE_NAME     J27 67
 '@T6G_MB_LIB.T6G(SCH_1):PAGE104_I174@PURE_QUANTA.SCONN288_DDR506112002KQ(CHIPS)':
 'VSS28': CDS_PINID='VSS28';
NODE_NAME     J27 69
 '@T6G_MB_LIB.T6G(SCH_1):PAGE104_I174@PURE_QUANTA.SCONN288_DDR506112002KQ(CHIPS)':
 'VSS29': CDS_PINID='VSS29';
NODE_NAME     J27 71
 '@T6G_MB_LIB.T6G(SCH_1):PAGE104_I174@PURE_QUANTA.SCONN288_DDR506112002KQ(CHIPS)':
 'VSS30': CDS_PINID='VSS30';
NODE_NAME     J27 73
 '@T6G_MB_LIB.T6G(SCH_1):PAGE104_I174@PURE_QUANTA.SCONN288_DDR506112002KQ(CHIPS)':
 'VSS31': CDS_PINID='VSS31';
NODE_NAME     J27 75
 '@T6G_MB_LIB.T6G(SCH_1):PAGE104_I174@PURE_QUANTA.SCONN288_DDR506112002KQ(CHIPS)':
 'VSS32': CDS_PINID='VSS32';
NODE_NAME     J27 77
 '@T6G_MB_LIB.T6G(SCH_1):PAGE104_I174@PURE_QUANTA.SCONN288_DDR506112002KQ(CHIPS)':
 'VSS33': CDS_PINID='VSS33';
NODE_NAME     J27 79
 '@T6G_MB_LIB.T6G(SCH_1):PAGE104_I174@PURE_QUANTA.SCONN288_DDR506112002KQ(CHIPS)':
 'VSS34': CDS_PINID='VSS34';
NODE_NAME     J27 81
 '@T6G_MB_LIB.T6G(SCH_1):PAGE104_I174@PURE_QUANTA.SCONN288_DDR506112002KQ(CHIPS)':
 'VSS35': CDS_PINID='VSS35';
NODE_NAME     J27 83
 '@T6G_MB_LIB.T6G(SCH_1):PAGE104_I174@PURE_QUANTA.SCONN288_DDR506112002KQ(CHIPS)':
 'VSS36': CDS_PINID='VSS36';
NODE_NAME     J27 85
 '@T6G_MB_LIB.T6G(SCH_1):PAGE104_I174@PURE_QUANTA.SCONN288_DDR506112002KQ(CHIPS)':
 'VSS37': CDS_PINID='VSS37';
NODE_NAME     J27 88
 '@T6G_MB_LIB.T6G(SCH_1):PAGE104_I174@PURE_QUANTA.SCONN288_DDR506112002KQ(CHIPS)':
 'VSS38': CDS_PINID='VSS38';
NODE_NAME     J27 90
 '@T6G_MB_LIB.T6G(SCH_1):PAGE104_I174@PURE_QUANTA.SCONN288_DDR506112002KQ(CHIPS)':
 'VSS39': CDS_PINID='VSS39';
NODE_NAME     J27 92
 '@T6G_MB_LIB.T6G(SCH_1):PAGE104_I174@PURE_QUANTA.SCONN288_DDR506112002KQ(CHIPS)':
 'VSS40': CDS_PINID='VSS40';
NODE_NAME     J27 95
 '@T6G_MB_LIB.T6G(SCH_1):PAGE104_I174@PURE_QUANTA.SCONN288_DDR506112002KQ(CHIPS)':
 'VSS41': CDS_PINID='VSS41';
NODE_NAME     J27 97
 '@T6G_MB_LIB.T6G(SCH_1):PAGE104_I174@PURE_QUANTA.SCONN288_DDR506112002KQ(CHIPS)':
 'VSS42': CDS_PINID='VSS42';
NODE_NAME     J27 99
 '@T6G_MB_LIB.T6G(SCH_1):PAGE104_I174@PURE_QUANTA.SCONN288_DDR506112002KQ(CHIPS)':
 'VSS43': CDS_PINID='VSS43';
NODE_NAME     J27 101
 '@T6G_MB_LIB.T6G(SCH_1):PAGE104_I174@PURE_QUANTA.SCONN288_DDR506112002KQ(CHIPS)':
 'VSS44': CDS_PINID='VSS44';
NODE_NAME     J27 103
 '@T6G_MB_LIB.T6G(SCH_1):PAGE104_I174@PURE_QUANTA.SCONN288_DDR506112002KQ(CHIPS)':
 'VSS45': CDS_PINID='VSS45';
NODE_NAME     J27 106
 '@T6G_MB_LIB.T6G(SCH_1):PAGE104_I174@PURE_QUANTA.SCONN288_DDR506112002KQ(CHIPS)':
 'VSS46': CDS_PINID='VSS46';
NODE_NAME     J27 108
 '@T6G_MB_LIB.T6G(SCH_1):PAGE104_I174@PURE_QUANTA.SCONN288_DDR506112002KQ(CHIPS)':
 'VSS47': CDS_PINID='VSS47';
NODE_NAME     J27 110
 '@T6G_MB_LIB.T6G(SCH_1):PAGE104_I174@PURE_QUANTA.SCONN288_DDR506112002KQ(CHIPS)':
 'VSS48': CDS_PINID='VSS48';
NODE_NAME     J27 112
 '@T6G_MB_LIB.T6G(SCH_1):PAGE104_I174@PURE_QUANTA.SCONN288_DDR506112002KQ(CHIPS)':
 'VSS49': CDS_PINID='VSS49';
NODE_NAME     J27 114
 '@T6G_MB_LIB.T6G(SCH_1):PAGE104_I174@PURE_QUANTA.SCONN288_DDR506112002KQ(CHIPS)':
 'VSS50': CDS_PINID='VSS50';
NODE_NAME     J27 117
 '@T6G_MB_LIB.T6G(SCH_1):PAGE104_I174@PURE_QUANTA.SCONN288_DDR506112002KQ(CHIPS)':
 'VSS51': CDS_PINID='VSS51';
NODE_NAME     J27 119
 '@T6G_MB_LIB.T6G(SCH_1):PAGE104_I174@PURE_QUANTA.SCONN288_DDR506112002KQ(CHIPS)':
 'VSS52': CDS_PINID='VSS52';
NODE_NAME     J27 121
 '@T6G_MB_LIB.T6G(SCH_1):PAGE104_I174@PURE_QUANTA.SCONN288_DDR506112002KQ(CHIPS)':
 'VSS53': CDS_PINID='VSS53';
NODE_NAME     J27 123
 '@T6G_MB_LIB.T6G(SCH_1):PAGE104_I174@PURE_QUANTA.SCONN288_DDR506112002KQ(CHIPS)':
 'VSS54': CDS_PINID='VSS54';
NODE_NAME     J27 125
 '@T6G_MB_LIB.T6G(SCH_1):PAGE104_I174@PURE_QUANTA.SCONN288_DDR506112002KQ(CHIPS)':
 'VSS55': CDS_PINID='VSS55';
NODE_NAME     J27 128
 '@T6G_MB_LIB.T6G(SCH_1):PAGE104_I174@PURE_QUANTA.SCONN288_DDR506112002KQ(CHIPS)':
 'VSS56': CDS_PINID='VSS56';
NODE_NAME     J27 130
 '@T6G_MB_LIB.T6G(SCH_1):PAGE104_I174@PURE_QUANTA.SCONN288_DDR506112002KQ(CHIPS)':
 'VSS57': CDS_PINID='VSS57';
NODE_NAME     J27 132
 '@T6G_MB_LIB.T6G(SCH_1):PAGE104_I174@PURE_QUANTA.SCONN288_DDR506112002KQ(CHIPS)':
 'VSS58': CDS_PINID='VSS58';
NODE_NAME     J27 134
 '@T6G_MB_LIB.T6G(SCH_1):PAGE104_I174@PURE_QUANTA.SCONN288_DDR506112002KQ(CHIPS)':
 'VSS59': CDS_PINID='VSS59';
NODE_NAME     J27 136
 '@T6G_MB_LIB.T6G(SCH_1):PAGE104_I174@PURE_QUANTA.SCONN288_DDR506112002KQ(CHIPS)':
 'VSS60': CDS_PINID='VSS60';
NODE_NAME     J27 139
 '@T6G_MB_LIB.T6G(SCH_1):PAGE104_I174@PURE_QUANTA.SCONN288_DDR506112002KQ(CHIPS)':
 'VSS61': CDS_PINID='VSS61';
NODE_NAME     J27 141
 '@T6G_MB_LIB.T6G(SCH_1):PAGE104_I174@PURE_QUANTA.SCONN288_DDR506112002KQ(CHIPS)':
 'VSS62': CDS_PINID='VSS62';
NODE_NAME     J27 143
 '@T6G_MB_LIB.T6G(SCH_1):PAGE104_I174@PURE_QUANTA.SCONN288_DDR506112002KQ(CHIPS)':
 'VSS63': CDS_PINID='VSS63';
NODE_NAME     J27 151
 '@T6G_MB_LIB.T6G(SCH_1):PAGE104_I174@PURE_QUANTA.SCONN288_DDR506112002KQ(CHIPS)':
 'VSS64': CDS_PINID='VSS64';
NODE_NAME     J27 153
 '@T6G_MB_LIB.T6G(SCH_1):PAGE104_I174@PURE_QUANTA.SCONN288_DDR506112002KQ(CHIPS)':
 'VSS65': CDS_PINID='VSS65';
NODE_NAME     J27 155
 '@T6G_MB_LIB.T6G(SCH_1):PAGE104_I174@PURE_QUANTA.SCONN288_DDR506112002KQ(CHIPS)':
 'VSS66': CDS_PINID='VSS66';
NODE_NAME     J27 158
 '@T6G_MB_LIB.T6G(SCH_1):PAGE104_I174@PURE_QUANTA.SCONN288_DDR506112002KQ(CHIPS)':
 'VSS67': CDS_PINID='VSS67';
NODE_NAME     J27 160
 '@T6G_MB_LIB.T6G(SCH_1):PAGE104_I174@PURE_QUANTA.SCONN288_DDR506112002KQ(CHIPS)':
 'VSS68': CDS_PINID='VSS68';
NODE_NAME     J27 162
 '@T6G_MB_LIB.T6G(SCH_1):PAGE104_I174@PURE_QUANTA.SCONN288_DDR506112002KQ(CHIPS)':
 'VSS69': CDS_PINID='VSS69';
NODE_NAME     J27 164
 '@T6G_MB_LIB.T6G(SCH_1):PAGE104_I174@PURE_QUANTA.SCONN288_DDR506112002KQ(CHIPS)':
 'VSS70': CDS_PINID='VSS70';
NODE_NAME     J27 166
 '@T6G_MB_LIB.T6G(SCH_1):PAGE104_I174@PURE_QUANTA.SCONN288_DDR506112002KQ(CHIPS)':
 'VSS71': CDS_PINID='VSS71';
NODE_NAME     J27 169
 '@T6G_MB_LIB.T6G(SCH_1):PAGE104_I174@PURE_QUANTA.SCONN288_DDR506112002KQ(CHIPS)':
 'VSS72': CDS_PINID='VSS72';
NODE_NAME     J27 171
 '@T6G_MB_LIB.T6G(SCH_1):PAGE104_I174@PURE_QUANTA.SCONN288_DDR506112002KQ(CHIPS)':
 'VSS73': CDS_PINID='VSS73';
NODE_NAME     J27 173
 '@T6G_MB_LIB.T6G(SCH_1):PAGE104_I174@PURE_QUANTA.SCONN288_DDR506112002KQ(CHIPS)':
 'VSS74': CDS_PINID='VSS74';
NODE_NAME     J27 175
 '@T6G_MB_LIB.T6G(SCH_1):PAGE104_I174@PURE_QUANTA.SCONN288_DDR506112002KQ(CHIPS)':
 'VSS75': CDS_PINID='VSS75';
NODE_NAME     J27 177
 '@T6G_MB_LIB.T6G(SCH_1):PAGE104_I174@PURE_QUANTA.SCONN288_DDR506112002KQ(CHIPS)':
 'VSS76': CDS_PINID='VSS76';
NODE_NAME     J27 180
 '@T6G_MB_LIB.T6G(SCH_1):PAGE104_I174@PURE_QUANTA.SCONN288_DDR506112002KQ(CHIPS)':
 'VSS77': CDS_PINID='VSS77';
NODE_NAME     J27 182
 '@T6G_MB_LIB.T6G(SCH_1):PAGE104_I174@PURE_QUANTA.SCONN288_DDR506112002KQ(CHIPS)':
 'VSS78': CDS_PINID='VSS78';
NODE_NAME     J27 184
 '@T6G_MB_LIB.T6G(SCH_1):PAGE104_I174@PURE_QUANTA.SCONN288_DDR506112002KQ(CHIPS)':
 'VSS79': CDS_PINID='VSS79';
NODE_NAME     J27 186
 '@T6G_MB_LIB.T6G(SCH_1):PAGE104_I174@PURE_QUANTA.SCONN288_DDR506112002KQ(CHIPS)':
 'VSS80': CDS_PINID='VSS80';
NODE_NAME     J27 188
 '@T6G_MB_LIB.T6G(SCH_1):PAGE104_I174@PURE_QUANTA.SCONN288_DDR506112002KQ(CHIPS)':
 'VSS81': CDS_PINID='VSS81';
NODE_NAME     J27 191
 '@T6G_MB_LIB.T6G(SCH_1):PAGE104_I174@PURE_QUANTA.SCONN288_DDR506112002KQ(CHIPS)':
 'VSS82': CDS_PINID='VSS82';
NODE_NAME     J27 193
 '@T6G_MB_LIB.T6G(SCH_1):PAGE104_I174@PURE_QUANTA.SCONN288_DDR506112002KQ(CHIPS)':
 'VSS83': CDS_PINID='VSS83';
NODE_NAME     J27 195
 '@T6G_MB_LIB.T6G(SCH_1):PAGE104_I174@PURE_QUANTA.SCONN288_DDR506112002KQ(CHIPS)':
 'VSS84': CDS_PINID='VSS84';
NODE_NAME     J27 197
 '@T6G_MB_LIB.T6G(SCH_1):PAGE104_I174@PURE_QUANTA.SCONN288_DDR506112002KQ(CHIPS)':
 'VSS85': CDS_PINID='VSS85';
NODE_NAME     J27 199
 '@T6G_MB_LIB.T6G(SCH_1):PAGE104_I174@PURE_QUANTA.SCONN288_DDR506112002KQ(CHIPS)':
 'VSS86': CDS_PINID='VSS86';
NODE_NAME     J27 202
 '@T6G_MB_LIB.T6G(SCH_1):PAGE104_I174@PURE_QUANTA.SCONN288_DDR506112002KQ(CHIPS)':
 'VSS87': CDS_PINID='VSS87';
NODE_NAME     J27 204
 '@T6G_MB_LIB.T6G(SCH_1):PAGE104_I174@PURE_QUANTA.SCONN288_DDR506112002KQ(CHIPS)':
 'VSS88': CDS_PINID='VSS88';
NODE_NAME     J27 206
 '@T6G_MB_LIB.T6G(SCH_1):PAGE104_I174@PURE_QUANTA.SCONN288_DDR506112002KQ(CHIPS)':
 'VSS89': CDS_PINID='VSS89';
NODE_NAME     J27 208
 '@T6G_MB_LIB.T6G(SCH_1):PAGE104_I174@PURE_QUANTA.SCONN288_DDR506112002KQ(CHIPS)':
 'VSS90': CDS_PINID='VSS90';
NODE_NAME     J27 210
 '@T6G_MB_LIB.T6G(SCH_1):PAGE104_I174@PURE_QUANTA.SCONN288_DDR506112002KQ(CHIPS)':
 'VSS91': CDS_PINID='VSS91';
NODE_NAME     J27 212
 '@T6G_MB_LIB.T6G(SCH_1):PAGE104_I174@PURE_QUANTA.SCONN288_DDR506112002KQ(CHIPS)':
 'VSS92': CDS_PINID='VSS92';
NODE_NAME     J27 214
 '@T6G_MB_LIB.T6G(SCH_1):PAGE104_I174@PURE_QUANTA.SCONN288_DDR506112002KQ(CHIPS)':
 'VSS93': CDS_PINID='VSS93';
NODE_NAME     J27 216
 '@T6G_MB_LIB.T6G(SCH_1):PAGE104_I174@PURE_QUANTA.SCONN288_DDR506112002KQ(CHIPS)':
 'VSS94': CDS_PINID='VSS94';
NODE_NAME     J27 219
 '@T6G_MB_LIB.T6G(SCH_1):PAGE104_I174@PURE_QUANTA.SCONN288_DDR506112002KQ(CHIPS)':
 'VSS95': CDS_PINID='VSS95';
NODE_NAME     J27 222
 '@T6G_MB_LIB.T6G(SCH_1):PAGE104_I174@PURE_QUANTA.SCONN288_DDR506112002KQ(CHIPS)':
 'VSS96': CDS_PINID='VSS96';
NODE_NAME     J27 224
 '@T6G_MB_LIB.T6G(SCH_1):PAGE104_I174@PURE_QUANTA.SCONN288_DDR506112002KQ(CHIPS)':
 'VSS97': CDS_PINID='VSS97';
NODE_NAME     J27 226
 '@T6G_MB_LIB.T6G(SCH_1):PAGE104_I174@PURE_QUANTA.SCONN288_DDR506112002KQ(CHIPS)':
 'VSS98': CDS_PINID='VSS98';
NODE_NAME     J27 228
 '@T6G_MB_LIB.T6G(SCH_1):PAGE104_I174@PURE_QUANTA.SCONN288_DDR506112002KQ(CHIPS)':
 'VSS99': CDS_PINID='VSS99';
NODE_NAME     J27 230
 '@T6G_MB_LIB.T6G(SCH_1):PAGE104_I174@PURE_QUANTA.SCONN288_DDR506112002KQ(CHIPS)':
 'VSS100': CDS_PINID='VSS100';
NODE_NAME     J27 233
 '@T6G_MB_LIB.T6G(SCH_1):PAGE104_I174@PURE_QUANTA.SCONN288_DDR506112002KQ(CHIPS)':
 'VSS101': CDS_PINID='VSS101';
NODE_NAME     J27 235
 '@T6G_MB_LIB.T6G(SCH_1):PAGE104_I174@PURE_QUANTA.SCONN288_DDR506112002KQ(CHIPS)':
 'VSS102': CDS_PINID='VSS102';
NODE_NAME     J27 237
 '@T6G_MB_LIB.T6G(SCH_1):PAGE104_I174@PURE_QUANTA.SCONN288_DDR506112002KQ(CHIPS)':
 'VSS103': CDS_PINID='VSS103';
NODE_NAME     J27 240
 '@T6G_MB_LIB.T6G(SCH_1):PAGE104_I174@PURE_QUANTA.SCONN288_DDR506112002KQ(CHIPS)':
 'VSS104': CDS_PINID='VSS104';
NODE_NAME     J27 242
 '@T6G_MB_LIB.T6G(SCH_1):PAGE104_I174@PURE_QUANTA.SCONN288_DDR506112002KQ(CHIPS)':
 'VSS105': CDS_PINID='VSS105';
NODE_NAME     J27 244
 '@T6G_MB_LIB.T6G(SCH_1):PAGE104_I174@PURE_QUANTA.SCONN288_DDR506112002KQ(CHIPS)':
 'VSS106': CDS_PINID='VSS106';
NODE_NAME     J27 246
 '@T6G_MB_LIB.T6G(SCH_1):PAGE104_I174@PURE_QUANTA.SCONN288_DDR506112002KQ(CHIPS)':
 'VSS107': CDS_PINID='VSS107';
NODE_NAME     J27 248
 '@T6G_MB_LIB.T6G(SCH_1):PAGE104_I174@PURE_QUANTA.SCONN288_DDR506112002KQ(CHIPS)':
 'VSS108': CDS_PINID='VSS108';
NODE_NAME     J27 251
 '@T6G_MB_LIB.T6G(SCH_1):PAGE104_I174@PURE_QUANTA.SCONN288_DDR506112002KQ(CHIPS)':
 'VSS109': CDS_PINID='VSS109';
NODE_NAME     J27 253
 '@T6G_MB_LIB.T6G(SCH_1):PAGE104_I174@PURE_QUANTA.SCONN288_DDR506112002KQ(CHIPS)':
 'VSS110': CDS_PINID='VSS110';
NODE_NAME     J27 255
 '@T6G_MB_LIB.T6G(SCH_1):PAGE104_I174@PURE_QUANTA.SCONN288_DDR506112002KQ(CHIPS)':
 'VSS111': CDS_PINID='VSS111';
NODE_NAME     J27 257
 '@T6G_MB_LIB.T6G(SCH_1):PAGE104_I174@PURE_QUANTA.SCONN288_DDR506112002KQ(CHIPS)':
 'VSS112': CDS_PINID='VSS112';
NODE_NAME     J27 259
 '@T6G_MB_LIB.T6G(SCH_1):PAGE104_I174@PURE_QUANTA.SCONN288_DDR506112002KQ(CHIPS)':
 'VSS113': CDS_PINID='VSS113';
NODE_NAME     J27 262
 '@T6G_MB_LIB.T6G(SCH_1):PAGE104_I174@PURE_QUANTA.SCONN288_DDR506112002KQ(CHIPS)':
 'VSS114': CDS_PINID='VSS114';
NODE_NAME     J27 264
 '@T6G_MB_LIB.T6G(SCH_1):PAGE104_I174@PURE_QUANTA.SCONN288_DDR506112002KQ(CHIPS)':
 'VSS115': CDS_PINID='VSS115';
NODE_NAME     J27 266
 '@T6G_MB_LIB.T6G(SCH_1):PAGE104_I174@PURE_QUANTA.SCONN288_DDR506112002KQ(CHIPS)':
 'VSS116': CDS_PINID='VSS116';
NODE_NAME     J27 268
 '@T6G_MB_LIB.T6G(SCH_1):PAGE104_I174@PURE_QUANTA.SCONN288_DDR506112002KQ(CHIPS)':
 'VSS117': CDS_PINID='VSS117';
NODE_NAME     J27 270
 '@T6G_MB_LIB.T6G(SCH_1):PAGE104_I174@PURE_QUANTA.SCONN288_DDR506112002KQ(CHIPS)':
 'VSS118': CDS_PINID='VSS118';
NODE_NAME     J27 273
 '@T6G_MB_LIB.T6G(SCH_1):PAGE104_I174@PURE_QUANTA.SCONN288_DDR506112002KQ(CHIPS)':
 'VSS119': CDS_PINID='VSS119';
NODE_NAME     J27 275
 '@T6G_MB_LIB.T6G(SCH_1):PAGE104_I174@PURE_QUANTA.SCONN288_DDR506112002KQ(CHIPS)':
 'VSS120': CDS_PINID='VSS120';
NODE_NAME     J27 277
 '@T6G_MB_LIB.T6G(SCH_1):PAGE104_I174@PURE_QUANTA.SCONN288_DDR506112002KQ(CHIPS)':
 'VSS121': CDS_PINID='VSS121';
NODE_NAME     J27 279
 '@T6G_MB_LIB.T6G(SCH_1):PAGE104_I174@PURE_QUANTA.SCONN288_DDR506112002KQ(CHIPS)':
 'VSS122': CDS_PINID='VSS122';
NODE_NAME     J27 281
 '@T6G_MB_LIB.T6G(SCH_1):PAGE104_I174@PURE_QUANTA.SCONN288_DDR506112002KQ(CHIPS)':
 'VSS123': CDS_PINID='VSS123';
NODE_NAME     J27 284
 '@T6G_MB_LIB.T6G(SCH_1):PAGE104_I174@PURE_QUANTA.SCONN288_DDR506112002KQ(CHIPS)':
 'VSS124': CDS_PINID='VSS124';
NODE_NAME     J27 286
 '@T6G_MB_LIB.T6G(SCH_1):PAGE104_I174@PURE_QUANTA.SCONN288_DDR506112002KQ(CHIPS)':
 'VSS125': CDS_PINID='VSS125';
NODE_NAME     J27 288
 '@T6G_MB_LIB.T6G(SCH_1):PAGE104_I174@PURE_QUANTA.SCONN288_DDR506112002KQ(CHIPS)':
 'VSS126': CDS_PINID='VSS126';
NODE_NAME     C164 2
 '@T6G_MB_LIB.T6G(SCH_1):PAGE104_I185@PURE_QUANTA.Q_CAP(CHIPS)':
 'B': CDS_PINID='B';
NODE_NAME     C532 2
 '@T6G_MB_LIB.T6G(SCH_1):PAGE104_I240@PURE_QUANTA.Q_CAP(CHIPS)':
 'B': CDS_PINID='B';
NODE_NAME     C533 2
 '@T6G_MB_LIB.T6G(SCH_1):PAGE104_I241@PURE_QUANTA.Q_CAP(CHIPS)':
 'B': CDS_PINID='B';
NODE_NAME     R775 2
 '@T6G_MB_LIB.T6G(SCH_1):PAGE105_I128@PURE_QUANTA.Q_RES(CHIPS)':
 'B': CDS_PINID='B';
NODE_NAME     J100 G1
 '@T6G_MB_LIB.T6G(SCH_1):PAGE105_I176@PURE_QUANTA.SCONN288_DDR506112002KQ(CHIPS)':
 'G1': CDS_PINID='G1';
NODE_NAME     J100 G2
 '@T6G_MB_LIB.T6G(SCH_1):PAGE105_I176@PURE_QUANTA.SCONN288_DDR506112002KQ(CHIPS)':
 'G2': CDS_PINID='G2';
NODE_NAME     J100 G3
 '@T6G_MB_LIB.T6G(SCH_1):PAGE105_I176@PURE_QUANTA.SCONN288_DDR506112002KQ(CHIPS)':
 'G3': CDS_PINID='G3';
NODE_NAME     J100 6
 '@T6G_MB_LIB.T6G(SCH_1):PAGE105_I176@PURE_QUANTA.SCONN288_DDR506112002KQ(CHIPS)':
 'VSS0': CDS_PINID='VSS0';
NODE_NAME     J100 8
 '@T6G_MB_LIB.T6G(SCH_1):PAGE105_I176@PURE_QUANTA.SCONN288_DDR506112002KQ(CHIPS)':
 'VSS1': CDS_PINID='VSS1';
NODE_NAME     J100 10
 '@T6G_MB_LIB.T6G(SCH_1):PAGE105_I176@PURE_QUANTA.SCONN288_DDR506112002KQ(CHIPS)':
 'VSS2': CDS_PINID='VSS2';
NODE_NAME     J100 13
 '@T6G_MB_LIB.T6G(SCH_1):PAGE105_I176@PURE_QUANTA.SCONN288_DDR506112002KQ(CHIPS)':
 'VSS3': CDS_PINID='VSS3';
NODE_NAME     J100 15
 '@T6G_MB_LIB.T6G(SCH_1):PAGE105_I176@PURE_QUANTA.SCONN288_DDR506112002KQ(CHIPS)':
 'VSS4': CDS_PINID='VSS4';
NODE_NAME     J100 17
 '@T6G_MB_LIB.T6G(SCH_1):PAGE105_I176@PURE_QUANTA.SCONN288_DDR506112002KQ(CHIPS)':
 'VSS5': CDS_PINID='VSS5';
NODE_NAME     J100 19
 '@T6G_MB_LIB.T6G(SCH_1):PAGE105_I176@PURE_QUANTA.SCONN288_DDR506112002KQ(CHIPS)':
 'VSS6': CDS_PINID='VSS6';
NODE_NAME     J100 21
 '@T6G_MB_LIB.T6G(SCH_1):PAGE105_I176@PURE_QUANTA.SCONN288_DDR506112002KQ(CHIPS)':
 'VSS7': CDS_PINID='VSS7';
NODE_NAME     J100 24
 '@T6G_MB_LIB.T6G(SCH_1):PAGE105_I176@PURE_QUANTA.SCONN288_DDR506112002KQ(CHIPS)':
 'VSS8': CDS_PINID='VSS8';
NODE_NAME     J100 26
 '@T6G_MB_LIB.T6G(SCH_1):PAGE105_I176@PURE_QUANTA.SCONN288_DDR506112002KQ(CHIPS)':
 'VSS9': CDS_PINID='VSS9';
NODE_NAME     J100 28
 '@T6G_MB_LIB.T6G(SCH_1):PAGE105_I176@PURE_QUANTA.SCONN288_DDR506112002KQ(CHIPS)':
 'VSS10': CDS_PINID='VSS10';
NODE_NAME     J100 30
 '@T6G_MB_LIB.T6G(SCH_1):PAGE105_I176@PURE_QUANTA.SCONN288_DDR506112002KQ(CHIPS)':
 'VSS11': CDS_PINID='VSS11';
NODE_NAME     J100 32
 '@T6G_MB_LIB.T6G(SCH_1):PAGE105_I176@PURE_QUANTA.SCONN288_DDR506112002KQ(CHIPS)':
 'VSS12': CDS_PINID='VSS12';
NODE_NAME     J100 35
 '@T6G_MB_LIB.T6G(SCH_1):PAGE105_I176@PURE_QUANTA.SCONN288_DDR506112002KQ(CHIPS)':
 'VSS13': CDS_PINID='VSS13';
NODE_NAME     J100 37
 '@T6G_MB_LIB.T6G(SCH_1):PAGE105_I176@PURE_QUANTA.SCONN288_DDR506112002KQ(CHIPS)':
 'VSS14': CDS_PINID='VSS14';
NODE_NAME     J100 39
 '@T6G_MB_LIB.T6G(SCH_1):PAGE105_I176@PURE_QUANTA.SCONN288_DDR506112002KQ(CHIPS)':
 'VSS15': CDS_PINID='VSS15';
NODE_NAME     J100 41
 '@T6G_MB_LIB.T6G(SCH_1):PAGE105_I176@PURE_QUANTA.SCONN288_DDR506112002KQ(CHIPS)':
 'VSS16': CDS_PINID='VSS16';
NODE_NAME     J100 43
 '@T6G_MB_LIB.T6G(SCH_1):PAGE105_I176@PURE_QUANTA.SCONN288_DDR506112002KQ(CHIPS)':
 'VSS17': CDS_PINID='VSS17';
NODE_NAME     J100 46
 '@T6G_MB_LIB.T6G(SCH_1):PAGE105_I176@PURE_QUANTA.SCONN288_DDR506112002KQ(CHIPS)':
 'VSS18': CDS_PINID='VSS18';
NODE_NAME     J100 48
 '@T6G_MB_LIB.T6G(SCH_1):PAGE105_I176@PURE_QUANTA.SCONN288_DDR506112002KQ(CHIPS)':
 'VSS19': CDS_PINID='VSS19';
NODE_NAME     J100 50
 '@T6G_MB_LIB.T6G(SCH_1):PAGE105_I176@PURE_QUANTA.SCONN288_DDR506112002KQ(CHIPS)':
 'VSS20': CDS_PINID='VSS20';
NODE_NAME     J100 52
 '@T6G_MB_LIB.T6G(SCH_1):PAGE105_I176@PURE_QUANTA.SCONN288_DDR506112002KQ(CHIPS)':
 'VSS21': CDS_PINID='VSS21';
NODE_NAME     J100 54
 '@T6G_MB_LIB.T6G(SCH_1):PAGE105_I176@PURE_QUANTA.SCONN288_DDR506112002KQ(CHIPS)':
 'VSS22': CDS_PINID='VSS22';
NODE_NAME     J100 57
 '@T6G_MB_LIB.T6G(SCH_1):PAGE105_I176@PURE_QUANTA.SCONN288_DDR506112002KQ(CHIPS)':
 'VSS23': CDS_PINID='VSS23';
NODE_NAME     J100 59
 '@T6G_MB_LIB.T6G(SCH_1):PAGE105_I176@PURE_QUANTA.SCONN288_DDR506112002KQ(CHIPS)':
 'VSS24': CDS_PINID='VSS24';
NODE_NAME     J100 61
 '@T6G_MB_LIB.T6G(SCH_1):PAGE105_I176@PURE_QUANTA.SCONN288_DDR506112002KQ(CHIPS)':
 'VSS25': CDS_PINID='VSS25';
NODE_NAME     J100 63
 '@T6G_MB_LIB.T6G(SCH_1):PAGE105_I176@PURE_QUANTA.SCONN288_DDR506112002KQ(CHIPS)':
 'VSS26': CDS_PINID='VSS26';
NODE_NAME     J100 65
 '@T6G_MB_LIB.T6G(SCH_1):PAGE105_I176@PURE_QUANTA.SCONN288_DDR506112002KQ(CHIPS)':
 'VSS27': CDS_PINID='VSS27';
NODE_NAME     J100 67
 '@T6G_MB_LIB.T6G(SCH_1):PAGE105_I176@PURE_QUANTA.SCONN288_DDR506112002KQ(CHIPS)':
 'VSS28': CDS_PINID='VSS28';
NODE_NAME     J100 69
 '@T6G_MB_LIB.T6G(SCH_1):PAGE105_I176@PURE_QUANTA.SCONN288_DDR506112002KQ(CHIPS)':
 'VSS29': CDS_PINID='VSS29';
NODE_NAME     J100 71
 '@T6G_MB_LIB.T6G(SCH_1):PAGE105_I176@PURE_QUANTA.SCONN288_DDR506112002KQ(CHIPS)':
 'VSS30': CDS_PINID='VSS30';
NODE_NAME     J100 73
 '@T6G_MB_LIB.T6G(SCH_1):PAGE105_I176@PURE_QUANTA.SCONN288_DDR506112002KQ(CHIPS)':
 'VSS31': CDS_PINID='VSS31';
NODE_NAME     J100 75
 '@T6G_MB_LIB.T6G(SCH_1):PAGE105_I176@PURE_QUANTA.SCONN288_DDR506112002KQ(CHIPS)':
 'VSS32': CDS_PINID='VSS32';
NODE_NAME     J100 77
 '@T6G_MB_LIB.T6G(SCH_1):PAGE105_I176@PURE_QUANTA.SCONN288_DDR506112002KQ(CHIPS)':
 'VSS33': CDS_PINID='VSS33';
NODE_NAME     J100 79
 '@T6G_MB_LIB.T6G(SCH_1):PAGE105_I176@PURE_QUANTA.SCONN288_DDR506112002KQ(CHIPS)':
 'VSS34': CDS_PINID='VSS34';
NODE_NAME     J100 81
 '@T6G_MB_LIB.T6G(SCH_1):PAGE105_I176@PURE_QUANTA.SCONN288_DDR506112002KQ(CHIPS)':
 'VSS35': CDS_PINID='VSS35';
NODE_NAME     J100 83
 '@T6G_MB_LIB.T6G(SCH_1):PAGE105_I176@PURE_QUANTA.SCONN288_DDR506112002KQ(CHIPS)':
 'VSS36': CDS_PINID='VSS36';
NODE_NAME     J100 85
 '@T6G_MB_LIB.T6G(SCH_1):PAGE105_I176@PURE_QUANTA.SCONN288_DDR506112002KQ(CHIPS)':
 'VSS37': CDS_PINID='VSS37';
NODE_NAME     J100 88
 '@T6G_MB_LIB.T6G(SCH_1):PAGE105_I176@PURE_QUANTA.SCONN288_DDR506112002KQ(CHIPS)':
 'VSS38': CDS_PINID='VSS38';
NODE_NAME     J100 90
 '@T6G_MB_LIB.T6G(SCH_1):PAGE105_I176@PURE_QUANTA.SCONN288_DDR506112002KQ(CHIPS)':
 'VSS39': CDS_PINID='VSS39';
NODE_NAME     J100 92
 '@T6G_MB_LIB.T6G(SCH_1):PAGE105_I176@PURE_QUANTA.SCONN288_DDR506112002KQ(CHIPS)':
 'VSS40': CDS_PINID='VSS40';
NODE_NAME     J100 95
 '@T6G_MB_LIB.T6G(SCH_1):PAGE105_I176@PURE_QUANTA.SCONN288_DDR506112002KQ(CHIPS)':
 'VSS41': CDS_PINID='VSS41';
NODE_NAME     J100 97
 '@T6G_MB_LIB.T6G(SCH_1):PAGE105_I176@PURE_QUANTA.SCONN288_DDR506112002KQ(CHIPS)':
 'VSS42': CDS_PINID='VSS42';
NODE_NAME     J100 99
 '@T6G_MB_LIB.T6G(SCH_1):PAGE105_I176@PURE_QUANTA.SCONN288_DDR506112002KQ(CHIPS)':
 'VSS43': CDS_PINID='VSS43';
NODE_NAME     J100 101
 '@T6G_MB_LIB.T6G(SCH_1):PAGE105_I176@PURE_QUANTA.SCONN288_DDR506112002KQ(CHIPS)':
 'VSS44': CDS_PINID='VSS44';
NODE_NAME     J100 103
 '@T6G_MB_LIB.T6G(SCH_1):PAGE105_I176@PURE_QUANTA.SCONN288_DDR506112002KQ(CHIPS)':
 'VSS45': CDS_PINID='VSS45';
NODE_NAME     J100 106
 '@T6G_MB_LIB.T6G(SCH_1):PAGE105_I176@PURE_QUANTA.SCONN288_DDR506112002KQ(CHIPS)':
 'VSS46': CDS_PINID='VSS46';
NODE_NAME     J100 108
 '@T6G_MB_LIB.T6G(SCH_1):PAGE105_I176@PURE_QUANTA.SCONN288_DDR506112002KQ(CHIPS)':
 'VSS47': CDS_PINID='VSS47';
NODE_NAME     J100 110
 '@T6G_MB_LIB.T6G(SCH_1):PAGE105_I176@PURE_QUANTA.SCONN288_DDR506112002KQ(CHIPS)':
 'VSS48': CDS_PINID='VSS48';
NODE_NAME     J100 112
 '@T6G_MB_LIB.T6G(SCH_1):PAGE105_I176@PURE_QUANTA.SCONN288_DDR506112002KQ(CHIPS)':
 'VSS49': CDS_PINID='VSS49';
NODE_NAME     J100 114
 '@T6G_MB_LIB.T6G(SCH_1):PAGE105_I176@PURE_QUANTA.SCONN288_DDR506112002KQ(CHIPS)':
 'VSS50': CDS_PINID='VSS50';
NODE_NAME     J100 117
 '@T6G_MB_LIB.T6G(SCH_1):PAGE105_I176@PURE_QUANTA.SCONN288_DDR506112002KQ(CHIPS)':
 'VSS51': CDS_PINID='VSS51';
NODE_NAME     J100 119
 '@T6G_MB_LIB.T6G(SCH_1):PAGE105_I176@PURE_QUANTA.SCONN288_DDR506112002KQ(CHIPS)':
 'VSS52': CDS_PINID='VSS52';
NODE_NAME     J100 121
 '@T6G_MB_LIB.T6G(SCH_1):PAGE105_I176@PURE_QUANTA.SCONN288_DDR506112002KQ(CHIPS)':
 'VSS53': CDS_PINID='VSS53';
NODE_NAME     J100 123
 '@T6G_MB_LIB.T6G(SCH_1):PAGE105_I176@PURE_QUANTA.SCONN288_DDR506112002KQ(CHIPS)':
 'VSS54': CDS_PINID='VSS54';
NODE_NAME     J100 125
 '@T6G_MB_LIB.T6G(SCH_1):PAGE105_I176@PURE_QUANTA.SCONN288_DDR506112002KQ(CHIPS)':
 'VSS55': CDS_PINID='VSS55';
NODE_NAME     J100 128
 '@T6G_MB_LIB.T6G(SCH_1):PAGE105_I176@PURE_QUANTA.SCONN288_DDR506112002KQ(CHIPS)':
 'VSS56': CDS_PINID='VSS56';
NODE_NAME     J100 130
 '@T6G_MB_LIB.T6G(SCH_1):PAGE105_I176@PURE_QUANTA.SCONN288_DDR506112002KQ(CHIPS)':
 'VSS57': CDS_PINID='VSS57';
NODE_NAME     J100 132
 '@T6G_MB_LIB.T6G(SCH_1):PAGE105_I176@PURE_QUANTA.SCONN288_DDR506112002KQ(CHIPS)':
 'VSS58': CDS_PINID='VSS58';
NODE_NAME     J100 134
 '@T6G_MB_LIB.T6G(SCH_1):PAGE105_I176@PURE_QUANTA.SCONN288_DDR506112002KQ(CHIPS)':
 'VSS59': CDS_PINID='VSS59';
NODE_NAME     J100 136
 '@T6G_MB_LIB.T6G(SCH_1):PAGE105_I176@PURE_QUANTA.SCONN288_DDR506112002KQ(CHIPS)':
 'VSS60': CDS_PINID='VSS60';
NODE_NAME     J100 139
 '@T6G_MB_LIB.T6G(SCH_1):PAGE105_I176@PURE_QUANTA.SCONN288_DDR506112002KQ(CHIPS)':
 'VSS61': CDS_PINID='VSS61';
NODE_NAME     J100 141
 '@T6G_MB_LIB.T6G(SCH_1):PAGE105_I176@PURE_QUANTA.SCONN288_DDR506112002KQ(CHIPS)':
 'VSS62': CDS_PINID='VSS62';
NODE_NAME     J100 143
 '@T6G_MB_LIB.T6G(SCH_1):PAGE105_I176@PURE_QUANTA.SCONN288_DDR506112002KQ(CHIPS)':
 'VSS63': CDS_PINID='VSS63';
NODE_NAME     J100 151
 '@T6G_MB_LIB.T6G(SCH_1):PAGE105_I176@PURE_QUANTA.SCONN288_DDR506112002KQ(CHIPS)':
 'VSS64': CDS_PINID='VSS64';
NODE_NAME     J100 153
 '@T6G_MB_LIB.T6G(SCH_1):PAGE105_I176@PURE_QUANTA.SCONN288_DDR506112002KQ(CHIPS)':
 'VSS65': CDS_PINID='VSS65';
NODE_NAME     J100 155
 '@T6G_MB_LIB.T6G(SCH_1):PAGE105_I176@PURE_QUANTA.SCONN288_DDR506112002KQ(CHIPS)':
 'VSS66': CDS_PINID='VSS66';
NODE_NAME     J100 158
 '@T6G_MB_LIB.T6G(SCH_1):PAGE105_I176@PURE_QUANTA.SCONN288_DDR506112002KQ(CHIPS)':
 'VSS67': CDS_PINID='VSS67';
NODE_NAME     J100 160
 '@T6G_MB_LIB.T6G(SCH_1):PAGE105_I176@PURE_QUANTA.SCONN288_DDR506112002KQ(CHIPS)':
 'VSS68': CDS_PINID='VSS68';
NODE_NAME     J100 162
 '@T6G_MB_LIB.T6G(SCH_1):PAGE105_I176@PURE_QUANTA.SCONN288_DDR506112002KQ(CHIPS)':
 'VSS69': CDS_PINID='VSS69';
NODE_NAME     J100 164
 '@T6G_MB_LIB.T6G(SCH_1):PAGE105_I176@PURE_QUANTA.SCONN288_DDR506112002KQ(CHIPS)':
 'VSS70': CDS_PINID='VSS70';
NODE_NAME     J100 166
 '@T6G_MB_LIB.T6G(SCH_1):PAGE105_I176@PURE_QUANTA.SCONN288_DDR506112002KQ(CHIPS)':
 'VSS71': CDS_PINID='VSS71';
NODE_NAME     J100 169
 '@T6G_MB_LIB.T6G(SCH_1):PAGE105_I176@PURE_QUANTA.SCONN288_DDR506112002KQ(CHIPS)':
 'VSS72': CDS_PINID='VSS72';
NODE_NAME     J100 171
 '@T6G_MB_LIB.T6G(SCH_1):PAGE105_I176@PURE_QUANTA.SCONN288_DDR506112002KQ(CHIPS)':
 'VSS73': CDS_PINID='VSS73';
NODE_NAME     J100 173
 '@T6G_MB_LIB.T6G(SCH_1):PAGE105_I176@PURE_QUANTA.SCONN288_DDR506112002KQ(CHIPS)':
 'VSS74': CDS_PINID='VSS74';
NODE_NAME     J100 175
 '@T6G_MB_LIB.T6G(SCH_1):PAGE105_I176@PURE_QUANTA.SCONN288_DDR506112002KQ(CHIPS)':
 'VSS75': CDS_PINID='VSS75';
NODE_NAME     J100 177
 '@T6G_MB_LIB.T6G(SCH_1):PAGE105_I176@PURE_QUANTA.SCONN288_DDR506112002KQ(CHIPS)':
 'VSS76': CDS_PINID='VSS76';
NODE_NAME     J100 180
 '@T6G_MB_LIB.T6G(SCH_1):PAGE105_I176@PURE_QUANTA.SCONN288_DDR506112002KQ(CHIPS)':
 'VSS77': CDS_PINID='VSS77';
NODE_NAME     J100 182
 '@T6G_MB_LIB.T6G(SCH_1):PAGE105_I176@PURE_QUANTA.SCONN288_DDR506112002KQ(CHIPS)':
 'VSS78': CDS_PINID='VSS78';
NODE_NAME     J100 184
 '@T6G_MB_LIB.T6G(SCH_1):PAGE105_I176@PURE_QUANTA.SCONN288_DDR506112002KQ(CHIPS)':
 'VSS79': CDS_PINID='VSS79';
NODE_NAME     J100 186
 '@T6G_MB_LIB.T6G(SCH_1):PAGE105_I176@PURE_QUANTA.SCONN288_DDR506112002KQ(CHIPS)':
 'VSS80': CDS_PINID='VSS80';
NODE_NAME     J100 188
 '@T6G_MB_LIB.T6G(SCH_1):PAGE105_I176@PURE_QUANTA.SCONN288_DDR506112002KQ(CHIPS)':
 'VSS81': CDS_PINID='VSS81';
NODE_NAME     J100 191
 '@T6G_MB_LIB.T6G(SCH_1):PAGE105_I176@PURE_QUANTA.SCONN288_DDR506112002KQ(CHIPS)':
 'VSS82': CDS_PINID='VSS82';
NODE_NAME     J100 193
 '@T6G_MB_LIB.T6G(SCH_1):PAGE105_I176@PURE_QUANTA.SCONN288_DDR506112002KQ(CHIPS)':
 'VSS83': CDS_PINID='VSS83';
NODE_NAME     J100 195
 '@T6G_MB_LIB.T6G(SCH_1):PAGE105_I176@PURE_QUANTA.SCONN288_DDR506112002KQ(CHIPS)':
 'VSS84': CDS_PINID='VSS84';
NODE_NAME     J100 197
 '@T6G_MB_LIB.T6G(SCH_1):PAGE105_I176@PURE_QUANTA.SCONN288_DDR506112002KQ(CHIPS)':
 'VSS85': CDS_PINID='VSS85';
NODE_NAME     J100 199
 '@T6G_MB_LIB.T6G(SCH_1):PAGE105_I176@PURE_QUANTA.SCONN288_DDR506112002KQ(CHIPS)':
 'VSS86': CDS_PINID='VSS86';
NODE_NAME     J100 202
 '@T6G_MB_LIB.T6G(SCH_1):PAGE105_I176@PURE_QUANTA.SCONN288_DDR506112002KQ(CHIPS)':
 'VSS87': CDS_PINID='VSS87';
NODE_NAME     J100 204
 '@T6G_MB_LIB.T6G(SCH_1):PAGE105_I176@PURE_QUANTA.SCONN288_DDR506112002KQ(CHIPS)':
 'VSS88': CDS_PINID='VSS88';
NODE_NAME     J100 206
 '@T6G_MB_LIB.T6G(SCH_1):PAGE105_I176@PURE_QUANTA.SCONN288_DDR506112002KQ(CHIPS)':
 'VSS89': CDS_PINID='VSS89';
NODE_NAME     J100 208
 '@T6G_MB_LIB.T6G(SCH_1):PAGE105_I176@PURE_QUANTA.SCONN288_DDR506112002KQ(CHIPS)':
 'VSS90': CDS_PINID='VSS90';
NODE_NAME     J100 210
 '@T6G_MB_LIB.T6G(SCH_1):PAGE105_I176@PURE_QUANTA.SCONN288_DDR506112002KQ(CHIPS)':
 'VSS91': CDS_PINID='VSS91';
NODE_NAME     J100 212
 '@T6G_MB_LIB.T6G(SCH_1):PAGE105_I176@PURE_QUANTA.SCONN288_DDR506112002KQ(CHIPS)':
 'VSS92': CDS_PINID='VSS92';
NODE_NAME     J100 214
 '@T6G_MB_LIB.T6G(SCH_1):PAGE105_I176@PURE_QUANTA.SCONN288_DDR506112002KQ(CHIPS)':
 'VSS93': CDS_PINID='VSS93';
NODE_NAME     J100 216
 '@T6G_MB_LIB.T6G(SCH_1):PAGE105_I176@PURE_QUANTA.SCONN288_DDR506112002KQ(CHIPS)':
 'VSS94': CDS_PINID='VSS94';
NODE_NAME     J100 219
 '@T6G_MB_LIB.T6G(SCH_1):PAGE105_I176@PURE_QUANTA.SCONN288_DDR506112002KQ(CHIPS)':
 'VSS95': CDS_PINID='VSS95';
NODE_NAME     J100 222
 '@T6G_MB_LIB.T6G(SCH_1):PAGE105_I176@PURE_QUANTA.SCONN288_DDR506112002KQ(CHIPS)':
 'VSS96': CDS_PINID='VSS96';
NODE_NAME     J100 224
 '@T6G_MB_LIB.T6G(SCH_1):PAGE105_I176@PURE_QUANTA.SCONN288_DDR506112002KQ(CHIPS)':
 'VSS97': CDS_PINID='VSS97';
NODE_NAME     J100 226
 '@T6G_MB_LIB.T6G(SCH_1):PAGE105_I176@PURE_QUANTA.SCONN288_DDR506112002KQ(CHIPS)':
 'VSS98': CDS_PINID='VSS98';
NODE_NAME     J100 228
 '@T6G_MB_LIB.T6G(SCH_1):PAGE105_I176@PURE_QUANTA.SCONN288_DDR506112002KQ(CHIPS)':
 'VSS99': CDS_PINID='VSS99';
NODE_NAME     J100 230
 '@T6G_MB_LIB.T6G(SCH_1):PAGE105_I176@PURE_QUANTA.SCONN288_DDR506112002KQ(CHIPS)':
 'VSS100': CDS_PINID='VSS100';
NODE_NAME     J100 233
 '@T6G_MB_LIB.T6G(SCH_1):PAGE105_I176@PURE_QUANTA.SCONN288_DDR506112002KQ(CHIPS)':
 'VSS101': CDS_PINID='VSS101';
NODE_NAME     J100 235
 '@T6G_MB_LIB.T6G(SCH_1):PAGE105_I176@PURE_QUANTA.SCONN288_DDR506112002KQ(CHIPS)':
 'VSS102': CDS_PINID='VSS102';
NODE_NAME     J100 237
 '@T6G_MB_LIB.T6G(SCH_1):PAGE105_I176@PURE_QUANTA.SCONN288_DDR506112002KQ(CHIPS)':
 'VSS103': CDS_PINID='VSS103';
NODE_NAME     J100 240
 '@T6G_MB_LIB.T6G(SCH_1):PAGE105_I176@PURE_QUANTA.SCONN288_DDR506112002KQ(CHIPS)':
 'VSS104': CDS_PINID='VSS104';
NODE_NAME     J100 242
 '@T6G_MB_LIB.T6G(SCH_1):PAGE105_I176@PURE_QUANTA.SCONN288_DDR506112002KQ(CHIPS)':
 'VSS105': CDS_PINID='VSS105';
NODE_NAME     J100 244
 '@T6G_MB_LIB.T6G(SCH_1):PAGE105_I176@PURE_QUANTA.SCONN288_DDR506112002KQ(CHIPS)':
 'VSS106': CDS_PINID='VSS106';
NODE_NAME     J100 246
 '@T6G_MB_LIB.T6G(SCH_1):PAGE105_I176@PURE_QUANTA.SCONN288_DDR506112002KQ(CHIPS)':
 'VSS107': CDS_PINID='VSS107';
NODE_NAME     J100 248
 '@T6G_MB_LIB.T6G(SCH_1):PAGE105_I176@PURE_QUANTA.SCONN288_DDR506112002KQ(CHIPS)':
 'VSS108': CDS_PINID='VSS108';
NODE_NAME     J100 251
 '@T6G_MB_LIB.T6G(SCH_1):PAGE105_I176@PURE_QUANTA.SCONN288_DDR506112002KQ(CHIPS)':
 'VSS109': CDS_PINID='VSS109';
NODE_NAME     J100 253
 '@T6G_MB_LIB.T6G(SCH_1):PAGE105_I176@PURE_QUANTA.SCONN288_DDR506112002KQ(CHIPS)':
 'VSS110': CDS_PINID='VSS110';
NODE_NAME     J100 255
 '@T6G_MB_LIB.T6G(SCH_1):PAGE105_I176@PURE_QUANTA.SCONN288_DDR506112002KQ(CHIPS)':
 'VSS111': CDS_PINID='VSS111';
NODE_NAME     J100 257
 '@T6G_MB_LIB.T6G(SCH_1):PAGE105_I176@PURE_QUANTA.SCONN288_DDR506112002KQ(CHIPS)':
 'VSS112': CDS_PINID='VSS112';
NODE_NAME     J100 259
 '@T6G_MB_LIB.T6G(SCH_1):PAGE105_I176@PURE_QUANTA.SCONN288_DDR506112002KQ(CHIPS)':
 'VSS113': CDS_PINID='VSS113';
NODE_NAME     J100 262
 '@T6G_MB_LIB.T6G(SCH_1):PAGE105_I176@PURE_QUANTA.SCONN288_DDR506112002KQ(CHIPS)':
 'VSS114': CDS_PINID='VSS114';
NODE_NAME     J100 264
 '@T6G_MB_LIB.T6G(SCH_1):PAGE105_I176@PURE_QUANTA.SCONN288_DDR506112002KQ(CHIPS)':
 'VSS115': CDS_PINID='VSS115';
NODE_NAME     J100 266
 '@T6G_MB_LIB.T6G(SCH_1):PAGE105_I176@PURE_QUANTA.SCONN288_DDR506112002KQ(CHIPS)':
 'VSS116': CDS_PINID='VSS116';
NODE_NAME     J100 268
 '@T6G_MB_LIB.T6G(SCH_1):PAGE105_I176@PURE_QUANTA.SCONN288_DDR506112002KQ(CHIPS)':
 'VSS117': CDS_PINID='VSS117';
NODE_NAME     J100 270
 '@T6G_MB_LIB.T6G(SCH_1):PAGE105_I176@PURE_QUANTA.SCONN288_DDR506112002KQ(CHIPS)':
 'VSS118': CDS_PINID='VSS118';
NODE_NAME     J100 273
 '@T6G_MB_LIB.T6G(SCH_1):PAGE105_I176@PURE_QUANTA.SCONN288_DDR506112002KQ(CHIPS)':
 'VSS119': CDS_PINID='VSS119';
NODE_NAME     J100 275
 '@T6G_MB_LIB.T6G(SCH_1):PAGE105_I176@PURE_QUANTA.SCONN288_DDR506112002KQ(CHIPS)':
 'VSS120': CDS_PINID='VSS120';
NODE_NAME     J100 277
 '@T6G_MB_LIB.T6G(SCH_1):PAGE105_I176@PURE_QUANTA.SCONN288_DDR506112002KQ(CHIPS)':
 'VSS121': CDS_PINID='VSS121';
NODE_NAME     J100 279
 '@T6G_MB_LIB.T6G(SCH_1):PAGE105_I176@PURE_QUANTA.SCONN288_DDR506112002KQ(CHIPS)':
 'VSS122': CDS_PINID='VSS122';
NODE_NAME     J100 281
 '@T6G_MB_LIB.T6G(SCH_1):PAGE105_I176@PURE_QUANTA.SCONN288_DDR506112002KQ(CHIPS)':
 'VSS123': CDS_PINID='VSS123';
NODE_NAME     J100 284
 '@T6G_MB_LIB.T6G(SCH_1):PAGE105_I176@PURE_QUANTA.SCONN288_DDR506112002KQ(CHIPS)':
 'VSS124': CDS_PINID='VSS124';
NODE_NAME     J100 286
 '@T6G_MB_LIB.T6G(SCH_1):PAGE105_I176@PURE_QUANTA.SCONN288_DDR506112002KQ(CHIPS)':
 'VSS125': CDS_PINID='VSS125';
NODE_NAME     J100 288
 '@T6G_MB_LIB.T6G(SCH_1):PAGE105_I176@PURE_QUANTA.SCONN288_DDR506112002KQ(CHIPS)':
 'VSS126': CDS_PINID='VSS126';
NODE_NAME     C168 2
 '@T6G_MB_LIB.T6G(SCH_1):PAGE105_I185@PURE_QUANTA.Q_CAP(CHIPS)':
 'B': CDS_PINID='B';
NODE_NAME     C534 2
 '@T6G_MB_LIB.T6G(SCH_1):PAGE105_I238@PURE_QUANTA.Q_CAP(CHIPS)':
 'B': CDS_PINID='B';
NODE_NAME     C535 2
 '@T6G_MB_LIB.T6G(SCH_1):PAGE105_I239@PURE_QUANTA.Q_CAP(CHIPS)':
 'B': CDS_PINID='B';
NODE_NAME     R776 2
 '@T6G_MB_LIB.T6G(SCH_1):PAGE106_I127@PURE_QUANTA.Q_RES(CHIPS)':
 'B': CDS_PINID='B';
NODE_NAME     J29 G1
 '@T6G_MB_LIB.T6G(SCH_1):PAGE106_I143@PURE_QUANTA.SCONN288_DDR506112002KQ(CHIPS)':
 'G1': CDS_PINID='G1';
NODE_NAME     J29 G2
 '@T6G_MB_LIB.T6G(SCH_1):PAGE106_I143@PURE_QUANTA.SCONN288_DDR506112002KQ(CHIPS)':
 'G2': CDS_PINID='G2';
NODE_NAME     J29 G3
 '@T6G_MB_LIB.T6G(SCH_1):PAGE106_I143@PURE_QUANTA.SCONN288_DDR506112002KQ(CHIPS)':
 'G3': CDS_PINID='G3';
NODE_NAME     J29 6
 '@T6G_MB_LIB.T6G(SCH_1):PAGE106_I143@PURE_QUANTA.SCONN288_DDR506112002KQ(CHIPS)':
 'VSS0': CDS_PINID='VSS0';
NODE_NAME     J29 8
 '@T6G_MB_LIB.T6G(SCH_1):PAGE106_I143@PURE_QUANTA.SCONN288_DDR506112002KQ(CHIPS)':
 'VSS1': CDS_PINID='VSS1';
NODE_NAME     J29 10
 '@T6G_MB_LIB.T6G(SCH_1):PAGE106_I143@PURE_QUANTA.SCONN288_DDR506112002KQ(CHIPS)':
 'VSS2': CDS_PINID='VSS2';
NODE_NAME     J29 13
 '@T6G_MB_LIB.T6G(SCH_1):PAGE106_I143@PURE_QUANTA.SCONN288_DDR506112002KQ(CHIPS)':
 'VSS3': CDS_PINID='VSS3';
NODE_NAME     J29 15
 '@T6G_MB_LIB.T6G(SCH_1):PAGE106_I143@PURE_QUANTA.SCONN288_DDR506112002KQ(CHIPS)':
 'VSS4': CDS_PINID='VSS4';
NODE_NAME     J29 17
 '@T6G_MB_LIB.T6G(SCH_1):PAGE106_I143@PURE_QUANTA.SCONN288_DDR506112002KQ(CHIPS)':
 'VSS5': CDS_PINID='VSS5';
NODE_NAME     J29 19
 '@T6G_MB_LIB.T6G(SCH_1):PAGE106_I143@PURE_QUANTA.SCONN288_DDR506112002KQ(CHIPS)':
 'VSS6': CDS_PINID='VSS6';
NODE_NAME     J29 21
 '@T6G_MB_LIB.T6G(SCH_1):PAGE106_I143@PURE_QUANTA.SCONN288_DDR506112002KQ(CHIPS)':
 'VSS7': CDS_PINID='VSS7';
NODE_NAME     J29 24
 '@T6G_MB_LIB.T6G(SCH_1):PAGE106_I143@PURE_QUANTA.SCONN288_DDR506112002KQ(CHIPS)':
 'VSS8': CDS_PINID='VSS8';
NODE_NAME     J29 26
 '@T6G_MB_LIB.T6G(SCH_1):PAGE106_I143@PURE_QUANTA.SCONN288_DDR506112002KQ(CHIPS)':
 'VSS9': CDS_PINID='VSS9';
NODE_NAME     J29 28
 '@T6G_MB_LIB.T6G(SCH_1):PAGE106_I143@PURE_QUANTA.SCONN288_DDR506112002KQ(CHIPS)':
 'VSS10': CDS_PINID='VSS10';
NODE_NAME     J29 30
 '@T6G_MB_LIB.T6G(SCH_1):PAGE106_I143@PURE_QUANTA.SCONN288_DDR506112002KQ(CHIPS)':
 'VSS11': CDS_PINID='VSS11';
NODE_NAME     J29 32
 '@T6G_MB_LIB.T6G(SCH_1):PAGE106_I143@PURE_QUANTA.SCONN288_DDR506112002KQ(CHIPS)':
 'VSS12': CDS_PINID='VSS12';
NODE_NAME     J29 35
 '@T6G_MB_LIB.T6G(SCH_1):PAGE106_I143@PURE_QUANTA.SCONN288_DDR506112002KQ(CHIPS)':
 'VSS13': CDS_PINID='VSS13';
NODE_NAME     J29 37
 '@T6G_MB_LIB.T6G(SCH_1):PAGE106_I143@PURE_QUANTA.SCONN288_DDR506112002KQ(CHIPS)':
 'VSS14': CDS_PINID='VSS14';
NODE_NAME     J29 39
 '@T6G_MB_LIB.T6G(SCH_1):PAGE106_I143@PURE_QUANTA.SCONN288_DDR506112002KQ(CHIPS)':
 'VSS15': CDS_PINID='VSS15';
NODE_NAME     J29 41
 '@T6G_MB_LIB.T6G(SCH_1):PAGE106_I143@PURE_QUANTA.SCONN288_DDR506112002KQ(CHIPS)':
 'VSS16': CDS_PINID='VSS16';
NODE_NAME     J29 43
 '@T6G_MB_LIB.T6G(SCH_1):PAGE106_I143@PURE_QUANTA.SCONN288_DDR506112002KQ(CHIPS)':
 'VSS17': CDS_PINID='VSS17';
NODE_NAME     J29 46
 '@T6G_MB_LIB.T6G(SCH_1):PAGE106_I143@PURE_QUANTA.SCONN288_DDR506112002KQ(CHIPS)':
 'VSS18': CDS_PINID='VSS18';
NODE_NAME     J29 48
 '@T6G_MB_LIB.T6G(SCH_1):PAGE106_I143@PURE_QUANTA.SCONN288_DDR506112002KQ(CHIPS)':
 'VSS19': CDS_PINID='VSS19';
NODE_NAME     J29 50
 '@T6G_MB_LIB.T6G(SCH_1):PAGE106_I143@PURE_QUANTA.SCONN288_DDR506112002KQ(CHIPS)':
 'VSS20': CDS_PINID='VSS20';
NODE_NAME     J29 52
 '@T6G_MB_LIB.T6G(SCH_1):PAGE106_I143@PURE_QUANTA.SCONN288_DDR506112002KQ(CHIPS)':
 'VSS21': CDS_PINID='VSS21';
NODE_NAME     J29 54
 '@T6G_MB_LIB.T6G(SCH_1):PAGE106_I143@PURE_QUANTA.SCONN288_DDR506112002KQ(CHIPS)':
 'VSS22': CDS_PINID='VSS22';
NODE_NAME     J29 57
 '@T6G_MB_LIB.T6G(SCH_1):PAGE106_I143@PURE_QUANTA.SCONN288_DDR506112002KQ(CHIPS)':
 'VSS23': CDS_PINID='VSS23';
NODE_NAME     J29 59
 '@T6G_MB_LIB.T6G(SCH_1):PAGE106_I143@PURE_QUANTA.SCONN288_DDR506112002KQ(CHIPS)':
 'VSS24': CDS_PINID='VSS24';
NODE_NAME     J29 61
 '@T6G_MB_LIB.T6G(SCH_1):PAGE106_I143@PURE_QUANTA.SCONN288_DDR506112002KQ(CHIPS)':
 'VSS25': CDS_PINID='VSS25';
NODE_NAME     J29 63
 '@T6G_MB_LIB.T6G(SCH_1):PAGE106_I143@PURE_QUANTA.SCONN288_DDR506112002KQ(CHIPS)':
 'VSS26': CDS_PINID='VSS26';
NODE_NAME     J29 65
 '@T6G_MB_LIB.T6G(SCH_1):PAGE106_I143@PURE_QUANTA.SCONN288_DDR506112002KQ(CHIPS)':
 'VSS27': CDS_PINID='VSS27';
NODE_NAME     J29 67
 '@T6G_MB_LIB.T6G(SCH_1):PAGE106_I143@PURE_QUANTA.SCONN288_DDR506112002KQ(CHIPS)':
 'VSS28': CDS_PINID='VSS28';
NODE_NAME     J29 69
 '@T6G_MB_LIB.T6G(SCH_1):PAGE106_I143@PURE_QUANTA.SCONN288_DDR506112002KQ(CHIPS)':
 'VSS29': CDS_PINID='VSS29';
NODE_NAME     J29 71
 '@T6G_MB_LIB.T6G(SCH_1):PAGE106_I143@PURE_QUANTA.SCONN288_DDR506112002KQ(CHIPS)':
 'VSS30': CDS_PINID='VSS30';
NODE_NAME     J29 73
 '@T6G_MB_LIB.T6G(SCH_1):PAGE106_I143@PURE_QUANTA.SCONN288_DDR506112002KQ(CHIPS)':
 'VSS31': CDS_PINID='VSS31';
NODE_NAME     J29 75
 '@T6G_MB_LIB.T6G(SCH_1):PAGE106_I143@PURE_QUANTA.SCONN288_DDR506112002KQ(CHIPS)':
 'VSS32': CDS_PINID='VSS32';
NODE_NAME     J29 77
 '@T6G_MB_LIB.T6G(SCH_1):PAGE106_I143@PURE_QUANTA.SCONN288_DDR506112002KQ(CHIPS)':
 'VSS33': CDS_PINID='VSS33';
NODE_NAME     J29 79
 '@T6G_MB_LIB.T6G(SCH_1):PAGE106_I143@PURE_QUANTA.SCONN288_DDR506112002KQ(CHIPS)':
 'VSS34': CDS_PINID='VSS34';
NODE_NAME     J29 81
 '@T6G_MB_LIB.T6G(SCH_1):PAGE106_I143@PURE_QUANTA.SCONN288_DDR506112002KQ(CHIPS)':
 'VSS35': CDS_PINID='VSS35';
NODE_NAME     J29 83
 '@T6G_MB_LIB.T6G(SCH_1):PAGE106_I143@PURE_QUANTA.SCONN288_DDR506112002KQ(CHIPS)':
 'VSS36': CDS_PINID='VSS36';
NODE_NAME     J29 85
 '@T6G_MB_LIB.T6G(SCH_1):PAGE106_I143@PURE_QUANTA.SCONN288_DDR506112002KQ(CHIPS)':
 'VSS37': CDS_PINID='VSS37';
NODE_NAME     J29 88
 '@T6G_MB_LIB.T6G(SCH_1):PAGE106_I143@PURE_QUANTA.SCONN288_DDR506112002KQ(CHIPS)':
 'VSS38': CDS_PINID='VSS38';
NODE_NAME     J29 90
 '@T6G_MB_LIB.T6G(SCH_1):PAGE106_I143@PURE_QUANTA.SCONN288_DDR506112002KQ(CHIPS)':
 'VSS39': CDS_PINID='VSS39';
NODE_NAME     J29 92
 '@T6G_MB_LIB.T6G(SCH_1):PAGE106_I143@PURE_QUANTA.SCONN288_DDR506112002KQ(CHIPS)':
 'VSS40': CDS_PINID='VSS40';
NODE_NAME     J29 95
 '@T6G_MB_LIB.T6G(SCH_1):PAGE106_I143@PURE_QUANTA.SCONN288_DDR506112002KQ(CHIPS)':
 'VSS41': CDS_PINID='VSS41';
NODE_NAME     J29 97
 '@T6G_MB_LIB.T6G(SCH_1):PAGE106_I143@PURE_QUANTA.SCONN288_DDR506112002KQ(CHIPS)':
 'VSS42': CDS_PINID='VSS42';
NODE_NAME     J29 99
 '@T6G_MB_LIB.T6G(SCH_1):PAGE106_I143@PURE_QUANTA.SCONN288_DDR506112002KQ(CHIPS)':
 'VSS43': CDS_PINID='VSS43';
NODE_NAME     J29 101
 '@T6G_MB_LIB.T6G(SCH_1):PAGE106_I143@PURE_QUANTA.SCONN288_DDR506112002KQ(CHIPS)':
 'VSS44': CDS_PINID='VSS44';
NODE_NAME     J29 103
 '@T6G_MB_LIB.T6G(SCH_1):PAGE106_I143@PURE_QUANTA.SCONN288_DDR506112002KQ(CHIPS)':
 'VSS45': CDS_PINID='VSS45';
NODE_NAME     J29 106
 '@T6G_MB_LIB.T6G(SCH_1):PAGE106_I143@PURE_QUANTA.SCONN288_DDR506112002KQ(CHIPS)':
 'VSS46': CDS_PINID='VSS46';
NODE_NAME     J29 108
 '@T6G_MB_LIB.T6G(SCH_1):PAGE106_I143@PURE_QUANTA.SCONN288_DDR506112002KQ(CHIPS)':
 'VSS47': CDS_PINID='VSS47';
NODE_NAME     J29 110
 '@T6G_MB_LIB.T6G(SCH_1):PAGE106_I143@PURE_QUANTA.SCONN288_DDR506112002KQ(CHIPS)':
 'VSS48': CDS_PINID='VSS48';
NODE_NAME     J29 112
 '@T6G_MB_LIB.T6G(SCH_1):PAGE106_I143@PURE_QUANTA.SCONN288_DDR506112002KQ(CHIPS)':
 'VSS49': CDS_PINID='VSS49';
NODE_NAME     J29 114
 '@T6G_MB_LIB.T6G(SCH_1):PAGE106_I143@PURE_QUANTA.SCONN288_DDR506112002KQ(CHIPS)':
 'VSS50': CDS_PINID='VSS50';
NODE_NAME     J29 117
 '@T6G_MB_LIB.T6G(SCH_1):PAGE106_I143@PURE_QUANTA.SCONN288_DDR506112002KQ(CHIPS)':
 'VSS51': CDS_PINID='VSS51';
NODE_NAME     J29 119
 '@T6G_MB_LIB.T6G(SCH_1):PAGE106_I143@PURE_QUANTA.SCONN288_DDR506112002KQ(CHIPS)':
 'VSS52': CDS_PINID='VSS52';
NODE_NAME     J29 121
 '@T6G_MB_LIB.T6G(SCH_1):PAGE106_I143@PURE_QUANTA.SCONN288_DDR506112002KQ(CHIPS)':
 'VSS53': CDS_PINID='VSS53';
NODE_NAME     J29 123
 '@T6G_MB_LIB.T6G(SCH_1):PAGE106_I143@PURE_QUANTA.SCONN288_DDR506112002KQ(CHIPS)':
 'VSS54': CDS_PINID='VSS54';
NODE_NAME     J29 125
 '@T6G_MB_LIB.T6G(SCH_1):PAGE106_I143@PURE_QUANTA.SCONN288_DDR506112002KQ(CHIPS)':
 'VSS55': CDS_PINID='VSS55';
NODE_NAME     J29 128
 '@T6G_MB_LIB.T6G(SCH_1):PAGE106_I143@PURE_QUANTA.SCONN288_DDR506112002KQ(CHIPS)':
 'VSS56': CDS_PINID='VSS56';
NODE_NAME     J29 130
 '@T6G_MB_LIB.T6G(SCH_1):PAGE106_I143@PURE_QUANTA.SCONN288_DDR506112002KQ(CHIPS)':
 'VSS57': CDS_PINID='VSS57';
NODE_NAME     J29 132
 '@T6G_MB_LIB.T6G(SCH_1):PAGE106_I143@PURE_QUANTA.SCONN288_DDR506112002KQ(CHIPS)':
 'VSS58': CDS_PINID='VSS58';
NODE_NAME     J29 134
 '@T6G_MB_LIB.T6G(SCH_1):PAGE106_I143@PURE_QUANTA.SCONN288_DDR506112002KQ(CHIPS)':
 'VSS59': CDS_PINID='VSS59';
NODE_NAME     J29 136
 '@T6G_MB_LIB.T6G(SCH_1):PAGE106_I143@PURE_QUANTA.SCONN288_DDR506112002KQ(CHIPS)':
 'VSS60': CDS_PINID='VSS60';
NODE_NAME     J29 139
 '@T6G_MB_LIB.T6G(SCH_1):PAGE106_I143@PURE_QUANTA.SCONN288_DDR506112002KQ(CHIPS)':
 'VSS61': CDS_PINID='VSS61';
NODE_NAME     J29 141
 '@T6G_MB_LIB.T6G(SCH_1):PAGE106_I143@PURE_QUANTA.SCONN288_DDR506112002KQ(CHIPS)':
 'VSS62': CDS_PINID='VSS62';
NODE_NAME     J29 143
 '@T6G_MB_LIB.T6G(SCH_1):PAGE106_I143@PURE_QUANTA.SCONN288_DDR506112002KQ(CHIPS)':
 'VSS63': CDS_PINID='VSS63';
NODE_NAME     J29 151
 '@T6G_MB_LIB.T6G(SCH_1):PAGE106_I143@PURE_QUANTA.SCONN288_DDR506112002KQ(CHIPS)':
 'VSS64': CDS_PINID='VSS64';
NODE_NAME     J29 153
 '@T6G_MB_LIB.T6G(SCH_1):PAGE106_I143@PURE_QUANTA.SCONN288_DDR506112002KQ(CHIPS)':
 'VSS65': CDS_PINID='VSS65';
NODE_NAME     J29 155
 '@T6G_MB_LIB.T6G(SCH_1):PAGE106_I143@PURE_QUANTA.SCONN288_DDR506112002KQ(CHIPS)':
 'VSS66': CDS_PINID='VSS66';
NODE_NAME     J29 158
 '@T6G_MB_LIB.T6G(SCH_1):PAGE106_I143@PURE_QUANTA.SCONN288_DDR506112002KQ(CHIPS)':
 'VSS67': CDS_PINID='VSS67';
NODE_NAME     J29 160
 '@T6G_MB_LIB.T6G(SCH_1):PAGE106_I143@PURE_QUANTA.SCONN288_DDR506112002KQ(CHIPS)':
 'VSS68': CDS_PINID='VSS68';
NODE_NAME     J29 162
 '@T6G_MB_LIB.T6G(SCH_1):PAGE106_I143@PURE_QUANTA.SCONN288_DDR506112002KQ(CHIPS)':
 'VSS69': CDS_PINID='VSS69';
NODE_NAME     J29 164
 '@T6G_MB_LIB.T6G(SCH_1):PAGE106_I143@PURE_QUANTA.SCONN288_DDR506112002KQ(CHIPS)':
 'VSS70': CDS_PINID='VSS70';
NODE_NAME     J29 166
 '@T6G_MB_LIB.T6G(SCH_1):PAGE106_I143@PURE_QUANTA.SCONN288_DDR506112002KQ(CHIPS)':
 'VSS71': CDS_PINID='VSS71';
NODE_NAME     J29 169
 '@T6G_MB_LIB.T6G(SCH_1):PAGE106_I143@PURE_QUANTA.SCONN288_DDR506112002KQ(CHIPS)':
 'VSS72': CDS_PINID='VSS72';
NODE_NAME     J29 171
 '@T6G_MB_LIB.T6G(SCH_1):PAGE106_I143@PURE_QUANTA.SCONN288_DDR506112002KQ(CHIPS)':
 'VSS73': CDS_PINID='VSS73';
NODE_NAME     J29 173
 '@T6G_MB_LIB.T6G(SCH_1):PAGE106_I143@PURE_QUANTA.SCONN288_DDR506112002KQ(CHIPS)':
 'VSS74': CDS_PINID='VSS74';
NODE_NAME     J29 175
 '@T6G_MB_LIB.T6G(SCH_1):PAGE106_I143@PURE_QUANTA.SCONN288_DDR506112002KQ(CHIPS)':
 'VSS75': CDS_PINID='VSS75';
NODE_NAME     J29 177
 '@T6G_MB_LIB.T6G(SCH_1):PAGE106_I143@PURE_QUANTA.SCONN288_DDR506112002KQ(CHIPS)':
 'VSS76': CDS_PINID='VSS76';
NODE_NAME     J29 180
 '@T6G_MB_LIB.T6G(SCH_1):PAGE106_I143@PURE_QUANTA.SCONN288_DDR506112002KQ(CHIPS)':
 'VSS77': CDS_PINID='VSS77';
NODE_NAME     J29 182
 '@T6G_MB_LIB.T6G(SCH_1):PAGE106_I143@PURE_QUANTA.SCONN288_DDR506112002KQ(CHIPS)':
 'VSS78': CDS_PINID='VSS78';
NODE_NAME     J29 184
 '@T6G_MB_LIB.T6G(SCH_1):PAGE106_I143@PURE_QUANTA.SCONN288_DDR506112002KQ(CHIPS)':
 'VSS79': CDS_PINID='VSS79';
NODE_NAME     J29 186
 '@T6G_MB_LIB.T6G(SCH_1):PAGE106_I143@PURE_QUANTA.SCONN288_DDR506112002KQ(CHIPS)':
 'VSS80': CDS_PINID='VSS80';
NODE_NAME     J29 188
 '@T6G_MB_LIB.T6G(SCH_1):PAGE106_I143@PURE_QUANTA.SCONN288_DDR506112002KQ(CHIPS)':
 'VSS81': CDS_PINID='VSS81';
NODE_NAME     J29 191
 '@T6G_MB_LIB.T6G(SCH_1):PAGE106_I143@PURE_QUANTA.SCONN288_DDR506112002KQ(CHIPS)':
 'VSS82': CDS_PINID='VSS82';
NODE_NAME     J29 193
 '@T6G_MB_LIB.T6G(SCH_1):PAGE106_I143@PURE_QUANTA.SCONN288_DDR506112002KQ(CHIPS)':
 'VSS83': CDS_PINID='VSS83';
NODE_NAME     J29 195
 '@T6G_MB_LIB.T6G(SCH_1):PAGE106_I143@PURE_QUANTA.SCONN288_DDR506112002KQ(CHIPS)':
 'VSS84': CDS_PINID='VSS84';
NODE_NAME     J29 197
 '@T6G_MB_LIB.T6G(SCH_1):PAGE106_I143@PURE_QUANTA.SCONN288_DDR506112002KQ(CHIPS)':
 'VSS85': CDS_PINID='VSS85';
NODE_NAME     J29 199
 '@T6G_MB_LIB.T6G(SCH_1):PAGE106_I143@PURE_QUANTA.SCONN288_DDR506112002KQ(CHIPS)':
 'VSS86': CDS_PINID='VSS86';
NODE_NAME     J29 202
 '@T6G_MB_LIB.T6G(SCH_1):PAGE106_I143@PURE_QUANTA.SCONN288_DDR506112002KQ(CHIPS)':
 'VSS87': CDS_PINID='VSS87';
NODE_NAME     J29 204
 '@T6G_MB_LIB.T6G(SCH_1):PAGE106_I143@PURE_QUANTA.SCONN288_DDR506112002KQ(CHIPS)':
 'VSS88': CDS_PINID='VSS88';
NODE_NAME     J29 206
 '@T6G_MB_LIB.T6G(SCH_1):PAGE106_I143@PURE_QUANTA.SCONN288_DDR506112002KQ(CHIPS)':
 'VSS89': CDS_PINID='VSS89';
NODE_NAME     J29 208
 '@T6G_MB_LIB.T6G(SCH_1):PAGE106_I143@PURE_QUANTA.SCONN288_DDR506112002KQ(CHIPS)':
 'VSS90': CDS_PINID='VSS90';
NODE_NAME     J29 210
 '@T6G_MB_LIB.T6G(SCH_1):PAGE106_I143@PURE_QUANTA.SCONN288_DDR506112002KQ(CHIPS)':
 'VSS91': CDS_PINID='VSS91';
NODE_NAME     J29 212
 '@T6G_MB_LIB.T6G(SCH_1):PAGE106_I143@PURE_QUANTA.SCONN288_DDR506112002KQ(CHIPS)':
 'VSS92': CDS_PINID='VSS92';
NODE_NAME     J29 214
 '@T6G_MB_LIB.T6G(SCH_1):PAGE106_I143@PURE_QUANTA.SCONN288_DDR506112002KQ(CHIPS)':
 'VSS93': CDS_PINID='VSS93';
NODE_NAME     J29 216
 '@T6G_MB_LIB.T6G(SCH_1):PAGE106_I143@PURE_QUANTA.SCONN288_DDR506112002KQ(CHIPS)':
 'VSS94': CDS_PINID='VSS94';
NODE_NAME     J29 219
 '@T6G_MB_LIB.T6G(SCH_1):PAGE106_I143@PURE_QUANTA.SCONN288_DDR506112002KQ(CHIPS)':
 'VSS95': CDS_PINID='VSS95';
NODE_NAME     J29 222
 '@T6G_MB_LIB.T6G(SCH_1):PAGE106_I143@PURE_QUANTA.SCONN288_DDR506112002KQ(CHIPS)':
 'VSS96': CDS_PINID='VSS96';
NODE_NAME     J29 224
 '@T6G_MB_LIB.T6G(SCH_1):PAGE106_I143@PURE_QUANTA.SCONN288_DDR506112002KQ(CHIPS)':
 'VSS97': CDS_PINID='VSS97';
NODE_NAME     J29 226
 '@T6G_MB_LIB.T6G(SCH_1):PAGE106_I143@PURE_QUANTA.SCONN288_DDR506112002KQ(CHIPS)':
 'VSS98': CDS_PINID='VSS98';
NODE_NAME     J29 228
 '@T6G_MB_LIB.T6G(SCH_1):PAGE106_I143@PURE_QUANTA.SCONN288_DDR506112002KQ(CHIPS)':
 'VSS99': CDS_PINID='VSS99';
NODE_NAME     J29 230
 '@T6G_MB_LIB.T6G(SCH_1):PAGE106_I143@PURE_QUANTA.SCONN288_DDR506112002KQ(CHIPS)':
 'VSS100': CDS_PINID='VSS100';
NODE_NAME     J29 233
 '@T6G_MB_LIB.T6G(SCH_1):PAGE106_I143@PURE_QUANTA.SCONN288_DDR506112002KQ(CHIPS)':
 'VSS101': CDS_PINID='VSS101';
NODE_NAME     J29 235
 '@T6G_MB_LIB.T6G(SCH_1):PAGE106_I143@PURE_QUANTA.SCONN288_DDR506112002KQ(CHIPS)':
 'VSS102': CDS_PINID='VSS102';
NODE_NAME     J29 237
 '@T6G_MB_LIB.T6G(SCH_1):PAGE106_I143@PURE_QUANTA.SCONN288_DDR506112002KQ(CHIPS)':
 'VSS103': CDS_PINID='VSS103';
NODE_NAME     J29 240
 '@T6G_MB_LIB.T6G(SCH_1):PAGE106_I143@PURE_QUANTA.SCONN288_DDR506112002KQ(CHIPS)':
 'VSS104': CDS_PINID='VSS104';
NODE_NAME     J29 242
 '@T6G_MB_LIB.T6G(SCH_1):PAGE106_I143@PURE_QUANTA.SCONN288_DDR506112002KQ(CHIPS)':
 'VSS105': CDS_PINID='VSS105';
NODE_NAME     J29 244
 '@T6G_MB_LIB.T6G(SCH_1):PAGE106_I143@PURE_QUANTA.SCONN288_DDR506112002KQ(CHIPS)':
 'VSS106': CDS_PINID='VSS106';
NODE_NAME     J29 246
 '@T6G_MB_LIB.T6G(SCH_1):PAGE106_I143@PURE_QUANTA.SCONN288_DDR506112002KQ(CHIPS)':
 'VSS107': CDS_PINID='VSS107';
NODE_NAME     J29 248
 '@T6G_MB_LIB.T6G(SCH_1):PAGE106_I143@PURE_QUANTA.SCONN288_DDR506112002KQ(CHIPS)':
 'VSS108': CDS_PINID='VSS108';
NODE_NAME     J29 251
 '@T6G_MB_LIB.T6G(SCH_1):PAGE106_I143@PURE_QUANTA.SCONN288_DDR506112002KQ(CHIPS)':
 'VSS109': CDS_PINID='VSS109';
NODE_NAME     J29 253
 '@T6G_MB_LIB.T6G(SCH_1):PAGE106_I143@PURE_QUANTA.SCONN288_DDR506112002KQ(CHIPS)':
 'VSS110': CDS_PINID='VSS110';
NODE_NAME     J29 255
 '@T6G_MB_LIB.T6G(SCH_1):PAGE106_I143@PURE_QUANTA.SCONN288_DDR506112002KQ(CHIPS)':
 'VSS111': CDS_PINID='VSS111';
NODE_NAME     J29 257
 '@T6G_MB_LIB.T6G(SCH_1):PAGE106_I143@PURE_QUANTA.SCONN288_DDR506112002KQ(CHIPS)':
 'VSS112': CDS_PINID='VSS112';
NODE_NAME     J29 259
 '@T6G_MB_LIB.T6G(SCH_1):PAGE106_I143@PURE_QUANTA.SCONN288_DDR506112002KQ(CHIPS)':
 'VSS113': CDS_PINID='VSS113';
NODE_NAME     J29 262
 '@T6G_MB_LIB.T6G(SCH_1):PAGE106_I143@PURE_QUANTA.SCONN288_DDR506112002KQ(CHIPS)':
 'VSS114': CDS_PINID='VSS114';
NODE_NAME     J29 264
 '@T6G_MB_LIB.T6G(SCH_1):PAGE106_I143@PURE_QUANTA.SCONN288_DDR506112002KQ(CHIPS)':
 'VSS115': CDS_PINID='VSS115';
NODE_NAME     J29 266
 '@T6G_MB_LIB.T6G(SCH_1):PAGE106_I143@PURE_QUANTA.SCONN288_DDR506112002KQ(CHIPS)':
 'VSS116': CDS_PINID='VSS116';
NODE_NAME     J29 268
 '@T6G_MB_LIB.T6G(SCH_1):PAGE106_I143@PURE_QUANTA.SCONN288_DDR506112002KQ(CHIPS)':
 'VSS117': CDS_PINID='VSS117';
NODE_NAME     J29 270
 '@T6G_MB_LIB.T6G(SCH_1):PAGE106_I143@PURE_QUANTA.SCONN288_DDR506112002KQ(CHIPS)':
 'VSS118': CDS_PINID='VSS118';
NODE_NAME     J29 273
 '@T6G_MB_LIB.T6G(SCH_1):PAGE106_I143@PURE_QUANTA.SCONN288_DDR506112002KQ(CHIPS)':
 'VSS119': CDS_PINID='VSS119';
NODE_NAME     J29 275
 '@T6G_MB_LIB.T6G(SCH_1):PAGE106_I143@PURE_QUANTA.SCONN288_DDR506112002KQ(CHIPS)':
 'VSS120': CDS_PINID='VSS120';
NODE_NAME     J29 277
 '@T6G_MB_LIB.T6G(SCH_1):PAGE106_I143@PURE_QUANTA.SCONN288_DDR506112002KQ(CHIPS)':
 'VSS121': CDS_PINID='VSS121';
NODE_NAME     J29 279
 '@T6G_MB_LIB.T6G(SCH_1):PAGE106_I143@PURE_QUANTA.SCONN288_DDR506112002KQ(CHIPS)':
 'VSS122': CDS_PINID='VSS122';
NODE_NAME     J29 281
 '@T6G_MB_LIB.T6G(SCH_1):PAGE106_I143@PURE_QUANTA.SCONN288_DDR506112002KQ(CHIPS)':
 'VSS123': CDS_PINID='VSS123';
NODE_NAME     J29 284
 '@T6G_MB_LIB.T6G(SCH_1):PAGE106_I143@PURE_QUANTA.SCONN288_DDR506112002KQ(CHIPS)':
 'VSS124': CDS_PINID='VSS124';
NODE_NAME     J29 286
 '@T6G_MB_LIB.T6G(SCH_1):PAGE106_I143@PURE_QUANTA.SCONN288_DDR506112002KQ(CHIPS)':
 'VSS125': CDS_PINID='VSS125';
NODE_NAME     J29 288
 '@T6G_MB_LIB.T6G(SCH_1):PAGE106_I143@PURE_QUANTA.SCONN288_DDR506112002KQ(CHIPS)':
 'VSS126': CDS_PINID='VSS126';
NODE_NAME     C172 2
 '@T6G_MB_LIB.T6G(SCH_1):PAGE106_I185@PURE_QUANTA.Q_CAP(CHIPS)':
 'B': CDS_PINID='B';
NODE_NAME     C536 2
 '@T6G_MB_LIB.T6G(SCH_1):PAGE106_I238@PURE_QUANTA.Q_CAP(CHIPS)':
 'B': CDS_PINID='B';
NODE_NAME     C537 2
 '@T6G_MB_LIB.T6G(SCH_1):PAGE106_I239@PURE_QUANTA.Q_CAP(CHIPS)':
 'B': CDS_PINID='B';
NODE_NAME     R777 2
 '@T6G_MB_LIB.T6G(SCH_1):PAGE107_I136@PURE_QUANTA.Q_RES(CHIPS)':
 'B': CDS_PINID='B';
NODE_NAME     J99 G1
 '@T6G_MB_LIB.T6G(SCH_1):PAGE107_I139@PURE_QUANTA.SCONN288_DDR506112002KQ(CHIPS)':
 'G1': CDS_PINID='G1';
NODE_NAME     J99 G2
 '@T6G_MB_LIB.T6G(SCH_1):PAGE107_I139@PURE_QUANTA.SCONN288_DDR506112002KQ(CHIPS)':
 'G2': CDS_PINID='G2';
NODE_NAME     J99 G3
 '@T6G_MB_LIB.T6G(SCH_1):PAGE107_I139@PURE_QUANTA.SCONN288_DDR506112002KQ(CHIPS)':
 'G3': CDS_PINID='G3';
NODE_NAME     J99 6
 '@T6G_MB_LIB.T6G(SCH_1):PAGE107_I139@PURE_QUANTA.SCONN288_DDR506112002KQ(CHIPS)':
 'VSS0': CDS_PINID='VSS0';
NODE_NAME     J99 8
 '@T6G_MB_LIB.T6G(SCH_1):PAGE107_I139@PURE_QUANTA.SCONN288_DDR506112002KQ(CHIPS)':
 'VSS1': CDS_PINID='VSS1';
NODE_NAME     J99 10
 '@T6G_MB_LIB.T6G(SCH_1):PAGE107_I139@PURE_QUANTA.SCONN288_DDR506112002KQ(CHIPS)':
 'VSS2': CDS_PINID='VSS2';
NODE_NAME     J99 13
 '@T6G_MB_LIB.T6G(SCH_1):PAGE107_I139@PURE_QUANTA.SCONN288_DDR506112002KQ(CHIPS)':
 'VSS3': CDS_PINID='VSS3';
NODE_NAME     J99 15
 '@T6G_MB_LIB.T6G(SCH_1):PAGE107_I139@PURE_QUANTA.SCONN288_DDR506112002KQ(CHIPS)':
 'VSS4': CDS_PINID='VSS4';
NODE_NAME     J99 17
 '@T6G_MB_LIB.T6G(SCH_1):PAGE107_I139@PURE_QUANTA.SCONN288_DDR506112002KQ(CHIPS)':
 'VSS5': CDS_PINID='VSS5';
NODE_NAME     J99 19
 '@T6G_MB_LIB.T6G(SCH_1):PAGE107_I139@PURE_QUANTA.SCONN288_DDR506112002KQ(CHIPS)':
 'VSS6': CDS_PINID='VSS6';
NODE_NAME     J99 21
 '@T6G_MB_LIB.T6G(SCH_1):PAGE107_I139@PURE_QUANTA.SCONN288_DDR506112002KQ(CHIPS)':
 'VSS7': CDS_PINID='VSS7';
NODE_NAME     J99 24
 '@T6G_MB_LIB.T6G(SCH_1):PAGE107_I139@PURE_QUANTA.SCONN288_DDR506112002KQ(CHIPS)':
 'VSS8': CDS_PINID='VSS8';
NODE_NAME     J99 26
 '@T6G_MB_LIB.T6G(SCH_1):PAGE107_I139@PURE_QUANTA.SCONN288_DDR506112002KQ(CHIPS)':
 'VSS9': CDS_PINID='VSS9';
NODE_NAME     J99 28
 '@T6G_MB_LIB.T6G(SCH_1):PAGE107_I139@PURE_QUANTA.SCONN288_DDR506112002KQ(CHIPS)':
 'VSS10': CDS_PINID='VSS10';
NODE_NAME     J99 30
 '@T6G_MB_LIB.T6G(SCH_1):PAGE107_I139@PURE_QUANTA.SCONN288_DDR506112002KQ(CHIPS)':
 'VSS11': CDS_PINID='VSS11';
NODE_NAME     J99 32
 '@T6G_MB_LIB.T6G(SCH_1):PAGE107_I139@PURE_QUANTA.SCONN288_DDR506112002KQ(CHIPS)':
 'VSS12': CDS_PINID='VSS12';
NODE_NAME     J99 35
 '@T6G_MB_LIB.T6G(SCH_1):PAGE107_I139@PURE_QUANTA.SCONN288_DDR506112002KQ(CHIPS)':
 'VSS13': CDS_PINID='VSS13';
NODE_NAME     J99 37
 '@T6G_MB_LIB.T6G(SCH_1):PAGE107_I139@PURE_QUANTA.SCONN288_DDR506112002KQ(CHIPS)':
 'VSS14': CDS_PINID='VSS14';
NODE_NAME     J99 39
 '@T6G_MB_LIB.T6G(SCH_1):PAGE107_I139@PURE_QUANTA.SCONN288_DDR506112002KQ(CHIPS)':
 'VSS15': CDS_PINID='VSS15';
NODE_NAME     J99 41
 '@T6G_MB_LIB.T6G(SCH_1):PAGE107_I139@PURE_QUANTA.SCONN288_DDR506112002KQ(CHIPS)':
 'VSS16': CDS_PINID='VSS16';
NODE_NAME     J99 43
 '@T6G_MB_LIB.T6G(SCH_1):PAGE107_I139@PURE_QUANTA.SCONN288_DDR506112002KQ(CHIPS)':
 'VSS17': CDS_PINID='VSS17';
NODE_NAME     J99 46
 '@T6G_MB_LIB.T6G(SCH_1):PAGE107_I139@PURE_QUANTA.SCONN288_DDR506112002KQ(CHIPS)':
 'VSS18': CDS_PINID='VSS18';
NODE_NAME     J99 48
 '@T6G_MB_LIB.T6G(SCH_1):PAGE107_I139@PURE_QUANTA.SCONN288_DDR506112002KQ(CHIPS)':
 'VSS19': CDS_PINID='VSS19';
NODE_NAME     J99 50
 '@T6G_MB_LIB.T6G(SCH_1):PAGE107_I139@PURE_QUANTA.SCONN288_DDR506112002KQ(CHIPS)':
 'VSS20': CDS_PINID='VSS20';
NODE_NAME     J99 52
 '@T6G_MB_LIB.T6G(SCH_1):PAGE107_I139@PURE_QUANTA.SCONN288_DDR506112002KQ(CHIPS)':
 'VSS21': CDS_PINID='VSS21';
NODE_NAME     J99 54
 '@T6G_MB_LIB.T6G(SCH_1):PAGE107_I139@PURE_QUANTA.SCONN288_DDR506112002KQ(CHIPS)':
 'VSS22': CDS_PINID='VSS22';
NODE_NAME     J99 57
 '@T6G_MB_LIB.T6G(SCH_1):PAGE107_I139@PURE_QUANTA.SCONN288_DDR506112002KQ(CHIPS)':
 'VSS23': CDS_PINID='VSS23';
NODE_NAME     J99 59
 '@T6G_MB_LIB.T6G(SCH_1):PAGE107_I139@PURE_QUANTA.SCONN288_DDR506112002KQ(CHIPS)':
 'VSS24': CDS_PINID='VSS24';
NODE_NAME     J99 61
 '@T6G_MB_LIB.T6G(SCH_1):PAGE107_I139@PURE_QUANTA.SCONN288_DDR506112002KQ(CHIPS)':
 'VSS25': CDS_PINID='VSS25';
NODE_NAME     J99 63
 '@T6G_MB_LIB.T6G(SCH_1):PAGE107_I139@PURE_QUANTA.SCONN288_DDR506112002KQ(CHIPS)':
 'VSS26': CDS_PINID='VSS26';
NODE_NAME     J99 65
 '@T6G_MB_LIB.T6G(SCH_1):PAGE107_I139@PURE_QUANTA.SCONN288_DDR506112002KQ(CHIPS)':
 'VSS27': CDS_PINID='VSS27';
NODE_NAME     J99 67
 '@T6G_MB_LIB.T6G(SCH_1):PAGE107_I139@PURE_QUANTA.SCONN288_DDR506112002KQ(CHIPS)':
 'VSS28': CDS_PINID='VSS28';
NODE_NAME     J99 69
 '@T6G_MB_LIB.T6G(SCH_1):PAGE107_I139@PURE_QUANTA.SCONN288_DDR506112002KQ(CHIPS)':
 'VSS29': CDS_PINID='VSS29';
NODE_NAME     J99 71
 '@T6G_MB_LIB.T6G(SCH_1):PAGE107_I139@PURE_QUANTA.SCONN288_DDR506112002KQ(CHIPS)':
 'VSS30': CDS_PINID='VSS30';
NODE_NAME     J99 73
 '@T6G_MB_LIB.T6G(SCH_1):PAGE107_I139@PURE_QUANTA.SCONN288_DDR506112002KQ(CHIPS)':
 'VSS31': CDS_PINID='VSS31';
NODE_NAME     J99 75
 '@T6G_MB_LIB.T6G(SCH_1):PAGE107_I139@PURE_QUANTA.SCONN288_DDR506112002KQ(CHIPS)':
 'VSS32': CDS_PINID='VSS32';
NODE_NAME     J99 77
 '@T6G_MB_LIB.T6G(SCH_1):PAGE107_I139@PURE_QUANTA.SCONN288_DDR506112002KQ(CHIPS)':
 'VSS33': CDS_PINID='VSS33';
NODE_NAME     J99 79
 '@T6G_MB_LIB.T6G(SCH_1):PAGE107_I139@PURE_QUANTA.SCONN288_DDR506112002KQ(CHIPS)':
 'VSS34': CDS_PINID='VSS34';
NODE_NAME     J99 81
 '@T6G_MB_LIB.T6G(SCH_1):PAGE107_I139@PURE_QUANTA.SCONN288_DDR506112002KQ(CHIPS)':
 'VSS35': CDS_PINID='VSS35';
NODE_NAME     J99 83
 '@T6G_MB_LIB.T6G(SCH_1):PAGE107_I139@PURE_QUANTA.SCONN288_DDR506112002KQ(CHIPS)':
 'VSS36': CDS_PINID='VSS36';
NODE_NAME     J99 85
 '@T6G_MB_LIB.T6G(SCH_1):PAGE107_I139@PURE_QUANTA.SCONN288_DDR506112002KQ(CHIPS)':
 'VSS37': CDS_PINID='VSS37';
NODE_NAME     J99 88
 '@T6G_MB_LIB.T6G(SCH_1):PAGE107_I139@PURE_QUANTA.SCONN288_DDR506112002KQ(CHIPS)':
 'VSS38': CDS_PINID='VSS38';
NODE_NAME     J99 90
 '@T6G_MB_LIB.T6G(SCH_1):PAGE107_I139@PURE_QUANTA.SCONN288_DDR506112002KQ(CHIPS)':
 'VSS39': CDS_PINID='VSS39';
NODE_NAME     J99 92
 '@T6G_MB_LIB.T6G(SCH_1):PAGE107_I139@PURE_QUANTA.SCONN288_DDR506112002KQ(CHIPS)':
 'VSS40': CDS_PINID='VSS40';
NODE_NAME     J99 95
 '@T6G_MB_LIB.T6G(SCH_1):PAGE107_I139@PURE_QUANTA.SCONN288_DDR506112002KQ(CHIPS)':
 'VSS41': CDS_PINID='VSS41';
NODE_NAME     J99 97
 '@T6G_MB_LIB.T6G(SCH_1):PAGE107_I139@PURE_QUANTA.SCONN288_DDR506112002KQ(CHIPS)':
 'VSS42': CDS_PINID='VSS42';
NODE_NAME     J99 99
 '@T6G_MB_LIB.T6G(SCH_1):PAGE107_I139@PURE_QUANTA.SCONN288_DDR506112002KQ(CHIPS)':
 'VSS43': CDS_PINID='VSS43';
NODE_NAME     J99 101
 '@T6G_MB_LIB.T6G(SCH_1):PAGE107_I139@PURE_QUANTA.SCONN288_DDR506112002KQ(CHIPS)':
 'VSS44': CDS_PINID='VSS44';
NODE_NAME     J99 103
 '@T6G_MB_LIB.T6G(SCH_1):PAGE107_I139@PURE_QUANTA.SCONN288_DDR506112002KQ(CHIPS)':
 'VSS45': CDS_PINID='VSS45';
NODE_NAME     J99 106
 '@T6G_MB_LIB.T6G(SCH_1):PAGE107_I139@PURE_QUANTA.SCONN288_DDR506112002KQ(CHIPS)':
 'VSS46': CDS_PINID='VSS46';
NODE_NAME     J99 108
 '@T6G_MB_LIB.T6G(SCH_1):PAGE107_I139@PURE_QUANTA.SCONN288_DDR506112002KQ(CHIPS)':
 'VSS47': CDS_PINID='VSS47';
NODE_NAME     J99 110
 '@T6G_MB_LIB.T6G(SCH_1):PAGE107_I139@PURE_QUANTA.SCONN288_DDR506112002KQ(CHIPS)':
 'VSS48': CDS_PINID='VSS48';
NODE_NAME     J99 112
 '@T6G_MB_LIB.T6G(SCH_1):PAGE107_I139@PURE_QUANTA.SCONN288_DDR506112002KQ(CHIPS)':
 'VSS49': CDS_PINID='VSS49';
NODE_NAME     J99 114
 '@T6G_MB_LIB.T6G(SCH_1):PAGE107_I139@PURE_QUANTA.SCONN288_DDR506112002KQ(CHIPS)':
 'VSS50': CDS_PINID='VSS50';
NODE_NAME     J99 117
 '@T6G_MB_LIB.T6G(SCH_1):PAGE107_I139@PURE_QUANTA.SCONN288_DDR506112002KQ(CHIPS)':
 'VSS51': CDS_PINID='VSS51';
NODE_NAME     J99 119
 '@T6G_MB_LIB.T6G(SCH_1):PAGE107_I139@PURE_QUANTA.SCONN288_DDR506112002KQ(CHIPS)':
 'VSS52': CDS_PINID='VSS52';
NODE_NAME     J99 121
 '@T6G_MB_LIB.T6G(SCH_1):PAGE107_I139@PURE_QUANTA.SCONN288_DDR506112002KQ(CHIPS)':
 'VSS53': CDS_PINID='VSS53';
NODE_NAME     J99 123
 '@T6G_MB_LIB.T6G(SCH_1):PAGE107_I139@PURE_QUANTA.SCONN288_DDR506112002KQ(CHIPS)':
 'VSS54': CDS_PINID='VSS54';
NODE_NAME     J99 125
 '@T6G_MB_LIB.T6G(SCH_1):PAGE107_I139@PURE_QUANTA.SCONN288_DDR506112002KQ(CHIPS)':
 'VSS55': CDS_PINID='VSS55';
NODE_NAME     J99 128
 '@T6G_MB_LIB.T6G(SCH_1):PAGE107_I139@PURE_QUANTA.SCONN288_DDR506112002KQ(CHIPS)':
 'VSS56': CDS_PINID='VSS56';
NODE_NAME     J99 130
 '@T6G_MB_LIB.T6G(SCH_1):PAGE107_I139@PURE_QUANTA.SCONN288_DDR506112002KQ(CHIPS)':
 'VSS57': CDS_PINID='VSS57';
NODE_NAME     J99 132
 '@T6G_MB_LIB.T6G(SCH_1):PAGE107_I139@PURE_QUANTA.SCONN288_DDR506112002KQ(CHIPS)':
 'VSS58': CDS_PINID='VSS58';
NODE_NAME     J99 134
 '@T6G_MB_LIB.T6G(SCH_1):PAGE107_I139@PURE_QUANTA.SCONN288_DDR506112002KQ(CHIPS)':
 'VSS59': CDS_PINID='VSS59';
NODE_NAME     J99 136
 '@T6G_MB_LIB.T6G(SCH_1):PAGE107_I139@PURE_QUANTA.SCONN288_DDR506112002KQ(CHIPS)':
 'VSS60': CDS_PINID='VSS60';
NODE_NAME     J99 139
 '@T6G_MB_LIB.T6G(SCH_1):PAGE107_I139@PURE_QUANTA.SCONN288_DDR506112002KQ(CHIPS)':
 'VSS61': CDS_PINID='VSS61';
NODE_NAME     J99 141
 '@T6G_MB_LIB.T6G(SCH_1):PAGE107_I139@PURE_QUANTA.SCONN288_DDR506112002KQ(CHIPS)':
 'VSS62': CDS_PINID='VSS62';
NODE_NAME     J99 143
 '@T6G_MB_LIB.T6G(SCH_1):PAGE107_I139@PURE_QUANTA.SCONN288_DDR506112002KQ(CHIPS)':
 'VSS63': CDS_PINID='VSS63';
NODE_NAME     J99 151
 '@T6G_MB_LIB.T6G(SCH_1):PAGE107_I139@PURE_QUANTA.SCONN288_DDR506112002KQ(CHIPS)':
 'VSS64': CDS_PINID='VSS64';
NODE_NAME     J99 153
 '@T6G_MB_LIB.T6G(SCH_1):PAGE107_I139@PURE_QUANTA.SCONN288_DDR506112002KQ(CHIPS)':
 'VSS65': CDS_PINID='VSS65';
NODE_NAME     J99 155
 '@T6G_MB_LIB.T6G(SCH_1):PAGE107_I139@PURE_QUANTA.SCONN288_DDR506112002KQ(CHIPS)':
 'VSS66': CDS_PINID='VSS66';
NODE_NAME     J99 158
 '@T6G_MB_LIB.T6G(SCH_1):PAGE107_I139@PURE_QUANTA.SCONN288_DDR506112002KQ(CHIPS)':
 'VSS67': CDS_PINID='VSS67';
NODE_NAME     J99 160
 '@T6G_MB_LIB.T6G(SCH_1):PAGE107_I139@PURE_QUANTA.SCONN288_DDR506112002KQ(CHIPS)':
 'VSS68': CDS_PINID='VSS68';
NODE_NAME     J99 162
 '@T6G_MB_LIB.T6G(SCH_1):PAGE107_I139@PURE_QUANTA.SCONN288_DDR506112002KQ(CHIPS)':
 'VSS69': CDS_PINID='VSS69';
NODE_NAME     J99 164
 '@T6G_MB_LIB.T6G(SCH_1):PAGE107_I139@PURE_QUANTA.SCONN288_DDR506112002KQ(CHIPS)':
 'VSS70': CDS_PINID='VSS70';
NODE_NAME     J99 166
 '@T6G_MB_LIB.T6G(SCH_1):PAGE107_I139@PURE_QUANTA.SCONN288_DDR506112002KQ(CHIPS)':
 'VSS71': CDS_PINID='VSS71';
NODE_NAME     J99 169
 '@T6G_MB_LIB.T6G(SCH_1):PAGE107_I139@PURE_QUANTA.SCONN288_DDR506112002KQ(CHIPS)':
 'VSS72': CDS_PINID='VSS72';
NODE_NAME     J99 171
 '@T6G_MB_LIB.T6G(SCH_1):PAGE107_I139@PURE_QUANTA.SCONN288_DDR506112002KQ(CHIPS)':
 'VSS73': CDS_PINID='VSS73';
NODE_NAME     J99 173
 '@T6G_MB_LIB.T6G(SCH_1):PAGE107_I139@PURE_QUANTA.SCONN288_DDR506112002KQ(CHIPS)':
 'VSS74': CDS_PINID='VSS74';
NODE_NAME     J99 175
 '@T6G_MB_LIB.T6G(SCH_1):PAGE107_I139@PURE_QUANTA.SCONN288_DDR506112002KQ(CHIPS)':
 'VSS75': CDS_PINID='VSS75';
NODE_NAME     J99 177
 '@T6G_MB_LIB.T6G(SCH_1):PAGE107_I139@PURE_QUANTA.SCONN288_DDR506112002KQ(CHIPS)':
 'VSS76': CDS_PINID='VSS76';
NODE_NAME     J99 180
 '@T6G_MB_LIB.T6G(SCH_1):PAGE107_I139@PURE_QUANTA.SCONN288_DDR506112002KQ(CHIPS)':
 'VSS77': CDS_PINID='VSS77';
NODE_NAME     J99 182
 '@T6G_MB_LIB.T6G(SCH_1):PAGE107_I139@PURE_QUANTA.SCONN288_DDR506112002KQ(CHIPS)':
 'VSS78': CDS_PINID='VSS78';
NODE_NAME     J99 184
 '@T6G_MB_LIB.T6G(SCH_1):PAGE107_I139@PURE_QUANTA.SCONN288_DDR506112002KQ(CHIPS)':
 'VSS79': CDS_PINID='VSS79';
NODE_NAME     J99 186
 '@T6G_MB_LIB.T6G(SCH_1):PAGE107_I139@PURE_QUANTA.SCONN288_DDR506112002KQ(CHIPS)':
 'VSS80': CDS_PINID='VSS80';
NODE_NAME     J99 188
 '@T6G_MB_LIB.T6G(SCH_1):PAGE107_I139@PURE_QUANTA.SCONN288_DDR506112002KQ(CHIPS)':
 'VSS81': CDS_PINID='VSS81';
NODE_NAME     J99 191
 '@T6G_MB_LIB.T6G(SCH_1):PAGE107_I139@PURE_QUANTA.SCONN288_DDR506112002KQ(CHIPS)':
 'VSS82': CDS_PINID='VSS82';
NODE_NAME     J99 193
 '@T6G_MB_LIB.T6G(SCH_1):PAGE107_I139@PURE_QUANTA.SCONN288_DDR506112002KQ(CHIPS)':
 'VSS83': CDS_PINID='VSS83';
NODE_NAME     J99 195
 '@T6G_MB_LIB.T6G(SCH_1):PAGE107_I139@PURE_QUANTA.SCONN288_DDR506112002KQ(CHIPS)':
 'VSS84': CDS_PINID='VSS84';
NODE_NAME     J99 197
 '@T6G_MB_LIB.T6G(SCH_1):PAGE107_I139@PURE_QUANTA.SCONN288_DDR506112002KQ(CHIPS)':
 'VSS85': CDS_PINID='VSS85';
NODE_NAME     J99 199
 '@T6G_MB_LIB.T6G(SCH_1):PAGE107_I139@PURE_QUANTA.SCONN288_DDR506112002KQ(CHIPS)':
 'VSS86': CDS_PINID='VSS86';
NODE_NAME     J99 202
 '@T6G_MB_LIB.T6G(SCH_1):PAGE107_I139@PURE_QUANTA.SCONN288_DDR506112002KQ(CHIPS)':
 'VSS87': CDS_PINID='VSS87';
NODE_NAME     J99 204
 '@T6G_MB_LIB.T6G(SCH_1):PAGE107_I139@PURE_QUANTA.SCONN288_DDR506112002KQ(CHIPS)':
 'VSS88': CDS_PINID='VSS88';
NODE_NAME     J99 206
 '@T6G_MB_LIB.T6G(SCH_1):PAGE107_I139@PURE_QUANTA.SCONN288_DDR506112002KQ(CHIPS)':
 'VSS89': CDS_PINID='VSS89';
NODE_NAME     J99 208
 '@T6G_MB_LIB.T6G(SCH_1):PAGE107_I139@PURE_QUANTA.SCONN288_DDR506112002KQ(CHIPS)':
 'VSS90': CDS_PINID='VSS90';
NODE_NAME     J99 210
 '@T6G_MB_LIB.T6G(SCH_1):PAGE107_I139@PURE_QUANTA.SCONN288_DDR506112002KQ(CHIPS)':
 'VSS91': CDS_PINID='VSS91';
NODE_NAME     J99 212
 '@T6G_MB_LIB.T6G(SCH_1):PAGE107_I139@PURE_QUANTA.SCONN288_DDR506112002KQ(CHIPS)':
 'VSS92': CDS_PINID='VSS92';
NODE_NAME     J99 214
 '@T6G_MB_LIB.T6G(SCH_1):PAGE107_I139@PURE_QUANTA.SCONN288_DDR506112002KQ(CHIPS)':
 'VSS93': CDS_PINID='VSS93';
NODE_NAME     J99 216
 '@T6G_MB_LIB.T6G(SCH_1):PAGE107_I139@PURE_QUANTA.SCONN288_DDR506112002KQ(CHIPS)':
 'VSS94': CDS_PINID='VSS94';
NODE_NAME     J99 219
 '@T6G_MB_LIB.T6G(SCH_1):PAGE107_I139@PURE_QUANTA.SCONN288_DDR506112002KQ(CHIPS)':
 'VSS95': CDS_PINID='VSS95';
NODE_NAME     J99 222
 '@T6G_MB_LIB.T6G(SCH_1):PAGE107_I139@PURE_QUANTA.SCONN288_DDR506112002KQ(CHIPS)':
 'VSS96': CDS_PINID='VSS96';
NODE_NAME     J99 224
 '@T6G_MB_LIB.T6G(SCH_1):PAGE107_I139@PURE_QUANTA.SCONN288_DDR506112002KQ(CHIPS)':
 'VSS97': CDS_PINID='VSS97';
NODE_NAME     J99 226
 '@T6G_MB_LIB.T6G(SCH_1):PAGE107_I139@PURE_QUANTA.SCONN288_DDR506112002KQ(CHIPS)':
 'VSS98': CDS_PINID='VSS98';
NODE_NAME     J99 228
 '@T6G_MB_LIB.T6G(SCH_1):PAGE107_I139@PURE_QUANTA.SCONN288_DDR506112002KQ(CHIPS)':
 'VSS99': CDS_PINID='VSS99';
NODE_NAME     J99 230
 '@T6G_MB_LIB.T6G(SCH_1):PAGE107_I139@PURE_QUANTA.SCONN288_DDR506112002KQ(CHIPS)':
 'VSS100': CDS_PINID='VSS100';
NODE_NAME     J99 233
 '@T6G_MB_LIB.T6G(SCH_1):PAGE107_I139@PURE_QUANTA.SCONN288_DDR506112002KQ(CHIPS)':
 'VSS101': CDS_PINID='VSS101';
NODE_NAME     J99 235
 '@T6G_MB_LIB.T6G(SCH_1):PAGE107_I139@PURE_QUANTA.SCONN288_DDR506112002KQ(CHIPS)':
 'VSS102': CDS_PINID='VSS102';
NODE_NAME     J99 237
 '@T6G_MB_LIB.T6G(SCH_1):PAGE107_I139@PURE_QUANTA.SCONN288_DDR506112002KQ(CHIPS)':
 'VSS103': CDS_PINID='VSS103';
NODE_NAME     J99 240
 '@T6G_MB_LIB.T6G(SCH_1):PAGE107_I139@PURE_QUANTA.SCONN288_DDR506112002KQ(CHIPS)':
 'VSS104': CDS_PINID='VSS104';
NODE_NAME     J99 242
 '@T6G_MB_LIB.T6G(SCH_1):PAGE107_I139@PURE_QUANTA.SCONN288_DDR506112002KQ(CHIPS)':
 'VSS105': CDS_PINID='VSS105';
NODE_NAME     J99 244
 '@T6G_MB_LIB.T6G(SCH_1):PAGE107_I139@PURE_QUANTA.SCONN288_DDR506112002KQ(CHIPS)':
 'VSS106': CDS_PINID='VSS106';
NODE_NAME     J99 246
 '@T6G_MB_LIB.T6G(SCH_1):PAGE107_I139@PURE_QUANTA.SCONN288_DDR506112002KQ(CHIPS)':
 'VSS107': CDS_PINID='VSS107';
NODE_NAME     J99 248
 '@T6G_MB_LIB.T6G(SCH_1):PAGE107_I139@PURE_QUANTA.SCONN288_DDR506112002KQ(CHIPS)':
 'VSS108': CDS_PINID='VSS108';
NODE_NAME     J99 251
 '@T6G_MB_LIB.T6G(SCH_1):PAGE107_I139@PURE_QUANTA.SCONN288_DDR506112002KQ(CHIPS)':
 'VSS109': CDS_PINID='VSS109';
NODE_NAME     J99 253
 '@T6G_MB_LIB.T6G(SCH_1):PAGE107_I139@PURE_QUANTA.SCONN288_DDR506112002KQ(CHIPS)':
 'VSS110': CDS_PINID='VSS110';
NODE_NAME     J99 255
 '@T6G_MB_LIB.T6G(SCH_1):PAGE107_I139@PURE_QUANTA.SCONN288_DDR506112002KQ(CHIPS)':
 'VSS111': CDS_PINID='VSS111';
NODE_NAME     J99 257
 '@T6G_MB_LIB.T6G(SCH_1):PAGE107_I139@PURE_QUANTA.SCONN288_DDR506112002KQ(CHIPS)':
 'VSS112': CDS_PINID='VSS112';
NODE_NAME     J99 259
 '@T6G_MB_LIB.T6G(SCH_1):PAGE107_I139@PURE_QUANTA.SCONN288_DDR506112002KQ(CHIPS)':
 'VSS113': CDS_PINID='VSS113';
NODE_NAME     J99 262
 '@T6G_MB_LIB.T6G(SCH_1):PAGE107_I139@PURE_QUANTA.SCONN288_DDR506112002KQ(CHIPS)':
 'VSS114': CDS_PINID='VSS114';
NODE_NAME     J99 264
 '@T6G_MB_LIB.T6G(SCH_1):PAGE107_I139@PURE_QUANTA.SCONN288_DDR506112002KQ(CHIPS)':
 'VSS115': CDS_PINID='VSS115';
NODE_NAME     J99 266
 '@T6G_MB_LIB.T6G(SCH_1):PAGE107_I139@PURE_QUANTA.SCONN288_DDR506112002KQ(CHIPS)':
 'VSS116': CDS_PINID='VSS116';
NODE_NAME     J99 268
 '@T6G_MB_LIB.T6G(SCH_1):PAGE107_I139@PURE_QUANTA.SCONN288_DDR506112002KQ(CHIPS)':
 'VSS117': CDS_PINID='VSS117';
NODE_NAME     J99 270
 '@T6G_MB_LIB.T6G(SCH_1):PAGE107_I139@PURE_QUANTA.SCONN288_DDR506112002KQ(CHIPS)':
 'VSS118': CDS_PINID='VSS118';
NODE_NAME     J99 273
 '@T6G_MB_LIB.T6G(SCH_1):PAGE107_I139@PURE_QUANTA.SCONN288_DDR506112002KQ(CHIPS)':
 'VSS119': CDS_PINID='VSS119';
NODE_NAME     J99 275
 '@T6G_MB_LIB.T6G(SCH_1):PAGE107_I139@PURE_QUANTA.SCONN288_DDR506112002KQ(CHIPS)':
 'VSS120': CDS_PINID='VSS120';
NODE_NAME     J99 277
 '@T6G_MB_LIB.T6G(SCH_1):PAGE107_I139@PURE_QUANTA.SCONN288_DDR506112002KQ(CHIPS)':
 'VSS121': CDS_PINID='VSS121';
NODE_NAME     J99 279
 '@T6G_MB_LIB.T6G(SCH_1):PAGE107_I139@PURE_QUANTA.SCONN288_DDR506112002KQ(CHIPS)':
 'VSS122': CDS_PINID='VSS122';
NODE_NAME     J99 281
 '@T6G_MB_LIB.T6G(SCH_1):PAGE107_I139@PURE_QUANTA.SCONN288_DDR506112002KQ(CHIPS)':
 'VSS123': CDS_PINID='VSS123';
NODE_NAME     J99 284
 '@T6G_MB_LIB.T6G(SCH_1):PAGE107_I139@PURE_QUANTA.SCONN288_DDR506112002KQ(CHIPS)':
 'VSS124': CDS_PINID='VSS124';
NODE_NAME     J99 286
 '@T6G_MB_LIB.T6G(SCH_1):PAGE107_I139@PURE_QUANTA.SCONN288_DDR506112002KQ(CHIPS)':
 'VSS125': CDS_PINID='VSS125';
NODE_NAME     J99 288
 '@T6G_MB_LIB.T6G(SCH_1):PAGE107_I139@PURE_QUANTA.SCONN288_DDR506112002KQ(CHIPS)':
 'VSS126': CDS_PINID='VSS126';
NODE_NAME     C176 2
 '@T6G_MB_LIB.T6G(SCH_1):PAGE107_I185@PURE_QUANTA.Q_CAP(CHIPS)':
 'B': CDS_PINID='B';
NODE_NAME     C546 2
 '@T6G_MB_LIB.T6G(SCH_1):PAGE107_I237@PURE_QUANTA.Q_CAP(CHIPS)':
 'B': CDS_PINID='B';
NODE_NAME     C547 2
 '@T6G_MB_LIB.T6G(SCH_1):PAGE107_I238@PURE_QUANTA.Q_CAP(CHIPS)':
 'B': CDS_PINID='B';
NODE_NAME     R778 2
 '@T6G_MB_LIB.T6G(SCH_1):PAGE108_I136@PURE_QUANTA.Q_RES(CHIPS)':
 'B': CDS_PINID='B';
NODE_NAME     J37 G1
 '@T6G_MB_LIB.T6G(SCH_1):PAGE108_I138@PURE_QUANTA.SCONN288_DDR506112002KQ(CHIPS)':
 'G1': CDS_PINID='G1';
NODE_NAME     J37 G2
 '@T6G_MB_LIB.T6G(SCH_1):PAGE108_I138@PURE_QUANTA.SCONN288_DDR506112002KQ(CHIPS)':
 'G2': CDS_PINID='G2';
NODE_NAME     J37 G3
 '@T6G_MB_LIB.T6G(SCH_1):PAGE108_I138@PURE_QUANTA.SCONN288_DDR506112002KQ(CHIPS)':
 'G3': CDS_PINID='G3';
NODE_NAME     J37 6
 '@T6G_MB_LIB.T6G(SCH_1):PAGE108_I138@PURE_QUANTA.SCONN288_DDR506112002KQ(CHIPS)':
 'VSS0': CDS_PINID='VSS0';
NODE_NAME     J37 8
 '@T6G_MB_LIB.T6G(SCH_1):PAGE108_I138@PURE_QUANTA.SCONN288_DDR506112002KQ(CHIPS)':
 'VSS1': CDS_PINID='VSS1';
NODE_NAME     J37 10
 '@T6G_MB_LIB.T6G(SCH_1):PAGE108_I138@PURE_QUANTA.SCONN288_DDR506112002KQ(CHIPS)':
 'VSS2': CDS_PINID='VSS2';
NODE_NAME     J37 13
 '@T6G_MB_LIB.T6G(SCH_1):PAGE108_I138@PURE_QUANTA.SCONN288_DDR506112002KQ(CHIPS)':
 'VSS3': CDS_PINID='VSS3';
NODE_NAME     J37 15
 '@T6G_MB_LIB.T6G(SCH_1):PAGE108_I138@PURE_QUANTA.SCONN288_DDR506112002KQ(CHIPS)':
 'VSS4': CDS_PINID='VSS4';
NODE_NAME     J37 17
 '@T6G_MB_LIB.T6G(SCH_1):PAGE108_I138@PURE_QUANTA.SCONN288_DDR506112002KQ(CHIPS)':
 'VSS5': CDS_PINID='VSS5';
NODE_NAME     J37 19
 '@T6G_MB_LIB.T6G(SCH_1):PAGE108_I138@PURE_QUANTA.SCONN288_DDR506112002KQ(CHIPS)':
 'VSS6': CDS_PINID='VSS6';
NODE_NAME     J37 21
 '@T6G_MB_LIB.T6G(SCH_1):PAGE108_I138@PURE_QUANTA.SCONN288_DDR506112002KQ(CHIPS)':
 'VSS7': CDS_PINID='VSS7';
NODE_NAME     J37 24
 '@T6G_MB_LIB.T6G(SCH_1):PAGE108_I138@PURE_QUANTA.SCONN288_DDR506112002KQ(CHIPS)':
 'VSS8': CDS_PINID='VSS8';
NODE_NAME     J37 26
 '@T6G_MB_LIB.T6G(SCH_1):PAGE108_I138@PURE_QUANTA.SCONN288_DDR506112002KQ(CHIPS)':
 'VSS9': CDS_PINID='VSS9';
NODE_NAME     J37 28
 '@T6G_MB_LIB.T6G(SCH_1):PAGE108_I138@PURE_QUANTA.SCONN288_DDR506112002KQ(CHIPS)':
 'VSS10': CDS_PINID='VSS10';
NODE_NAME     J37 30
 '@T6G_MB_LIB.T6G(SCH_1):PAGE108_I138@PURE_QUANTA.SCONN288_DDR506112002KQ(CHIPS)':
 'VSS11': CDS_PINID='VSS11';
NODE_NAME     J37 32
 '@T6G_MB_LIB.T6G(SCH_1):PAGE108_I138@PURE_QUANTA.SCONN288_DDR506112002KQ(CHIPS)':
 'VSS12': CDS_PINID='VSS12';
NODE_NAME     J37 35
 '@T6G_MB_LIB.T6G(SCH_1):PAGE108_I138@PURE_QUANTA.SCONN288_DDR506112002KQ(CHIPS)':
 'VSS13': CDS_PINID='VSS13';
NODE_NAME     J37 37
 '@T6G_MB_LIB.T6G(SCH_1):PAGE108_I138@PURE_QUANTA.SCONN288_DDR506112002KQ(CHIPS)':
 'VSS14': CDS_PINID='VSS14';
NODE_NAME     J37 39
 '@T6G_MB_LIB.T6G(SCH_1):PAGE108_I138@PURE_QUANTA.SCONN288_DDR506112002KQ(CHIPS)':
 'VSS15': CDS_PINID='VSS15';
NODE_NAME     J37 41
 '@T6G_MB_LIB.T6G(SCH_1):PAGE108_I138@PURE_QUANTA.SCONN288_DDR506112002KQ(CHIPS)':
 'VSS16': CDS_PINID='VSS16';
NODE_NAME     J37 43
 '@T6G_MB_LIB.T6G(SCH_1):PAGE108_I138@PURE_QUANTA.SCONN288_DDR506112002KQ(CHIPS)':
 'VSS17': CDS_PINID='VSS17';
NODE_NAME     J37 46
 '@T6G_MB_LIB.T6G(SCH_1):PAGE108_I138@PURE_QUANTA.SCONN288_DDR506112002KQ(CHIPS)':
 'VSS18': CDS_PINID='VSS18';
NODE_NAME     J37 48
 '@T6G_MB_LIB.T6G(SCH_1):PAGE108_I138@PURE_QUANTA.SCONN288_DDR506112002KQ(CHIPS)':
 'VSS19': CDS_PINID='VSS19';
NODE_NAME     J37 50
 '@T6G_MB_LIB.T6G(SCH_1):PAGE108_I138@PURE_QUANTA.SCONN288_DDR506112002KQ(CHIPS)':
 'VSS20': CDS_PINID='VSS20';
NODE_NAME     J37 52
 '@T6G_MB_LIB.T6G(SCH_1):PAGE108_I138@PURE_QUANTA.SCONN288_DDR506112002KQ(CHIPS)':
 'VSS21': CDS_PINID='VSS21';
NODE_NAME     J37 54
 '@T6G_MB_LIB.T6G(SCH_1):PAGE108_I138@PURE_QUANTA.SCONN288_DDR506112002KQ(CHIPS)':
 'VSS22': CDS_PINID='VSS22';
NODE_NAME     J37 57
 '@T6G_MB_LIB.T6G(SCH_1):PAGE108_I138@PURE_QUANTA.SCONN288_DDR506112002KQ(CHIPS)':
 'VSS23': CDS_PINID='VSS23';
NODE_NAME     J37 59
 '@T6G_MB_LIB.T6G(SCH_1):PAGE108_I138@PURE_QUANTA.SCONN288_DDR506112002KQ(CHIPS)':
 'VSS24': CDS_PINID='VSS24';
NODE_NAME     J37 61
 '@T6G_MB_LIB.T6G(SCH_1):PAGE108_I138@PURE_QUANTA.SCONN288_DDR506112002KQ(CHIPS)':
 'VSS25': CDS_PINID='VSS25';
NODE_NAME     J37 63
 '@T6G_MB_LIB.T6G(SCH_1):PAGE108_I138@PURE_QUANTA.SCONN288_DDR506112002KQ(CHIPS)':
 'VSS26': CDS_PINID='VSS26';
NODE_NAME     J37 65
 '@T6G_MB_LIB.T6G(SCH_1):PAGE108_I138@PURE_QUANTA.SCONN288_DDR506112002KQ(CHIPS)':
 'VSS27': CDS_PINID='VSS27';
NODE_NAME     J37 67
 '@T6G_MB_LIB.T6G(SCH_1):PAGE108_I138@PURE_QUANTA.SCONN288_DDR506112002KQ(CHIPS)':
 'VSS28': CDS_PINID='VSS28';
NODE_NAME     J37 69
 '@T6G_MB_LIB.T6G(SCH_1):PAGE108_I138@PURE_QUANTA.SCONN288_DDR506112002KQ(CHIPS)':
 'VSS29': CDS_PINID='VSS29';
NODE_NAME     J37 71
 '@T6G_MB_LIB.T6G(SCH_1):PAGE108_I138@PURE_QUANTA.SCONN288_DDR506112002KQ(CHIPS)':
 'VSS30': CDS_PINID='VSS30';
NODE_NAME     J37 73
 '@T6G_MB_LIB.T6G(SCH_1):PAGE108_I138@PURE_QUANTA.SCONN288_DDR506112002KQ(CHIPS)':
 'VSS31': CDS_PINID='VSS31';
NODE_NAME     J37 75
 '@T6G_MB_LIB.T6G(SCH_1):PAGE108_I138@PURE_QUANTA.SCONN288_DDR506112002KQ(CHIPS)':
 'VSS32': CDS_PINID='VSS32';
NODE_NAME     J37 77
 '@T6G_MB_LIB.T6G(SCH_1):PAGE108_I138@PURE_QUANTA.SCONN288_DDR506112002KQ(CHIPS)':
 'VSS33': CDS_PINID='VSS33';
NODE_NAME     J37 79
 '@T6G_MB_LIB.T6G(SCH_1):PAGE108_I138@PURE_QUANTA.SCONN288_DDR506112002KQ(CHIPS)':
 'VSS34': CDS_PINID='VSS34';
NODE_NAME     J37 81
 '@T6G_MB_LIB.T6G(SCH_1):PAGE108_I138@PURE_QUANTA.SCONN288_DDR506112002KQ(CHIPS)':
 'VSS35': CDS_PINID='VSS35';
NODE_NAME     J37 83
 '@T6G_MB_LIB.T6G(SCH_1):PAGE108_I138@PURE_QUANTA.SCONN288_DDR506112002KQ(CHIPS)':
 'VSS36': CDS_PINID='VSS36';
NODE_NAME     J37 85
 '@T6G_MB_LIB.T6G(SCH_1):PAGE108_I138@PURE_QUANTA.SCONN288_DDR506112002KQ(CHIPS)':
 'VSS37': CDS_PINID='VSS37';
NODE_NAME     J37 88
 '@T6G_MB_LIB.T6G(SCH_1):PAGE108_I138@PURE_QUANTA.SCONN288_DDR506112002KQ(CHIPS)':
 'VSS38': CDS_PINID='VSS38';
NODE_NAME     J37 90
 '@T6G_MB_LIB.T6G(SCH_1):PAGE108_I138@PURE_QUANTA.SCONN288_DDR506112002KQ(CHIPS)':
 'VSS39': CDS_PINID='VSS39';
NODE_NAME     J37 92
 '@T6G_MB_LIB.T6G(SCH_1):PAGE108_I138@PURE_QUANTA.SCONN288_DDR506112002KQ(CHIPS)':
 'VSS40': CDS_PINID='VSS40';
NODE_NAME     J37 95
 '@T6G_MB_LIB.T6G(SCH_1):PAGE108_I138@PURE_QUANTA.SCONN288_DDR506112002KQ(CHIPS)':
 'VSS41': CDS_PINID='VSS41';
NODE_NAME     J37 97
 '@T6G_MB_LIB.T6G(SCH_1):PAGE108_I138@PURE_QUANTA.SCONN288_DDR506112002KQ(CHIPS)':
 'VSS42': CDS_PINID='VSS42';
NODE_NAME     J37 99
 '@T6G_MB_LIB.T6G(SCH_1):PAGE108_I138@PURE_QUANTA.SCONN288_DDR506112002KQ(CHIPS)':
 'VSS43': CDS_PINID='VSS43';
NODE_NAME     J37 101
 '@T6G_MB_LIB.T6G(SCH_1):PAGE108_I138@PURE_QUANTA.SCONN288_DDR506112002KQ(CHIPS)':
 'VSS44': CDS_PINID='VSS44';
NODE_NAME     J37 103
 '@T6G_MB_LIB.T6G(SCH_1):PAGE108_I138@PURE_QUANTA.SCONN288_DDR506112002KQ(CHIPS)':
 'VSS45': CDS_PINID='VSS45';
NODE_NAME     J37 106
 '@T6G_MB_LIB.T6G(SCH_1):PAGE108_I138@PURE_QUANTA.SCONN288_DDR506112002KQ(CHIPS)':
 'VSS46': CDS_PINID='VSS46';
NODE_NAME     J37 108
 '@T6G_MB_LIB.T6G(SCH_1):PAGE108_I138@PURE_QUANTA.SCONN288_DDR506112002KQ(CHIPS)':
 'VSS47': CDS_PINID='VSS47';
NODE_NAME     J37 110
 '@T6G_MB_LIB.T6G(SCH_1):PAGE108_I138@PURE_QUANTA.SCONN288_DDR506112002KQ(CHIPS)':
 'VSS48': CDS_PINID='VSS48';
NODE_NAME     J37 112
 '@T6G_MB_LIB.T6G(SCH_1):PAGE108_I138@PURE_QUANTA.SCONN288_DDR506112002KQ(CHIPS)':
 'VSS49': CDS_PINID='VSS49';
NODE_NAME     J37 114
 '@T6G_MB_LIB.T6G(SCH_1):PAGE108_I138@PURE_QUANTA.SCONN288_DDR506112002KQ(CHIPS)':
 'VSS50': CDS_PINID='VSS50';
NODE_NAME     J37 117
 '@T6G_MB_LIB.T6G(SCH_1):PAGE108_I138@PURE_QUANTA.SCONN288_DDR506112002KQ(CHIPS)':
 'VSS51': CDS_PINID='VSS51';
NODE_NAME     J37 119
 '@T6G_MB_LIB.T6G(SCH_1):PAGE108_I138@PURE_QUANTA.SCONN288_DDR506112002KQ(CHIPS)':
 'VSS52': CDS_PINID='VSS52';
NODE_NAME     J37 121
 '@T6G_MB_LIB.T6G(SCH_1):PAGE108_I138@PURE_QUANTA.SCONN288_DDR506112002KQ(CHIPS)':
 'VSS53': CDS_PINID='VSS53';
NODE_NAME     J37 123
 '@T6G_MB_LIB.T6G(SCH_1):PAGE108_I138@PURE_QUANTA.SCONN288_DDR506112002KQ(CHIPS)':
 'VSS54': CDS_PINID='VSS54';
NODE_NAME     J37 125
 '@T6G_MB_LIB.T6G(SCH_1):PAGE108_I138@PURE_QUANTA.SCONN288_DDR506112002KQ(CHIPS)':
 'VSS55': CDS_PINID='VSS55';
NODE_NAME     J37 128
 '@T6G_MB_LIB.T6G(SCH_1):PAGE108_I138@PURE_QUANTA.SCONN288_DDR506112002KQ(CHIPS)':
 'VSS56': CDS_PINID='VSS56';
NODE_NAME     J37 130
 '@T6G_MB_LIB.T6G(SCH_1):PAGE108_I138@PURE_QUANTA.SCONN288_DDR506112002KQ(CHIPS)':
 'VSS57': CDS_PINID='VSS57';
NODE_NAME     J37 132
 '@T6G_MB_LIB.T6G(SCH_1):PAGE108_I138@PURE_QUANTA.SCONN288_DDR506112002KQ(CHIPS)':
 'VSS58': CDS_PINID='VSS58';
NODE_NAME     J37 134
 '@T6G_MB_LIB.T6G(SCH_1):PAGE108_I138@PURE_QUANTA.SCONN288_DDR506112002KQ(CHIPS)':
 'VSS59': CDS_PINID='VSS59';
NODE_NAME     J37 136
 '@T6G_MB_LIB.T6G(SCH_1):PAGE108_I138@PURE_QUANTA.SCONN288_DDR506112002KQ(CHIPS)':
 'VSS60': CDS_PINID='VSS60';
NODE_NAME     J37 139
 '@T6G_MB_LIB.T6G(SCH_1):PAGE108_I138@PURE_QUANTA.SCONN288_DDR506112002KQ(CHIPS)':
 'VSS61': CDS_PINID='VSS61';
NODE_NAME     J37 141
 '@T6G_MB_LIB.T6G(SCH_1):PAGE108_I138@PURE_QUANTA.SCONN288_DDR506112002KQ(CHIPS)':
 'VSS62': CDS_PINID='VSS62';
NODE_NAME     J37 143
 '@T6G_MB_LIB.T6G(SCH_1):PAGE108_I138@PURE_QUANTA.SCONN288_DDR506112002KQ(CHIPS)':
 'VSS63': CDS_PINID='VSS63';
NODE_NAME     J37 151
 '@T6G_MB_LIB.T6G(SCH_1):PAGE108_I138@PURE_QUANTA.SCONN288_DDR506112002KQ(CHIPS)':
 'VSS64': CDS_PINID='VSS64';
NODE_NAME     J37 153
 '@T6G_MB_LIB.T6G(SCH_1):PAGE108_I138@PURE_QUANTA.SCONN288_DDR506112002KQ(CHIPS)':
 'VSS65': CDS_PINID='VSS65';
NODE_NAME     J37 155
 '@T6G_MB_LIB.T6G(SCH_1):PAGE108_I138@PURE_QUANTA.SCONN288_DDR506112002KQ(CHIPS)':
 'VSS66': CDS_PINID='VSS66';
NODE_NAME     J37 158
 '@T6G_MB_LIB.T6G(SCH_1):PAGE108_I138@PURE_QUANTA.SCONN288_DDR506112002KQ(CHIPS)':
 'VSS67': CDS_PINID='VSS67';
NODE_NAME     J37 160
 '@T6G_MB_LIB.T6G(SCH_1):PAGE108_I138@PURE_QUANTA.SCONN288_DDR506112002KQ(CHIPS)':
 'VSS68': CDS_PINID='VSS68';
NODE_NAME     J37 162
 '@T6G_MB_LIB.T6G(SCH_1):PAGE108_I138@PURE_QUANTA.SCONN288_DDR506112002KQ(CHIPS)':
 'VSS69': CDS_PINID='VSS69';
NODE_NAME     J37 164
 '@T6G_MB_LIB.T6G(SCH_1):PAGE108_I138@PURE_QUANTA.SCONN288_DDR506112002KQ(CHIPS)':
 'VSS70': CDS_PINID='VSS70';
NODE_NAME     J37 166
 '@T6G_MB_LIB.T6G(SCH_1):PAGE108_I138@PURE_QUANTA.SCONN288_DDR506112002KQ(CHIPS)':
 'VSS71': CDS_PINID='VSS71';
NODE_NAME     J37 169
 '@T6G_MB_LIB.T6G(SCH_1):PAGE108_I138@PURE_QUANTA.SCONN288_DDR506112002KQ(CHIPS)':
 'VSS72': CDS_PINID='VSS72';
NODE_NAME     J37 171
 '@T6G_MB_LIB.T6G(SCH_1):PAGE108_I138@PURE_QUANTA.SCONN288_DDR506112002KQ(CHIPS)':
 'VSS73': CDS_PINID='VSS73';
NODE_NAME     J37 173
 '@T6G_MB_LIB.T6G(SCH_1):PAGE108_I138@PURE_QUANTA.SCONN288_DDR506112002KQ(CHIPS)':
 'VSS74': CDS_PINID='VSS74';
NODE_NAME     J37 175
 '@T6G_MB_LIB.T6G(SCH_1):PAGE108_I138@PURE_QUANTA.SCONN288_DDR506112002KQ(CHIPS)':
 'VSS75': CDS_PINID='VSS75';
NODE_NAME     J37 177
 '@T6G_MB_LIB.T6G(SCH_1):PAGE108_I138@PURE_QUANTA.SCONN288_DDR506112002KQ(CHIPS)':
 'VSS76': CDS_PINID='VSS76';
NODE_NAME     J37 180
 '@T6G_MB_LIB.T6G(SCH_1):PAGE108_I138@PURE_QUANTA.SCONN288_DDR506112002KQ(CHIPS)':
 'VSS77': CDS_PINID='VSS77';
NODE_NAME     J37 182
 '@T6G_MB_LIB.T6G(SCH_1):PAGE108_I138@PURE_QUANTA.SCONN288_DDR506112002KQ(CHIPS)':
 'VSS78': CDS_PINID='VSS78';
NODE_NAME     J37 184
 '@T6G_MB_LIB.T6G(SCH_1):PAGE108_I138@PURE_QUANTA.SCONN288_DDR506112002KQ(CHIPS)':
 'VSS79': CDS_PINID='VSS79';
NODE_NAME     J37 186
 '@T6G_MB_LIB.T6G(SCH_1):PAGE108_I138@PURE_QUANTA.SCONN288_DDR506112002KQ(CHIPS)':
 'VSS80': CDS_PINID='VSS80';
NODE_NAME     J37 188
 '@T6G_MB_LIB.T6G(SCH_1):PAGE108_I138@PURE_QUANTA.SCONN288_DDR506112002KQ(CHIPS)':
 'VSS81': CDS_PINID='VSS81';
NODE_NAME     J37 191
 '@T6G_MB_LIB.T6G(SCH_1):PAGE108_I138@PURE_QUANTA.SCONN288_DDR506112002KQ(CHIPS)':
 'VSS82': CDS_PINID='VSS82';
NODE_NAME     J37 193
 '@T6G_MB_LIB.T6G(SCH_1):PAGE108_I138@PURE_QUANTA.SCONN288_DDR506112002KQ(CHIPS)':
 'VSS83': CDS_PINID='VSS83';
NODE_NAME     J37 195
 '@T6G_MB_LIB.T6G(SCH_1):PAGE108_I138@PURE_QUANTA.SCONN288_DDR506112002KQ(CHIPS)':
 'VSS84': CDS_PINID='VSS84';
NODE_NAME     J37 197
 '@T6G_MB_LIB.T6G(SCH_1):PAGE108_I138@PURE_QUANTA.SCONN288_DDR506112002KQ(CHIPS)':
 'VSS85': CDS_PINID='VSS85';
NODE_NAME     J37 199
 '@T6G_MB_LIB.T6G(SCH_1):PAGE108_I138@PURE_QUANTA.SCONN288_DDR506112002KQ(CHIPS)':
 'VSS86': CDS_PINID='VSS86';
NODE_NAME     J37 202
 '@T6G_MB_LIB.T6G(SCH_1):PAGE108_I138@PURE_QUANTA.SCONN288_DDR506112002KQ(CHIPS)':
 'VSS87': CDS_PINID='VSS87';
NODE_NAME     J37 204
 '@T6G_MB_LIB.T6G(SCH_1):PAGE108_I138@PURE_QUANTA.SCONN288_DDR506112002KQ(CHIPS)':
 'VSS88': CDS_PINID='VSS88';
NODE_NAME     J37 206
 '@T6G_MB_LIB.T6G(SCH_1):PAGE108_I138@PURE_QUANTA.SCONN288_DDR506112002KQ(CHIPS)':
 'VSS89': CDS_PINID='VSS89';
NODE_NAME     J37 208
 '@T6G_MB_LIB.T6G(SCH_1):PAGE108_I138@PURE_QUANTA.SCONN288_DDR506112002KQ(CHIPS)':
 'VSS90': CDS_PINID='VSS90';
NODE_NAME     J37 210
 '@T6G_MB_LIB.T6G(SCH_1):PAGE108_I138@PURE_QUANTA.SCONN288_DDR506112002KQ(CHIPS)':
 'VSS91': CDS_PINID='VSS91';
NODE_NAME     J37 212
 '@T6G_MB_LIB.T6G(SCH_1):PAGE108_I138@PURE_QUANTA.SCONN288_DDR506112002KQ(CHIPS)':
 'VSS92': CDS_PINID='VSS92';
NODE_NAME     J37 214
 '@T6G_MB_LIB.T6G(SCH_1):PAGE108_I138@PURE_QUANTA.SCONN288_DDR506112002KQ(CHIPS)':
 'VSS93': CDS_PINID='VSS93';
NODE_NAME     J37 216
 '@T6G_MB_LIB.T6G(SCH_1):PAGE108_I138@PURE_QUANTA.SCONN288_DDR506112002KQ(CHIPS)':
 'VSS94': CDS_PINID='VSS94';
NODE_NAME     J37 219
 '@T6G_MB_LIB.T6G(SCH_1):PAGE108_I138@PURE_QUANTA.SCONN288_DDR506112002KQ(CHIPS)':
 'VSS95': CDS_PINID='VSS95';
NODE_NAME     J37 222
 '@T6G_MB_LIB.T6G(SCH_1):PAGE108_I138@PURE_QUANTA.SCONN288_DDR506112002KQ(CHIPS)':
 'VSS96': CDS_PINID='VSS96';
NODE_NAME     J37 224
 '@T6G_MB_LIB.T6G(SCH_1):PAGE108_I138@PURE_QUANTA.SCONN288_DDR506112002KQ(CHIPS)':
 'VSS97': CDS_PINID='VSS97';
NODE_NAME     J37 226
 '@T6G_MB_LIB.T6G(SCH_1):PAGE108_I138@PURE_QUANTA.SCONN288_DDR506112002KQ(CHIPS)':
 'VSS98': CDS_PINID='VSS98';
NODE_NAME     J37 228
 '@T6G_MB_LIB.T6G(SCH_1):PAGE108_I138@PURE_QUANTA.SCONN288_DDR506112002KQ(CHIPS)':
 'VSS99': CDS_PINID='VSS99';
NODE_NAME     J37 230
 '@T6G_MB_LIB.T6G(SCH_1):PAGE108_I138@PURE_QUANTA.SCONN288_DDR506112002KQ(CHIPS)':
 'VSS100': CDS_PINID='VSS100';
NODE_NAME     J37 233
 '@T6G_MB_LIB.T6G(SCH_1):PAGE108_I138@PURE_QUANTA.SCONN288_DDR506112002KQ(CHIPS)':
 'VSS101': CDS_PINID='VSS101';
NODE_NAME     J37 235
 '@T6G_MB_LIB.T6G(SCH_1):PAGE108_I138@PURE_QUANTA.SCONN288_DDR506112002KQ(CHIPS)':
 'VSS102': CDS_PINID='VSS102';
NODE_NAME     J37 237
 '@T6G_MB_LIB.T6G(SCH_1):PAGE108_I138@PURE_QUANTA.SCONN288_DDR506112002KQ(CHIPS)':
 'VSS103': CDS_PINID='VSS103';
NODE_NAME     J37 240
 '@T6G_MB_LIB.T6G(SCH_1):PAGE108_I138@PURE_QUANTA.SCONN288_DDR506112002KQ(CHIPS)':
 'VSS104': CDS_PINID='VSS104';
NODE_NAME     J37 242
 '@T6G_MB_LIB.T6G(SCH_1):PAGE108_I138@PURE_QUANTA.SCONN288_DDR506112002KQ(CHIPS)':
 'VSS105': CDS_PINID='VSS105';
NODE_NAME     J37 244
 '@T6G_MB_LIB.T6G(SCH_1):PAGE108_I138@PURE_QUANTA.SCONN288_DDR506112002KQ(CHIPS)':
 'VSS106': CDS_PINID='VSS106';
NODE_NAME     J37 246
 '@T6G_MB_LIB.T6G(SCH_1):PAGE108_I138@PURE_QUANTA.SCONN288_DDR506112002KQ(CHIPS)':
 'VSS107': CDS_PINID='VSS107';
NODE_NAME     J37 248
 '@T6G_MB_LIB.T6G(SCH_1):PAGE108_I138@PURE_QUANTA.SCONN288_DDR506112002KQ(CHIPS)':
 'VSS108': CDS_PINID='VSS108';
NODE_NAME     J37 251
 '@T6G_MB_LIB.T6G(SCH_1):PAGE108_I138@PURE_QUANTA.SCONN288_DDR506112002KQ(CHIPS)':
 'VSS109': CDS_PINID='VSS109';
NODE_NAME     J37 253
 '@T6G_MB_LIB.T6G(SCH_1):PAGE108_I138@PURE_QUANTA.SCONN288_DDR506112002KQ(CHIPS)':
 'VSS110': CDS_PINID='VSS110';
NODE_NAME     J37 255
 '@T6G_MB_LIB.T6G(SCH_1):PAGE108_I138@PURE_QUANTA.SCONN288_DDR506112002KQ(CHIPS)':
 'VSS111': CDS_PINID='VSS111';
NODE_NAME     J37 257
 '@T6G_MB_LIB.T6G(SCH_1):PAGE108_I138@PURE_QUANTA.SCONN288_DDR506112002KQ(CHIPS)':
 'VSS112': CDS_PINID='VSS112';
NODE_NAME     J37 259
 '@T6G_MB_LIB.T6G(SCH_1):PAGE108_I138@PURE_QUANTA.SCONN288_DDR506112002KQ(CHIPS)':
 'VSS113': CDS_PINID='VSS113';
NODE_NAME     J37 262
 '@T6G_MB_LIB.T6G(SCH_1):PAGE108_I138@PURE_QUANTA.SCONN288_DDR506112002KQ(CHIPS)':
 'VSS114': CDS_PINID='VSS114';
NODE_NAME     J37 264
 '@T6G_MB_LIB.T6G(SCH_1):PAGE108_I138@PURE_QUANTA.SCONN288_DDR506112002KQ(CHIPS)':
 'VSS115': CDS_PINID='VSS115';
NODE_NAME     J37 266
 '@T6G_MB_LIB.T6G(SCH_1):PAGE108_I138@PURE_QUANTA.SCONN288_DDR506112002KQ(CHIPS)':
 'VSS116': CDS_PINID='VSS116';
NODE_NAME     J37 268
 '@T6G_MB_LIB.T6G(SCH_1):PAGE108_I138@PURE_QUANTA.SCONN288_DDR506112002KQ(CHIPS)':
 'VSS117': CDS_PINID='VSS117';
NODE_NAME     J37 270
 '@T6G_MB_LIB.T6G(SCH_1):PAGE108_I138@PURE_QUANTA.SCONN288_DDR506112002KQ(CHIPS)':
 'VSS118': CDS_PINID='VSS118';
NODE_NAME     J37 273
 '@T6G_MB_LIB.T6G(SCH_1):PAGE108_I138@PURE_QUANTA.SCONN288_DDR506112002KQ(CHIPS)':
 'VSS119': CDS_PINID='VSS119';
NODE_NAME     J37 275
 '@T6G_MB_LIB.T6G(SCH_1):PAGE108_I138@PURE_QUANTA.SCONN288_DDR506112002KQ(CHIPS)':
 'VSS120': CDS_PINID='VSS120';
NODE_NAME     J37 277
 '@T6G_MB_LIB.T6G(SCH_1):PAGE108_I138@PURE_QUANTA.SCONN288_DDR506112002KQ(CHIPS)':
 'VSS121': CDS_PINID='VSS121';
NODE_NAME     J37 279
 '@T6G_MB_LIB.T6G(SCH_1):PAGE108_I138@PURE_QUANTA.SCONN288_DDR506112002KQ(CHIPS)':
 'VSS122': CDS_PINID='VSS122';
NODE_NAME     J37 281
 '@T6G_MB_LIB.T6G(SCH_1):PAGE108_I138@PURE_QUANTA.SCONN288_DDR506112002KQ(CHIPS)':
 'VSS123': CDS_PINID='VSS123';
NODE_NAME     J37 284
 '@T6G_MB_LIB.T6G(SCH_1):PAGE108_I138@PURE_QUANTA.SCONN288_DDR506112002KQ(CHIPS)':
 'VSS124': CDS_PINID='VSS124';
NODE_NAME     J37 286
 '@T6G_MB_LIB.T6G(SCH_1):PAGE108_I138@PURE_QUANTA.SCONN288_DDR506112002KQ(CHIPS)':
 'VSS125': CDS_PINID='VSS125';
NODE_NAME     J37 288
 '@T6G_MB_LIB.T6G(SCH_1):PAGE108_I138@PURE_QUANTA.SCONN288_DDR506112002KQ(CHIPS)':
 'VSS126': CDS_PINID='VSS126';
NODE_NAME     C180 2
 '@T6G_MB_LIB.T6G(SCH_1):PAGE108_I185@PURE_QUANTA.Q_CAP(CHIPS)':
 'B': CDS_PINID='B';
NODE_NAME     C548 2
 '@T6G_MB_LIB.T6G(SCH_1):PAGE108_I237@PURE_QUANTA.Q_CAP(CHIPS)':
 'B': CDS_PINID='B';
NODE_NAME     C549 2
 '@T6G_MB_LIB.T6G(SCH_1):PAGE108_I238@PURE_QUANTA.Q_CAP(CHIPS)':
 'B': CDS_PINID='B';
NODE_NAME     Q4 1
 '@T6G_MB_LIB.T6G(SCH_1):PAGE132_I12@PURE_QUANTA.MOSFET_DUAL_6P(CHIPS)':
 'S1': CDS_PINID='S1';
NODE_NAME     Q4 4
 '@T6G_MB_LIB.T6G(SCH_1):PAGE132_I12@PURE_QUANTA.MOSFET_DUAL_6P(CHIPS)':
 'S2': CDS_PINID='S2';
NODE_NAME     U105 5
 '@T6G_MB_LIB.T6G(SCH_1):PAGE136_I47@PURE_QUANTA.PI3CSW12ZUAEX(CHIPS)':
 'GND': CDS_PINID='GND';
NODE_NAME     C1336 2
 '@T6G_MB_LIB.T6G(SCH_1):PAGE136_I50@PURE_QUANTA.Q_CAP(CHIPS)':
 'B': CDS_PINID='B';
NODE_NAME     U106 5
 '@T6G_MB_LIB.T6G(SCH_1):PAGE136_I54@PURE_QUANTA.PI3CSW12ZUAEX(CHIPS)':
 'GND': CDS_PINID='GND';
NODE_NAME     C1337 2
 '@T6G_MB_LIB.T6G(SCH_1):PAGE136_I56@PURE_QUANTA.Q_CAP(CHIPS)':
 'B': CDS_PINID='B';
NODE_NAME     C1338 2
 '@T6G_MB_LIB.T6G(SCH_1):PAGE136_I61@PURE_QUANTA.Q_CAP(CHIPS)':
 'B': CDS_PINID='B';
NODE_NAME     U107 5
 '@T6G_MB_LIB.T6G(SCH_1):PAGE136_I63@PURE_QUANTA.PI3CSW12ZUAEX(CHIPS)':
 'GND': CDS_PINID='GND';
NODE_NAME     C1339 2
 '@T6G_MB_LIB.T6G(SCH_1):PAGE136_I66@PURE_QUANTA.Q_CAP(CHIPS)':
 'B': CDS_PINID='B';
NODE_NAME     U108 5
 '@T6G_MB_LIB.T6G(SCH_1):PAGE136_I68@PURE_QUANTA.PI3CSW12ZUAEX(CHIPS)':
 'GND': CDS_PINID='GND';
NODE_NAME     R5004 2
 '@T6G_MB_LIB.T6G(SCH_1):PAGE138_I27@PURE_QUANTA.Q_RES(CHIPS)':
 'B': CDS_PINID='B';
NODE_NAME     Q61 S
 '@T6G_MB_LIB.T6G(SCH_1):PAGE141_I89@PURE_QUANTA.MOSFET_N_GSD(CHIPS)':
 'SOURCE': CDS_PINID='SOURCE';
NODE_NAME     U116 2
 '@T6G_MB_LIB.T6G(SCH_1):PAGE141_I117@PURE_QUANTA.SN74AVC4T774PWR(CHIPS)':
 'DIR2': CDS_PINID='DIR2';
NODE_NAME     U116 8
 '@T6G_MB_LIB.T6G(SCH_1):PAGE141_I117@PURE_QUANTA.SN74AVC4T774PWR(CHIPS)':
 'DIR4': CDS_PINID='DIR4';
NODE_NAME     U116 10
 '@T6G_MB_LIB.T6G(SCH_1):PAGE141_I117@PURE_QUANTA.SN74AVC4T774PWR(CHIPS)':
 'GND': CDS_PINID='GND';
NODE_NAME     C1354 2
 '@T6G_MB_LIB.T6G(SCH_1):PAGE141_I133@PURE_QUANTA.Q_CAP(CHIPS)':
 'B': CDS_PINID='B';
NODE_NAME     C1352 2
 '@T6G_MB_LIB.T6G(SCH_1):PAGE141_I137@PURE_QUANTA.Q_CAP(CHIPS)':
 'B': CDS_PINID='B';
NODE_NAME     C364 2
 '@T6G_MB_LIB.T6G(SCH_1):PAGE141_I187@PURE_QUANTA.Q_CAP(CHIPS)':
 'B': CDS_PINID='B';
NODE_NAME     C363 2
 '@T6G_MB_LIB.T6G(SCH_1):PAGE141_I190@PURE_QUANTA.Q_CAP(CHIPS)':
 'B': CDS_PINID='B';
NODE_NAME     J13 4
 '@T6G_MB_LIB.T6G(SCH_1):PAGE141_I195@PURE_QUANTA.CONN4_HFK1040L0P1L7H(CHIPS)':
 '4': CDS_PINID='\4\';
NODE_NAME     Q2 1
 '@T6G_MB_LIB.T6G(SCH_1):PAGE143_I16@PURE_QUANTA.MOSFET_DUAL_6P(CHIPS)':
 'S1': CDS_PINID='S1';
NODE_NAME     Q2 4
 '@T6G_MB_LIB.T6G(SCH_1):PAGE143_I16@PURE_QUANTA.MOSFET_DUAL_6P(CHIPS)':
 'S2': CDS_PINID='S2';
NODE_NAME     Q11 1
 '@T6G_MB_LIB.T6G(SCH_1):PAGE143_I19@PURE_QUANTA.MOSFET_DUAL_6P(CHIPS)':
 'S1': CDS_PINID='S1';
NODE_NAME     Q11 4
 '@T6G_MB_LIB.T6G(SCH_1):PAGE143_I19@PURE_QUANTA.MOSFET_DUAL_6P(CHIPS)':
 'S2': CDS_PINID='S2';
NODE_NAME     C218 2
 '@T6G_MB_LIB.T6G(SCH_1):PAGE143_I24@PURE_QUANTA.Q_CAP(CHIPS)':
 'B': CDS_PINID='B';
NODE_NAME     U82 3
 '@T6G_MB_LIB.T6G(SCH_1):PAGE143_I26@PURE_QUANTA.SN74LVC1G07DBVR(CHIPS)':
 'GND': CDS_PINID='GND';
NODE_NAME     C219 2
 '@T6G_MB_LIB.T6G(SCH_1):PAGE143_I29@PURE_QUANTA.Q_CAP(CHIPS)':
 'B': CDS_PINID='B';
NODE_NAME     U86 3
 '@T6G_MB_LIB.T6G(SCH_1):PAGE143_I31@PURE_QUANTA.SN74LVC1G07DBVR(CHIPS)':
 'GND': CDS_PINID='GND';
NODE_NAME     D49 C
 '@T6G_MB_LIB.T6G(SCH_1):PAGE143_I38@PURE_QUANTA.Q_LED(CHIPS)':
 'C': CDS_PINID='C';
NODE_NAME     Q12 S
 '@T6G_MB_LIB.T6G(SCH_1):PAGE143_I44@PURE_QUANTA.MOSFET_N_GSD(CHIPS)':
 'SOURCE': CDS_PINID='SOURCE';
NODE_NAME     U124 3
 '@T6G_MB_LIB.T6G(SCH_1):PAGE144_I38@PURE_QUANTA.SN74LVC1G07DBVR(CHIPS)':
 'GND': CDS_PINID='GND';
NODE_NAME     C693 2
 '@T6G_MB_LIB.T6G(SCH_1):PAGE144_I39@PURE_QUANTA.Q_CAP(CHIPS)':
 'B': CDS_PINID='B';
NODE_NAME     R1735 2
 '@T6G_MB_LIB.T6G(SCH_1):PAGE148_I246@PURE_QUANTA.Q_RES(CHIPS)':
 'B': CDS_PINID='B';
NODE_NAME     R1748 2
 '@T6G_MB_LIB.T6G(SCH_1):PAGE148_I258@PURE_QUANTA.Q_RES(CHIPS)':
 'B': CDS_PINID='B';
NODE_NAME     U160 8
 '@T6G_MB_LIB.T6G(SCH_1):PAGE148_I266@PURE_QUANTA.74LV4052PW(CHIPS)':
 'GND': CDS_PINID='GND';
NODE_NAME     U160 7
 '@T6G_MB_LIB.T6G(SCH_1):PAGE148_I266@PURE_QUANTA.74LV4052PW(CHIPS)':
 'VEE': CDS_PINID='VEE';
NODE_NAME     C1554 2
 '@T6G_MB_LIB.T6G(SCH_1):PAGE148_I293@PURE_QUANTA.Q_CAP(CHIPS)':
 'B': CDS_PINID='B';
NODE_NAME     C194 2
 '@T6G_MB_LIB.T6G(SCH_1):PAGE148_I299@PURE_QUANTA.Q_CAP(CHIPS)':
 'B': CDS_PINID='B';
NODE_NAME     U212 8
 '@T6G_MB_LIB.T6G(SCH_1):PAGE148_I302@PURE_QUANTA.74LV4052PW(CHIPS)':
 'GND': CDS_PINID='GND';
NODE_NAME     U212 7
 '@T6G_MB_LIB.T6G(SCH_1):PAGE148_I302@PURE_QUANTA.74LV4052PW(CHIPS)':
 'VEE': CDS_PINID='VEE';
NODE_NAME     R1729 2
 '@T6G_MB_LIB.T6G(SCH_1):PAGE148_I306@PURE_QUANTA.Q_RES(CHIPS)':
 'B': CDS_PINID='B';
NODE_NAME     R1658 2
 '@T6G_MB_LIB.T6G(SCH_1):PAGE148_I310@PURE_QUANTA.Q_RES(CHIPS)':
 'B': CDS_PINID='B';
NODE_NAME     U99 3
 '@T6G_MB_LIB.T6G(SCH_1):PAGE148_I340@PURE_QUANTA.SN74LVC1G07DBVR(CHIPS)':
 'GND': CDS_PINID='GND';
NODE_NAME     C553 2
 '@T6G_MB_LIB.T6G(SCH_1):PAGE148_I342@PURE_QUANTA.Q_CAP(CHIPS)':
 'B': CDS_PINID='B';
NODE_NAME     U147 1
 '@T6G_MB_LIB.T6G(SCH_1):PAGE149_I1@PURE_QUANTA.SN74AVC2T245RSWR(CHIPS)':
 'DIR2': CDS_PINID='DIR2';
NODE_NAME     U147 3
 '@T6G_MB_LIB.T6G(SCH_1):PAGE149_I1@PURE_QUANTA.SN74AVC2T245RSWR(CHIPS)':
 'GND': CDS_PINID='GND';
NODE_NAME     C1509 2
 '@T6G_MB_LIB.T6G(SCH_1):PAGE149_I10@PURE_QUANTA.Q_CAP(CHIPS)':
 'B': CDS_PINID='B';
NODE_NAME     C1512 2
 '@T6G_MB_LIB.T6G(SCH_1):PAGE149_I21@PURE_QUANTA.Q_CAP(CHIPS)':
 'B': CDS_PINID='B';
NODE_NAME     C1511 2
 '@T6G_MB_LIB.T6G(SCH_1):PAGE149_I23@PURE_QUANTA.Q_CAP(CHIPS)':
 'B': CDS_PINID='B';
NODE_NAME     C1510 2
 '@T6G_MB_LIB.T6G(SCH_1):PAGE149_I25@PURE_QUANTA.Q_CAP(CHIPS)':
 'B': CDS_PINID='B';
NODE_NAME     C1508 2
 '@T6G_MB_LIB.T6G(SCH_1):PAGE149_I29@PURE_QUANTA.Q_CAP(CHIPS)':
 'B': CDS_PINID='B';
NODE_NAME     U149 10
 '@T6G_MB_LIB.T6G(SCH_1):PAGE149_I31@PURE_QUANTA.SN74AVC4T774PWR(CHIPS)':
 'GND': CDS_PINID='GND';
NODE_NAME     U148 10
 '@T6G_MB_LIB.T6G(SCH_1):PAGE149_I34@PURE_QUANTA.SN74AVC4T774PWR(CHIPS)':
 'GND': CDS_PINID='GND';
NODE_NAME     C1507 2
 '@T6G_MB_LIB.T6G(SCH_1):PAGE149_I41@PURE_QUANTA.Q_CAP(CHIPS)':
 'B': CDS_PINID='B';
NODE_NAME     C1504 2
 '@T6G_MB_LIB.T6G(SCH_1):PAGE149_I56@PURE_QUANTA.Q_CAP(CHIPS)':
 'B': CDS_PINID='B';
NODE_NAME     C1506 2
 '@T6G_MB_LIB.T6G(SCH_1):PAGE149_I62@PURE_QUANTA.Q_CAP(CHIPS)':
 'B': CDS_PINID='B';
NODE_NAME     C1505 2
 '@T6G_MB_LIB.T6G(SCH_1):PAGE149_I74@PURE_QUANTA.Q_CAP(CHIPS)':
 'B': CDS_PINID='B';
NODE_NAME     U146 1
 '@T6G_MB_LIB.T6G(SCH_1):PAGE149_I76@PURE_QUANTA.SN74AVC2T245RSWR(CHIPS)':
 'DIR2': CDS_PINID='DIR2';
NODE_NAME     U146 3
 '@T6G_MB_LIB.T6G(SCH_1):PAGE149_I76@PURE_QUANTA.SN74AVC2T245RSWR(CHIPS)':
 'GND': CDS_PINID='GND';
NODE_NAME     C1503 2
 '@T6G_MB_LIB.T6G(SCH_1):PAGE149_I80@PURE_QUANTA.Q_CAP(CHIPS)':
 'B': CDS_PINID='B';
NODE_NAME     Q62 S
 '@T6G_MB_LIB.T6G(SCH_1):PAGE149_I102@PURE_QUANTA.MOSFET_N(CHIPS)':
 'SOURCE': CDS_PINID='SOURCE';
NODE_NAME     R1629 2
 '@T6G_MB_LIB.T6G(SCH_1):PAGE149_I112@PURE_QUANTA.Q_RES(CHIPS)':
 'B': CDS_PINID='B';
NODE_NAME     C551 2
 '@T6G_MB_LIB.T6G(SCH_1):PAGE149_I123@PURE_QUANTA.Q_CAP(CHIPS)':
 'B': CDS_PINID='B';
NODE_NAME     C87 2
 '@T6G_MB_LIB.T6G(SCH_1):PAGE149_I134@PURE_QUANTA.Q_CAP(CHIPS)':
 'B': CDS_PINID='B';
NODE_NAME     C605 2
 '@T6G_MB_LIB.T6G(SCH_1):PAGE149_I137@PURE_QUANTA.Q_CAP(CHIPS)':
 'B': CDS_PINID='B';
NODE_NAME     C604 2
 '@T6G_MB_LIB.T6G(SCH_1):PAGE149_I140@PURE_QUANTA.Q_CAP(CHIPS)':
 'B': CDS_PINID='B';
NODE_NAME     J54 5
 '@T6G_MB_LIB.T6G(SCH_1):PAGE149_I142@PURE_QUANTA.SCONN20_HSU2101L00007H(CHIPS)':
 '5': CDS_PINID='\5\';
NODE_NAME     J54 7
 '@T6G_MB_LIB.T6G(SCH_1):PAGE149_I142@PURE_QUANTA.SCONN20_HSU2101L00007H(CHIPS)':
 '7': CDS_PINID='\7\';
NODE_NAME     J54 17
 '@T6G_MB_LIB.T6G(SCH_1):PAGE149_I142@PURE_QUANTA.SCONN20_HSU2101L00007H(CHIPS)':
 '17': CDS_PINID='\17\';
NODE_NAME     C85 2
 '@T6G_MB_LIB.T6G(SCH_1):PAGE149_I152@PURE_QUANTA.Q_CAP(CHIPS)':
 'B': CDS_PINID='B';
NODE_NAME     U150 10
 '@T6G_MB_LIB.T6G(SCH_1):PAGE150_I8@PURE_QUANTA.SN74AVC4T774PWR(CHIPS)':
 'GND': CDS_PINID='GND';
NODE_NAME     C1516 2
 '@T6G_MB_LIB.T6G(SCH_1):PAGE150_I14@PURE_QUANTA.Q_CAP(CHIPS)':
 'B': CDS_PINID='B';
NODE_NAME     C1514 2
 '@T6G_MB_LIB.T6G(SCH_1):PAGE150_I19@PURE_QUANTA.Q_CAP(CHIPS)':
 'B': CDS_PINID='B';
NODE_NAME     U151 10
 '@T6G_MB_LIB.T6G(SCH_1):PAGE150_I28@PURE_QUANTA.SN74AVC4T774PWR(CHIPS)':
 'GND': CDS_PINID='GND';
NODE_NAME     C1517 2
 '@T6G_MB_LIB.T6G(SCH_1):PAGE150_I40@PURE_QUANTA.Q_CAP(CHIPS)':
 'B': CDS_PINID='B';
NODE_NAME     C1515 2
 '@T6G_MB_LIB.T6G(SCH_1):PAGE150_I43@PURE_QUANTA.Q_CAP(CHIPS)':
 'B': CDS_PINID='B';
NODE_NAME     U152 1
 '@T6G_MB_LIB.T6G(SCH_1):PAGE150_I60@PURE_QUANTA.SN74AVC2T245RSWR(CHIPS)':
 'DIR2': CDS_PINID='DIR2';
NODE_NAME     U152 3
 '@T6G_MB_LIB.T6G(SCH_1):PAGE150_I60@PURE_QUANTA.SN74AVC2T245RSWR(CHIPS)':
 'GND': CDS_PINID='GND';
NODE_NAME     C1518 2
 '@T6G_MB_LIB.T6G(SCH_1):PAGE150_I66@PURE_QUANTA.Q_CAP(CHIPS)':
 'B': CDS_PINID='B';
NODE_NAME     C1513 2
 '@T6G_MB_LIB.T6G(SCH_1):PAGE150_I69@PURE_QUANTA.Q_CAP(CHIPS)':
 'B': CDS_PINID='B';
NODE_NAME     R1637 2
 '@T6G_MB_LIB.T6G(SCH_1):PAGE150_I71@PURE_QUANTA.Q_RES(CHIPS)':
 'B': CDS_PINID='B';
NODE_NAME     U153 4
 '@T6G_MB_LIB.T6G(SCH_1):PAGE151_I1@PURE_QUANTA.SN74AUC2G66DCTR(CHIPS)':
 'GND': CDS_PINID='GND';
NODE_NAME     C1520 2
 '@T6G_MB_LIB.T6G(SCH_1):PAGE151_I4@PURE_QUANTA.Q_CAP(CHIPS)':
 'B': CDS_PINID='B';
NODE_NAME     C1519 2
 '@T6G_MB_LIB.T6G(SCH_1):PAGE151_I15@PURE_QUANTA.Q_CAP(CHIPS)':
 'B': CDS_PINID='B';
NODE_NAME     U13 4
 '@T6G_MB_LIB.T6G(SCH_1):PAGE151_I17@PURE_QUANTA.SN74AUC2G66DCTR(CHIPS)':
 'GND': CDS_PINID='GND';
NODE_NAME     C1521 2
 '@T6G_MB_LIB.T6G(SCH_1):PAGE151_I22@PURE_QUANTA.Q_CAP(CHIPS)':
 'B': CDS_PINID='B';
NODE_NAME     U14 4
 '@T6G_MB_LIB.T6G(SCH_1):PAGE151_I23@PURE_QUANTA.SN74AUC2G66DCTR(CHIPS)':
 'GND': CDS_PINID='GND';
NODE_NAME     U154 4
 '@T6G_MB_LIB.T6G(SCH_1):PAGE151_I31@PURE_QUANTA.SN74AUC2G66DCTR(CHIPS)':
 'GND': CDS_PINID='GND';
NODE_NAME     C1522 2
 '@T6G_MB_LIB.T6G(SCH_1):PAGE151_I36@PURE_QUANTA.Q_CAP(CHIPS)':
 'B': CDS_PINID='B';
NODE_NAME     C1523 2
 '@T6G_MB_LIB.T6G(SCH_1):PAGE151_I42@PURE_QUANTA.Q_CAP(CHIPS)':
 'B': CDS_PINID='B';
NODE_NAME     Q63 S
 '@T6G_MB_LIB.T6G(SCH_1):PAGE151_I45@PURE_QUANTA.MOSFET_N(CHIPS)':
 'SOURCE': CDS_PINID='SOURCE';
NODE_NAME     Q64 S
 '@T6G_MB_LIB.T6G(SCH_1):PAGE151_I46@PURE_QUANTA.MOSFET_N(CHIPS)':
 'SOURCE': CDS_PINID='SOURCE';
NODE_NAME     R1342 2
 '@T6G_MB_LIB.T6G(SCH_1):PAGE148_I369@PURE_QUANTA.Q_RES(CHIPS)':
 'B': CDS_PINID='B';
NODE_NAME     Q29 S
 '@T6G_MB_LIB.T6G(SCH_1):PAGE142_I80@PURE_QUANTA.MOSFET_N_GSD(CHIPS)':
 'SOURCE': CDS_PINID='SOURCE';
NODE_NAME     Q30 S
 '@T6G_MB_LIB.T6G(SCH_1):PAGE142_I81@PURE_QUANTA.MOSFET_N_GSD(CHIPS)':
 'SOURCE': CDS_PINID='SOURCE';
NODE_NAME     PC6002 2
 '@T6G_MB_LIB.T6G(SCH_1):PAGE201_I3@PURE_QUANTA.Q_CAP(CHIPS)':
 'B': CDS_PINID='B';
NODE_NAME     C675 2
 '@T6G_MB_LIB.T6G(SCH_1):PAGE201_I6@PURE_QUANTA.Q_CAP(CHIPS)':
 'B': CDS_PINID='B';
NODE_NAME     PR8 2
 '@T6G_MB_LIB.T6G(SCH_1):PAGE201_I11@PURE_QUANTA.Q_RES(CHIPS)':
 'B': CDS_PINID='B';
NODE_NAME     PU3 2
 '@T6G_MB_LIB.T6G(SCH_1):PAGE201_I15@PURE_QUANTA.MPQ8633BGLEC838Z(CHIPS)':
 'AGND': CDS_PINID='AGND';
NODE_NAME     PU3 11_18
 '@T6G_MB_LIB.T6G(SCH_1):PAGE201_I15@PURE_QUANTA.MPQ8633BGLEC838Z(CHIPS)':
 'PGND': CDS_PINID='PGND';
NODE_NAME     PC153 2
 '@T6G_MB_LIB.T6G(SCH_1):PAGE201_I18@PURE_QUANTA.Q_CAP(CHIPS)':
 'B': CDS_PINID='B';
NODE_NAME     PC61 2
 '@T6G_MB_LIB.T6G(SCH_1):PAGE201_I21@PURE_QUANTA.Q_CAP(CHIPS)':
 'B': CDS_PINID='B';
NODE_NAME     PC150 2
 '@T6G_MB_LIB.T6G(SCH_1):PAGE201_I22@PURE_QUANTA.Q_CAP(CHIPS)':
 'B': CDS_PINID='B';
NODE_NAME     PC152 2
 '@T6G_MB_LIB.T6G(SCH_1):PAGE201_I23@PURE_QUANTA.Q_CAP(CHIPS)':
 'B': CDS_PINID='B';
NODE_NAME     PC22 2
 '@T6G_MB_LIB.T6G(SCH_1):PAGE201_I24@PURE_QUANTA.Q_CAP(CHIPS)':
 'B': CDS_PINID='B';
NODE_NAME     PC65 2
 '@T6G_MB_LIB.T6G(SCH_1):PAGE201_I37@PURE_QUANTA.Q_CAP(CHIPS)':
 'B': CDS_PINID='B';
NODE_NAME     PC83 2
 '@T6G_MB_LIB.T6G(SCH_1):PAGE201_I38@PURE_QUANTA.Q_CAP(CHIPS)':
 'B': CDS_PINID='B';
NODE_NAME     PC88 2
 '@T6G_MB_LIB.T6G(SCH_1):PAGE201_I42@PURE_QUANTA.Q_CAP(CHIPS)':
 'B': CDS_PINID='B';
NODE_NAME     PC89 2
 '@T6G_MB_LIB.T6G(SCH_1):PAGE201_I43@PURE_QUANTA.Q_CAPP(CHIPS)':
 'B': CDS_PINID='B';
NODE_NAME     PR403 2
 '@T6G_MB_LIB.T6G(SCH_1):PAGE201_I50@PURE_QUANTA.Q_RES(CHIPS)':
 'B': CDS_PINID='B';
NODE_NAME     PC20 2
 '@T6G_MB_LIB.T6G(SCH_1):PAGE201_I53@PURE_QUANTA.Q_CAP(CHIPS)':
 'B': CDS_PINID='B';
NODE_NAME     R754 1
 '@T6G_MB_LIB.T6G(SCH_1):PAGE75_I91@PURE_QUANTA.Q_RES(CHIPS)':
 'A': CDS_PINID='A';
NODE_NAME     R760 1
 '@T6G_MB_LIB.T6G(SCH_1):PAGE75_I92@PURE_QUANTA.Q_RES(CHIPS)':
 'A': CDS_PINID='A';
NODE_NAME     R1502 1
 '@T6G_MB_LIB.T6G(SCH_1):PAGE75_I94@PURE_QUANTA.Q_RES(CHIPS)':
 'A': CDS_PINID='A';
NODE_NAME     PR519 2
 '@T6G_MB_LIB.T6G(SCH_1):PAGE200_I25@PURE_QUANTA.Q_RES(CHIPS)':
 'B': CDS_PINID='B';
NODE_NAME     PC510_2 2
 '@T6G_MB_LIB.T6G(SCH_1):PAGE200_I29@PURE_QUANTA.Q_CAP(CHIPS)':
 'B': CDS_PINID='B';
NODE_NAME     PC503_1 2
 '@T6G_MB_LIB.T6G(SCH_1):PAGE200_I34@PURE_QUANTA.Q_CAP(CHIPS)':
 'B': CDS_PINID='B';
NODE_NAME     PR328 1
 '@T6G_MB_LIB.T6G(SCH_1):PAGE200_I37@PURE_QUANTA.Q_RES(CHIPS)':
 'A': CDS_PINID='A';
NODE_NAME     PC507_11P1_1 2
 '@T6G_MB_LIB.T6G(SCH_1):PAGE200_I43@PURE_QUANTA.Q_CAP(CHIPS)':
 'B': CDS_PINID='B';
NODE_NAME     PC509_1 2
 '@T6G_MB_LIB.T6G(SCH_1):PAGE200_I48@PURE_QUANTA.Q_CAP(CHIPS)':
 'B': CDS_PINID='B';
NODE_NAME     PC518_2 2
 '@T6G_MB_LIB.T6G(SCH_1):PAGE200_I52@PURE_QUANTA.Q_CAP(CHIPS)':
 'B': CDS_PINID='B';
NODE_NAME     PC528 2
 '@T6G_MB_LIB.T6G(SCH_1):PAGE200_I63@PURE_QUANTA.Q_CAPP(CHIPS)':
 'B': CDS_PINID='B';
NODE_NAME     PC527_2 2
 '@T6G_MB_LIB.T6G(SCH_1):PAGE200_I67@PURE_QUANTA.Q_CAP(CHIPS)':
 'B': CDS_PINID='B';
NODE_NAME     PC530 2
 '@T6G_MB_LIB.T6G(SCH_1):PAGE200_I69@PURE_QUANTA.Q_CAPP(CHIPS)':
 'B': CDS_PINID='B';
NODE_NAME     PC522 2
 '@T6G_MB_LIB.T6G(SCH_1):PAGE200_I81@PURE_QUANTA.Q_CAPP(CHIPS)':
 'B': CDS_PINID='B';
NODE_NAME     J1 G1
 '@T6G_MB_LIB.T6G(SCH_1):PAGE85_I538@PURE_QUANTA.SCONN288_DDR506112002KQ(CHIPS)':
 'G1': CDS_PINID='G1';
NODE_NAME     J1 G2
 '@T6G_MB_LIB.T6G(SCH_1):PAGE85_I538@PURE_QUANTA.SCONN288_DDR506112002KQ(CHIPS)':
 'G2': CDS_PINID='G2';
NODE_NAME     J1 G3
 '@T6G_MB_LIB.T6G(SCH_1):PAGE85_I538@PURE_QUANTA.SCONN288_DDR506112002KQ(CHIPS)':
 'G3': CDS_PINID='G3';
NODE_NAME     J1 6
 '@T6G_MB_LIB.T6G(SCH_1):PAGE85_I538@PURE_QUANTA.SCONN288_DDR506112002KQ(CHIPS)':
 'VSS0': CDS_PINID='VSS0';
NODE_NAME     J1 8
 '@T6G_MB_LIB.T6G(SCH_1):PAGE85_I538@PURE_QUANTA.SCONN288_DDR506112002KQ(CHIPS)':
 'VSS1': CDS_PINID='VSS1';
NODE_NAME     J1 10
 '@T6G_MB_LIB.T6G(SCH_1):PAGE85_I538@PURE_QUANTA.SCONN288_DDR506112002KQ(CHIPS)':
 'VSS2': CDS_PINID='VSS2';
NODE_NAME     J1 13
 '@T6G_MB_LIB.T6G(SCH_1):PAGE85_I538@PURE_QUANTA.SCONN288_DDR506112002KQ(CHIPS)':
 'VSS3': CDS_PINID='VSS3';
NODE_NAME     J1 15
 '@T6G_MB_LIB.T6G(SCH_1):PAGE85_I538@PURE_QUANTA.SCONN288_DDR506112002KQ(CHIPS)':
 'VSS4': CDS_PINID='VSS4';
NODE_NAME     J1 17
 '@T6G_MB_LIB.T6G(SCH_1):PAGE85_I538@PURE_QUANTA.SCONN288_DDR506112002KQ(CHIPS)':
 'VSS5': CDS_PINID='VSS5';
NODE_NAME     J1 19
 '@T6G_MB_LIB.T6G(SCH_1):PAGE85_I538@PURE_QUANTA.SCONN288_DDR506112002KQ(CHIPS)':
 'VSS6': CDS_PINID='VSS6';
NODE_NAME     J1 21
 '@T6G_MB_LIB.T6G(SCH_1):PAGE85_I538@PURE_QUANTA.SCONN288_DDR506112002KQ(CHIPS)':
 'VSS7': CDS_PINID='VSS7';
NODE_NAME     J1 24
 '@T6G_MB_LIB.T6G(SCH_1):PAGE85_I538@PURE_QUANTA.SCONN288_DDR506112002KQ(CHIPS)':
 'VSS8': CDS_PINID='VSS8';
NODE_NAME     J1 26
 '@T6G_MB_LIB.T6G(SCH_1):PAGE85_I538@PURE_QUANTA.SCONN288_DDR506112002KQ(CHIPS)':
 'VSS9': CDS_PINID='VSS9';
NODE_NAME     J1 28
 '@T6G_MB_LIB.T6G(SCH_1):PAGE85_I538@PURE_QUANTA.SCONN288_DDR506112002KQ(CHIPS)':
 'VSS10': CDS_PINID='VSS10';
NODE_NAME     J1 30
 '@T6G_MB_LIB.T6G(SCH_1):PAGE85_I538@PURE_QUANTA.SCONN288_DDR506112002KQ(CHIPS)':
 'VSS11': CDS_PINID='VSS11';
NODE_NAME     J1 32
 '@T6G_MB_LIB.T6G(SCH_1):PAGE85_I538@PURE_QUANTA.SCONN288_DDR506112002KQ(CHIPS)':
 'VSS12': CDS_PINID='VSS12';
NODE_NAME     J1 35
 '@T6G_MB_LIB.T6G(SCH_1):PAGE85_I538@PURE_QUANTA.SCONN288_DDR506112002KQ(CHIPS)':
 'VSS13': CDS_PINID='VSS13';
NODE_NAME     J1 37
 '@T6G_MB_LIB.T6G(SCH_1):PAGE85_I538@PURE_QUANTA.SCONN288_DDR506112002KQ(CHIPS)':
 'VSS14': CDS_PINID='VSS14';
NODE_NAME     J1 39
 '@T6G_MB_LIB.T6G(SCH_1):PAGE85_I538@PURE_QUANTA.SCONN288_DDR506112002KQ(CHIPS)':
 'VSS15': CDS_PINID='VSS15';
NODE_NAME     J1 41
 '@T6G_MB_LIB.T6G(SCH_1):PAGE85_I538@PURE_QUANTA.SCONN288_DDR506112002KQ(CHIPS)':
 'VSS16': CDS_PINID='VSS16';
NODE_NAME     J1 43
 '@T6G_MB_LIB.T6G(SCH_1):PAGE85_I538@PURE_QUANTA.SCONN288_DDR506112002KQ(CHIPS)':
 'VSS17': CDS_PINID='VSS17';
NODE_NAME     J1 46
 '@T6G_MB_LIB.T6G(SCH_1):PAGE85_I538@PURE_QUANTA.SCONN288_DDR506112002KQ(CHIPS)':
 'VSS18': CDS_PINID='VSS18';
NODE_NAME     J1 48
 '@T6G_MB_LIB.T6G(SCH_1):PAGE85_I538@PURE_QUANTA.SCONN288_DDR506112002KQ(CHIPS)':
 'VSS19': CDS_PINID='VSS19';
NODE_NAME     J1 50
 '@T6G_MB_LIB.T6G(SCH_1):PAGE85_I538@PURE_QUANTA.SCONN288_DDR506112002KQ(CHIPS)':
 'VSS20': CDS_PINID='VSS20';
NODE_NAME     J1 52
 '@T6G_MB_LIB.T6G(SCH_1):PAGE85_I538@PURE_QUANTA.SCONN288_DDR506112002KQ(CHIPS)':
 'VSS21': CDS_PINID='VSS21';
NODE_NAME     J1 54
 '@T6G_MB_LIB.T6G(SCH_1):PAGE85_I538@PURE_QUANTA.SCONN288_DDR506112002KQ(CHIPS)':
 'VSS22': CDS_PINID='VSS22';
NODE_NAME     J1 57
 '@T6G_MB_LIB.T6G(SCH_1):PAGE85_I538@PURE_QUANTA.SCONN288_DDR506112002KQ(CHIPS)':
 'VSS23': CDS_PINID='VSS23';
NODE_NAME     J1 59
 '@T6G_MB_LIB.T6G(SCH_1):PAGE85_I538@PURE_QUANTA.SCONN288_DDR506112002KQ(CHIPS)':
 'VSS24': CDS_PINID='VSS24';
NODE_NAME     J1 61
 '@T6G_MB_LIB.T6G(SCH_1):PAGE85_I538@PURE_QUANTA.SCONN288_DDR506112002KQ(CHIPS)':
 'VSS25': CDS_PINID='VSS25';
NODE_NAME     J1 63
 '@T6G_MB_LIB.T6G(SCH_1):PAGE85_I538@PURE_QUANTA.SCONN288_DDR506112002KQ(CHIPS)':
 'VSS26': CDS_PINID='VSS26';
NODE_NAME     J1 65
 '@T6G_MB_LIB.T6G(SCH_1):PAGE85_I538@PURE_QUANTA.SCONN288_DDR506112002KQ(CHIPS)':
 'VSS27': CDS_PINID='VSS27';
NODE_NAME     J1 67
 '@T6G_MB_LIB.T6G(SCH_1):PAGE85_I538@PURE_QUANTA.SCONN288_DDR506112002KQ(CHIPS)':
 'VSS28': CDS_PINID='VSS28';
NODE_NAME     J1 69
 '@T6G_MB_LIB.T6G(SCH_1):PAGE85_I538@PURE_QUANTA.SCONN288_DDR506112002KQ(CHIPS)':
 'VSS29': CDS_PINID='VSS29';
NODE_NAME     J1 71
 '@T6G_MB_LIB.T6G(SCH_1):PAGE85_I538@PURE_QUANTA.SCONN288_DDR506112002KQ(CHIPS)':
 'VSS30': CDS_PINID='VSS30';
NODE_NAME     J1 73
 '@T6G_MB_LIB.T6G(SCH_1):PAGE85_I538@PURE_QUANTA.SCONN288_DDR506112002KQ(CHIPS)':
 'VSS31': CDS_PINID='VSS31';
NODE_NAME     J1 75
 '@T6G_MB_LIB.T6G(SCH_1):PAGE85_I538@PURE_QUANTA.SCONN288_DDR506112002KQ(CHIPS)':
 'VSS32': CDS_PINID='VSS32';
NODE_NAME     J1 77
 '@T6G_MB_LIB.T6G(SCH_1):PAGE85_I538@PURE_QUANTA.SCONN288_DDR506112002KQ(CHIPS)':
 'VSS33': CDS_PINID='VSS33';
NODE_NAME     J1 79
 '@T6G_MB_LIB.T6G(SCH_1):PAGE85_I538@PURE_QUANTA.SCONN288_DDR506112002KQ(CHIPS)':
 'VSS34': CDS_PINID='VSS34';
NODE_NAME     J1 81
 '@T6G_MB_LIB.T6G(SCH_1):PAGE85_I538@PURE_QUANTA.SCONN288_DDR506112002KQ(CHIPS)':
 'VSS35': CDS_PINID='VSS35';
NODE_NAME     J1 83
 '@T6G_MB_LIB.T6G(SCH_1):PAGE85_I538@PURE_QUANTA.SCONN288_DDR506112002KQ(CHIPS)':
 'VSS36': CDS_PINID='VSS36';
NODE_NAME     J1 85
 '@T6G_MB_LIB.T6G(SCH_1):PAGE85_I538@PURE_QUANTA.SCONN288_DDR506112002KQ(CHIPS)':
 'VSS37': CDS_PINID='VSS37';
NODE_NAME     J1 88
 '@T6G_MB_LIB.T6G(SCH_1):PAGE85_I538@PURE_QUANTA.SCONN288_DDR506112002KQ(CHIPS)':
 'VSS38': CDS_PINID='VSS38';
NODE_NAME     J1 90
 '@T6G_MB_LIB.T6G(SCH_1):PAGE85_I538@PURE_QUANTA.SCONN288_DDR506112002KQ(CHIPS)':
 'VSS39': CDS_PINID='VSS39';
NODE_NAME     J1 92
 '@T6G_MB_LIB.T6G(SCH_1):PAGE85_I538@PURE_QUANTA.SCONN288_DDR506112002KQ(CHIPS)':
 'VSS40': CDS_PINID='VSS40';
NODE_NAME     J1 95
 '@T6G_MB_LIB.T6G(SCH_1):PAGE85_I538@PURE_QUANTA.SCONN288_DDR506112002KQ(CHIPS)':
 'VSS41': CDS_PINID='VSS41';
NODE_NAME     J1 97
 '@T6G_MB_LIB.T6G(SCH_1):PAGE85_I538@PURE_QUANTA.SCONN288_DDR506112002KQ(CHIPS)':
 'VSS42': CDS_PINID='VSS42';
NODE_NAME     J1 99
 '@T6G_MB_LIB.T6G(SCH_1):PAGE85_I538@PURE_QUANTA.SCONN288_DDR506112002KQ(CHIPS)':
 'VSS43': CDS_PINID='VSS43';
NODE_NAME     J1 101
 '@T6G_MB_LIB.T6G(SCH_1):PAGE85_I538@PURE_QUANTA.SCONN288_DDR506112002KQ(CHIPS)':
 'VSS44': CDS_PINID='VSS44';
NODE_NAME     J1 103
 '@T6G_MB_LIB.T6G(SCH_1):PAGE85_I538@PURE_QUANTA.SCONN288_DDR506112002KQ(CHIPS)':
 'VSS45': CDS_PINID='VSS45';
NODE_NAME     J1 106
 '@T6G_MB_LIB.T6G(SCH_1):PAGE85_I538@PURE_QUANTA.SCONN288_DDR506112002KQ(CHIPS)':
 'VSS46': CDS_PINID='VSS46';
NODE_NAME     J1 108
 '@T6G_MB_LIB.T6G(SCH_1):PAGE85_I538@PURE_QUANTA.SCONN288_DDR506112002KQ(CHIPS)':
 'VSS47': CDS_PINID='VSS47';
NODE_NAME     J1 110
 '@T6G_MB_LIB.T6G(SCH_1):PAGE85_I538@PURE_QUANTA.SCONN288_DDR506112002KQ(CHIPS)':
 'VSS48': CDS_PINID='VSS48';
NODE_NAME     J1 112
 '@T6G_MB_LIB.T6G(SCH_1):PAGE85_I538@PURE_QUANTA.SCONN288_DDR506112002KQ(CHIPS)':
 'VSS49': CDS_PINID='VSS49';
NODE_NAME     J1 114
 '@T6G_MB_LIB.T6G(SCH_1):PAGE85_I538@PURE_QUANTA.SCONN288_DDR506112002KQ(CHIPS)':
 'VSS50': CDS_PINID='VSS50';
NODE_NAME     J1 117
 '@T6G_MB_LIB.T6G(SCH_1):PAGE85_I538@PURE_QUANTA.SCONN288_DDR506112002KQ(CHIPS)':
 'VSS51': CDS_PINID='VSS51';
NODE_NAME     J1 119
 '@T6G_MB_LIB.T6G(SCH_1):PAGE85_I538@PURE_QUANTA.SCONN288_DDR506112002KQ(CHIPS)':
 'VSS52': CDS_PINID='VSS52';
NODE_NAME     J1 121
 '@T6G_MB_LIB.T6G(SCH_1):PAGE85_I538@PURE_QUANTA.SCONN288_DDR506112002KQ(CHIPS)':
 'VSS53': CDS_PINID='VSS53';
NODE_NAME     J1 123
 '@T6G_MB_LIB.T6G(SCH_1):PAGE85_I538@PURE_QUANTA.SCONN288_DDR506112002KQ(CHIPS)':
 'VSS54': CDS_PINID='VSS54';
NODE_NAME     J1 125
 '@T6G_MB_LIB.T6G(SCH_1):PAGE85_I538@PURE_QUANTA.SCONN288_DDR506112002KQ(CHIPS)':
 'VSS55': CDS_PINID='VSS55';
NODE_NAME     J1 128
 '@T6G_MB_LIB.T6G(SCH_1):PAGE85_I538@PURE_QUANTA.SCONN288_DDR506112002KQ(CHIPS)':
 'VSS56': CDS_PINID='VSS56';
NODE_NAME     J1 130
 '@T6G_MB_LIB.T6G(SCH_1):PAGE85_I538@PURE_QUANTA.SCONN288_DDR506112002KQ(CHIPS)':
 'VSS57': CDS_PINID='VSS57';
NODE_NAME     J1 132
 '@T6G_MB_LIB.T6G(SCH_1):PAGE85_I538@PURE_QUANTA.SCONN288_DDR506112002KQ(CHIPS)':
 'VSS58': CDS_PINID='VSS58';
NODE_NAME     J1 134
 '@T6G_MB_LIB.T6G(SCH_1):PAGE85_I538@PURE_QUANTA.SCONN288_DDR506112002KQ(CHIPS)':
 'VSS59': CDS_PINID='VSS59';
NODE_NAME     J1 136
 '@T6G_MB_LIB.T6G(SCH_1):PAGE85_I538@PURE_QUANTA.SCONN288_DDR506112002KQ(CHIPS)':
 'VSS60': CDS_PINID='VSS60';
NODE_NAME     J1 139
 '@T6G_MB_LIB.T6G(SCH_1):PAGE85_I538@PURE_QUANTA.SCONN288_DDR506112002KQ(CHIPS)':
 'VSS61': CDS_PINID='VSS61';
NODE_NAME     J1 141
 '@T6G_MB_LIB.T6G(SCH_1):PAGE85_I538@PURE_QUANTA.SCONN288_DDR506112002KQ(CHIPS)':
 'VSS62': CDS_PINID='VSS62';
NODE_NAME     J1 143
 '@T6G_MB_LIB.T6G(SCH_1):PAGE85_I538@PURE_QUANTA.SCONN288_DDR506112002KQ(CHIPS)':
 'VSS63': CDS_PINID='VSS63';
NODE_NAME     J1 151
 '@T6G_MB_LIB.T6G(SCH_1):PAGE85_I538@PURE_QUANTA.SCONN288_DDR506112002KQ(CHIPS)':
 'VSS64': CDS_PINID='VSS64';
NODE_NAME     J1 153
 '@T6G_MB_LIB.T6G(SCH_1):PAGE85_I538@PURE_QUANTA.SCONN288_DDR506112002KQ(CHIPS)':
 'VSS65': CDS_PINID='VSS65';
NODE_NAME     J1 155
 '@T6G_MB_LIB.T6G(SCH_1):PAGE85_I538@PURE_QUANTA.SCONN288_DDR506112002KQ(CHIPS)':
 'VSS66': CDS_PINID='VSS66';
NODE_NAME     J1 158
 '@T6G_MB_LIB.T6G(SCH_1):PAGE85_I538@PURE_QUANTA.SCONN288_DDR506112002KQ(CHIPS)':
 'VSS67': CDS_PINID='VSS67';
NODE_NAME     J1 160
 '@T6G_MB_LIB.T6G(SCH_1):PAGE85_I538@PURE_QUANTA.SCONN288_DDR506112002KQ(CHIPS)':
 'VSS68': CDS_PINID='VSS68';
NODE_NAME     J1 162
 '@T6G_MB_LIB.T6G(SCH_1):PAGE85_I538@PURE_QUANTA.SCONN288_DDR506112002KQ(CHIPS)':
 'VSS69': CDS_PINID='VSS69';
NODE_NAME     J1 164
 '@T6G_MB_LIB.T6G(SCH_1):PAGE85_I538@PURE_QUANTA.SCONN288_DDR506112002KQ(CHIPS)':
 'VSS70': CDS_PINID='VSS70';
NODE_NAME     J1 166
 '@T6G_MB_LIB.T6G(SCH_1):PAGE85_I538@PURE_QUANTA.SCONN288_DDR506112002KQ(CHIPS)':
 'VSS71': CDS_PINID='VSS71';
NODE_NAME     J1 169
 '@T6G_MB_LIB.T6G(SCH_1):PAGE85_I538@PURE_QUANTA.SCONN288_DDR506112002KQ(CHIPS)':
 'VSS72': CDS_PINID='VSS72';
NODE_NAME     J1 171
 '@T6G_MB_LIB.T6G(SCH_1):PAGE85_I538@PURE_QUANTA.SCONN288_DDR506112002KQ(CHIPS)':
 'VSS73': CDS_PINID='VSS73';
NODE_NAME     J1 173
 '@T6G_MB_LIB.T6G(SCH_1):PAGE85_I538@PURE_QUANTA.SCONN288_DDR506112002KQ(CHIPS)':
 'VSS74': CDS_PINID='VSS74';
NODE_NAME     J1 175
 '@T6G_MB_LIB.T6G(SCH_1):PAGE85_I538@PURE_QUANTA.SCONN288_DDR506112002KQ(CHIPS)':
 'VSS75': CDS_PINID='VSS75';
NODE_NAME     J1 177
 '@T6G_MB_LIB.T6G(SCH_1):PAGE85_I538@PURE_QUANTA.SCONN288_DDR506112002KQ(CHIPS)':
 'VSS76': CDS_PINID='VSS76';
NODE_NAME     J1 180
 '@T6G_MB_LIB.T6G(SCH_1):PAGE85_I538@PURE_QUANTA.SCONN288_DDR506112002KQ(CHIPS)':
 'VSS77': CDS_PINID='VSS77';
NODE_NAME     J1 182
 '@T6G_MB_LIB.T6G(SCH_1):PAGE85_I538@PURE_QUANTA.SCONN288_DDR506112002KQ(CHIPS)':
 'VSS78': CDS_PINID='VSS78';
NODE_NAME     J1 184
 '@T6G_MB_LIB.T6G(SCH_1):PAGE85_I538@PURE_QUANTA.SCONN288_DDR506112002KQ(CHIPS)':
 'VSS79': CDS_PINID='VSS79';
NODE_NAME     J1 186
 '@T6G_MB_LIB.T6G(SCH_1):PAGE85_I538@PURE_QUANTA.SCONN288_DDR506112002KQ(CHIPS)':
 'VSS80': CDS_PINID='VSS80';
NODE_NAME     J1 188
 '@T6G_MB_LIB.T6G(SCH_1):PAGE85_I538@PURE_QUANTA.SCONN288_DDR506112002KQ(CHIPS)':
 'VSS81': CDS_PINID='VSS81';
NODE_NAME     J1 191
 '@T6G_MB_LIB.T6G(SCH_1):PAGE85_I538@PURE_QUANTA.SCONN288_DDR506112002KQ(CHIPS)':
 'VSS82': CDS_PINID='VSS82';
NODE_NAME     J1 193
 '@T6G_MB_LIB.T6G(SCH_1):PAGE85_I538@PURE_QUANTA.SCONN288_DDR506112002KQ(CHIPS)':
 'VSS83': CDS_PINID='VSS83';
NODE_NAME     J1 195
 '@T6G_MB_LIB.T6G(SCH_1):PAGE85_I538@PURE_QUANTA.SCONN288_DDR506112002KQ(CHIPS)':
 'VSS84': CDS_PINID='VSS84';
NODE_NAME     J1 197
 '@T6G_MB_LIB.T6G(SCH_1):PAGE85_I538@PURE_QUANTA.SCONN288_DDR506112002KQ(CHIPS)':
 'VSS85': CDS_PINID='VSS85';
NODE_NAME     J1 199
 '@T6G_MB_LIB.T6G(SCH_1):PAGE85_I538@PURE_QUANTA.SCONN288_DDR506112002KQ(CHIPS)':
 'VSS86': CDS_PINID='VSS86';
NODE_NAME     J1 202
 '@T6G_MB_LIB.T6G(SCH_1):PAGE85_I538@PURE_QUANTA.SCONN288_DDR506112002KQ(CHIPS)':
 'VSS87': CDS_PINID='VSS87';
NODE_NAME     J1 204
 '@T6G_MB_LIB.T6G(SCH_1):PAGE85_I538@PURE_QUANTA.SCONN288_DDR506112002KQ(CHIPS)':
 'VSS88': CDS_PINID='VSS88';
NODE_NAME     J1 206
 '@T6G_MB_LIB.T6G(SCH_1):PAGE85_I538@PURE_QUANTA.SCONN288_DDR506112002KQ(CHIPS)':
 'VSS89': CDS_PINID='VSS89';
NODE_NAME     J1 208
 '@T6G_MB_LIB.T6G(SCH_1):PAGE85_I538@PURE_QUANTA.SCONN288_DDR506112002KQ(CHIPS)':
 'VSS90': CDS_PINID='VSS90';
NODE_NAME     J1 210
 '@T6G_MB_LIB.T6G(SCH_1):PAGE85_I538@PURE_QUANTA.SCONN288_DDR506112002KQ(CHIPS)':
 'VSS91': CDS_PINID='VSS91';
NODE_NAME     J1 212
 '@T6G_MB_LIB.T6G(SCH_1):PAGE85_I538@PURE_QUANTA.SCONN288_DDR506112002KQ(CHIPS)':
 'VSS92': CDS_PINID='VSS92';
NODE_NAME     J1 214
 '@T6G_MB_LIB.T6G(SCH_1):PAGE85_I538@PURE_QUANTA.SCONN288_DDR506112002KQ(CHIPS)':
 'VSS93': CDS_PINID='VSS93';
NODE_NAME     J1 216
 '@T6G_MB_LIB.T6G(SCH_1):PAGE85_I538@PURE_QUANTA.SCONN288_DDR506112002KQ(CHIPS)':
 'VSS94': CDS_PINID='VSS94';
NODE_NAME     J1 219
 '@T6G_MB_LIB.T6G(SCH_1):PAGE85_I538@PURE_QUANTA.SCONN288_DDR506112002KQ(CHIPS)':
 'VSS95': CDS_PINID='VSS95';
NODE_NAME     J1 222
 '@T6G_MB_LIB.T6G(SCH_1):PAGE85_I538@PURE_QUANTA.SCONN288_DDR506112002KQ(CHIPS)':
 'VSS96': CDS_PINID='VSS96';
NODE_NAME     J1 224
 '@T6G_MB_LIB.T6G(SCH_1):PAGE85_I538@PURE_QUANTA.SCONN288_DDR506112002KQ(CHIPS)':
 'VSS97': CDS_PINID='VSS97';
NODE_NAME     J1 226
 '@T6G_MB_LIB.T6G(SCH_1):PAGE85_I538@PURE_QUANTA.SCONN288_DDR506112002KQ(CHIPS)':
 'VSS98': CDS_PINID='VSS98';
NODE_NAME     J1 228
 '@T6G_MB_LIB.T6G(SCH_1):PAGE85_I538@PURE_QUANTA.SCONN288_DDR506112002KQ(CHIPS)':
 'VSS99': CDS_PINID='VSS99';
NODE_NAME     J1 230
 '@T6G_MB_LIB.T6G(SCH_1):PAGE85_I538@PURE_QUANTA.SCONN288_DDR506112002KQ(CHIPS)':
 'VSS100': CDS_PINID='VSS100';
NODE_NAME     J1 233
 '@T6G_MB_LIB.T6G(SCH_1):PAGE85_I538@PURE_QUANTA.SCONN288_DDR506112002KQ(CHIPS)':
 'VSS101': CDS_PINID='VSS101';
NODE_NAME     J1 235
 '@T6G_MB_LIB.T6G(SCH_1):PAGE85_I538@PURE_QUANTA.SCONN288_DDR506112002KQ(CHIPS)':
 'VSS102': CDS_PINID='VSS102';
NODE_NAME     J1 237
 '@T6G_MB_LIB.T6G(SCH_1):PAGE85_I538@PURE_QUANTA.SCONN288_DDR506112002KQ(CHIPS)':
 'VSS103': CDS_PINID='VSS103';
NODE_NAME     J1 240
 '@T6G_MB_LIB.T6G(SCH_1):PAGE85_I538@PURE_QUANTA.SCONN288_DDR506112002KQ(CHIPS)':
 'VSS104': CDS_PINID='VSS104';
NODE_NAME     J1 242
 '@T6G_MB_LIB.T6G(SCH_1):PAGE85_I538@PURE_QUANTA.SCONN288_DDR506112002KQ(CHIPS)':
 'VSS105': CDS_PINID='VSS105';
NODE_NAME     J1 244
 '@T6G_MB_LIB.T6G(SCH_1):PAGE85_I538@PURE_QUANTA.SCONN288_DDR506112002KQ(CHIPS)':
 'VSS106': CDS_PINID='VSS106';
NODE_NAME     J1 246
 '@T6G_MB_LIB.T6G(SCH_1):PAGE85_I538@PURE_QUANTA.SCONN288_DDR506112002KQ(CHIPS)':
 'VSS107': CDS_PINID='VSS107';
NODE_NAME     J1 248
 '@T6G_MB_LIB.T6G(SCH_1):PAGE85_I538@PURE_QUANTA.SCONN288_DDR506112002KQ(CHIPS)':
 'VSS108': CDS_PINID='VSS108';
NODE_NAME     J1 251
 '@T6G_MB_LIB.T6G(SCH_1):PAGE85_I538@PURE_QUANTA.SCONN288_DDR506112002KQ(CHIPS)':
 'VSS109': CDS_PINID='VSS109';
NODE_NAME     J1 253
 '@T6G_MB_LIB.T6G(SCH_1):PAGE85_I538@PURE_QUANTA.SCONN288_DDR506112002KQ(CHIPS)':
 'VSS110': CDS_PINID='VSS110';
NODE_NAME     J1 255
 '@T6G_MB_LIB.T6G(SCH_1):PAGE85_I538@PURE_QUANTA.SCONN288_DDR506112002KQ(CHIPS)':
 'VSS111': CDS_PINID='VSS111';
NODE_NAME     J1 257
 '@T6G_MB_LIB.T6G(SCH_1):PAGE85_I538@PURE_QUANTA.SCONN288_DDR506112002KQ(CHIPS)':
 'VSS112': CDS_PINID='VSS112';
NODE_NAME     J1 259
 '@T6G_MB_LIB.T6G(SCH_1):PAGE85_I538@PURE_QUANTA.SCONN288_DDR506112002KQ(CHIPS)':
 'VSS113': CDS_PINID='VSS113';
NODE_NAME     J1 262
 '@T6G_MB_LIB.T6G(SCH_1):PAGE85_I538@PURE_QUANTA.SCONN288_DDR506112002KQ(CHIPS)':
 'VSS114': CDS_PINID='VSS114';
NODE_NAME     J1 264
 '@T6G_MB_LIB.T6G(SCH_1):PAGE85_I538@PURE_QUANTA.SCONN288_DDR506112002KQ(CHIPS)':
 'VSS115': CDS_PINID='VSS115';
NODE_NAME     J1 266
 '@T6G_MB_LIB.T6G(SCH_1):PAGE85_I538@PURE_QUANTA.SCONN288_DDR506112002KQ(CHIPS)':
 'VSS116': CDS_PINID='VSS116';
NODE_NAME     J1 268
 '@T6G_MB_LIB.T6G(SCH_1):PAGE85_I538@PURE_QUANTA.SCONN288_DDR506112002KQ(CHIPS)':
 'VSS117': CDS_PINID='VSS117';
NODE_NAME     J1 270
 '@T6G_MB_LIB.T6G(SCH_1):PAGE85_I538@PURE_QUANTA.SCONN288_DDR506112002KQ(CHIPS)':
 'VSS118': CDS_PINID='VSS118';
NODE_NAME     J1 273
 '@T6G_MB_LIB.T6G(SCH_1):PAGE85_I538@PURE_QUANTA.SCONN288_DDR506112002KQ(CHIPS)':
 'VSS119': CDS_PINID='VSS119';
NODE_NAME     J1 275
 '@T6G_MB_LIB.T6G(SCH_1):PAGE85_I538@PURE_QUANTA.SCONN288_DDR506112002KQ(CHIPS)':
 'VSS120': CDS_PINID='VSS120';
NODE_NAME     J1 277
 '@T6G_MB_LIB.T6G(SCH_1):PAGE85_I538@PURE_QUANTA.SCONN288_DDR506112002KQ(CHIPS)':
 'VSS121': CDS_PINID='VSS121';
NODE_NAME     J1 279
 '@T6G_MB_LIB.T6G(SCH_1):PAGE85_I538@PURE_QUANTA.SCONN288_DDR506112002KQ(CHIPS)':
 'VSS122': CDS_PINID='VSS122';
NODE_NAME     J1 281
 '@T6G_MB_LIB.T6G(SCH_1):PAGE85_I538@PURE_QUANTA.SCONN288_DDR506112002KQ(CHIPS)':
 'VSS123': CDS_PINID='VSS123';
NODE_NAME     J1 284
 '@T6G_MB_LIB.T6G(SCH_1):PAGE85_I538@PURE_QUANTA.SCONN288_DDR506112002KQ(CHIPS)':
 'VSS124': CDS_PINID='VSS124';
NODE_NAME     J1 286
 '@T6G_MB_LIB.T6G(SCH_1):PAGE85_I538@PURE_QUANTA.SCONN288_DDR506112002KQ(CHIPS)':
 'VSS125': CDS_PINID='VSS125';
NODE_NAME     J1 288
 '@T6G_MB_LIB.T6G(SCH_1):PAGE85_I538@PURE_QUANTA.SCONN288_DDR506112002KQ(CHIPS)':
 'VSS126': CDS_PINID='VSS126';
NODE_NAME     PR283 2
 '@T6G_MB_LIB.T6G(SCH_1):PAGE168_I4@PURE_QUANTA.Q_RES(CHIPS)':
 'B': CDS_PINID='B';
NODE_NAME     C461 2
 '@T6G_MB_LIB.T6G(SCH_1):PAGE168_I13@PURE_QUANTA.Q_CAP(CHIPS)':
 'B': CDS_PINID='B';
NODE_NAME     PR297 2
 '@T6G_MB_LIB.T6G(SCH_1):PAGE168_I36@PURE_QUANTA.Q_RES(CHIPS)':
 'B': CDS_PINID='B';
NODE_NAME     PR599 2
 '@T6G_MB_LIB.T6G(SCH_1):PAGE168_I47@PURE_QUANTA.Q_RES(CHIPS)':
 'B': CDS_PINID='B';
NODE_NAME     C299 2
 '@T6G_MB_LIB.T6G(SCH_1):PAGE168_I66@PURE_QUANTA.Q_CAP(CHIPS)':
 'B': CDS_PINID='B';
NODE_NAME     C302 2
 '@T6G_MB_LIB.T6G(SCH_1):PAGE168_I68@PURE_QUANTA.Q_CAP(CHIPS)':
 'B': CDS_PINID='B';
NODE_NAME     C468 2
 '@T6G_MB_LIB.T6G(SCH_1):PAGE168_I90@PURE_QUANTA.Q_CAP(CHIPS)':
 'B': CDS_PINID='B';
NODE_NAME     PC13 2
 '@T6G_MB_LIB.T6G(SCH_1):PAGE168_I118@PURE_QUANTA.Q_CAP(CHIPS)':
 'B': CDS_PINID='B';
NODE_NAME     PU43 2
 '@T6G_MB_LIB.T6G(SCH_1):PAGE169_I16@PURE_QUANTA.ISL99390FRZTR5935(CHIPS)':
 'AGND': CDS_PINID='AGND';
NODE_NAME     PU43 5
 '@T6G_MB_LIB.T6G(SCH_1):PAGE169_I16@PURE_QUANTA.ISL99390FRZTR5935(CHIPS)':
 'PGND1': CDS_PINID='PGND1';
NODE_NAME     PU43 7_9-20_24
 '@T6G_MB_LIB.T6G(SCH_1):PAGE169_I16@PURE_QUANTA.ISL99390FRZTR5935(CHIPS)':
 'PGND2': CDS_PINID='PGND2';
NODE_NAME     PU43 40
 '@T6G_MB_LIB.T6G(SCH_1):PAGE169_I16@PURE_QUANTA.ISL99390FRZTR5935(CHIPS)':
 'PGND3': CDS_PINID='PGND3';
NODE_NAME     PC478_C0P0_2 2
 '@T6G_MB_LIB.T6G(SCH_1):PAGE169_I19@PURE_QUANTA.Q_CAP(CHIPS)':
 'B': CDS_PINID='B';
NODE_NAME     PU6 2
 '@T6G_MB_LIB.T6G(SCH_1):PAGE169_I26@PURE_QUANTA.ISL99390FRZTR5935(CHIPS)':
 'AGND': CDS_PINID='AGND';
NODE_NAME     PU6 5
 '@T6G_MB_LIB.T6G(SCH_1):PAGE169_I26@PURE_QUANTA.ISL99390FRZTR5935(CHIPS)':
 'PGND1': CDS_PINID='PGND1';
NODE_NAME     PU6 7_9-20_24
 '@T6G_MB_LIB.T6G(SCH_1):PAGE169_I26@PURE_QUANTA.ISL99390FRZTR5935(CHIPS)':
 'PGND2': CDS_PINID='PGND2';
NODE_NAME     PU6 40
 '@T6G_MB_LIB.T6G(SCH_1):PAGE169_I26@PURE_QUANTA.ISL99390FRZTR5935(CHIPS)':
 'PGND3': CDS_PINID='PGND3';
NODE_NAME     PC482_2 2
 '@T6G_MB_LIB.T6G(SCH_1):PAGE169_I33@PURE_QUANTA.Q_CAP(CHIPS)':
 'B': CDS_PINID='B';
NODE_NAME     PC108 2
 '@T6G_MB_LIB.T6G(SCH_1):PAGE169_I64@PURE_QUANTA.Q_CAPP(CHIPS)':
 'B': CDS_PINID='B';
NODE_NAME     PC494 2
 '@T6G_MB_LIB.T6G(SCH_1):PAGE169_I65@PURE_QUANTA.Q_CAPP(CHIPS)':
 'B': CDS_PINID='B';
NODE_NAME     PC495 2
 '@T6G_MB_LIB.T6G(SCH_1):PAGE169_I66@PURE_QUANTA.Q_CAPP(CHIPS)':
 'B': CDS_PINID='B';
NODE_NAME     PC496 2
 '@T6G_MB_LIB.T6G(SCH_1):PAGE169_I67@PURE_QUANTA.Q_CAPP(CHIPS)':
 'B': CDS_PINID='B';
NODE_NAME     PC499_2 2
 '@T6G_MB_LIB.T6G(SCH_1):PAGE169_I68@PURE_QUANTA.Q_CAP(CHIPS)':
 'B': CDS_PINID='B';
NODE_NAME     PR499 2
 '@T6G_MB_LIB.T6G(SCH_1):PAGE170_I18@PURE_QUANTA.Q_RES(CHIPS)':
 'B': CDS_PINID='B';
NODE_NAME     PC551_4 2
 '@T6G_MB_LIB.T6G(SCH_1):PAGE170_I21@PURE_QUANTA.Q_CAP(CHIPS)':
 'B': CDS_PINID='B';
NODE_NAME     PC555_4 2
 '@T6G_MB_LIB.T6G(SCH_1):PAGE170_I23@PURE_QUANTA.Q_CAP(CHIPS)':
 'B': CDS_PINID='B';
NODE_NAME     PR346 1
 '@T6G_MB_LIB.T6G(SCH_1):PAGE170_I33@PURE_QUANTA.Q_RES(CHIPS)':
 'A': CDS_PINID='A';
NODE_NAME     PC578_8 2
 '@T6G_MB_LIB.T6G(SCH_1):PAGE173_I4@PURE_QUANTA.Q_CAP(CHIPS)':
 'B': CDS_PINID='B';
NODE_NAME     PR503 2
 '@T6G_MB_LIB.T6G(SCH_1):PAGE173_I19@PURE_QUANTA.Q_RES(CHIPS)':
 'B': CDS_PINID='B';
NODE_NAME     PC584_2 2
 '@T6G_MB_LIB.T6G(SCH_1):PAGE173_I23@PURE_QUANTA.Q_CAP(CHIPS)':
 'B': CDS_PINID='B';
NODE_NAME     PC588_2 2
 '@T6G_MB_LIB.T6G(SCH_1):PAGE173_I24@PURE_QUANTA.Q_CAP(CHIPS)':
 'B': CDS_PINID='B';
NODE_NAME     PC590_2 2
 '@T6G_MB_LIB.T6G(SCH_1):PAGE173_I25@PURE_QUANTA.Q_CAP(CHIPS)':
 'B': CDS_PINID='B';
NODE_NAME     PC577_7 2
 '@T6G_MB_LIB.T6G(SCH_1):PAGE173_I29@PURE_QUANTA.Q_CAP(CHIPS)':
 'B': CDS_PINID='B';
NODE_NAME     PC583_1 2
 '@T6G_MB_LIB.T6G(SCH_1):PAGE173_I43@PURE_QUANTA.Q_CAP(CHIPS)':
 'B': CDS_PINID='B';
NODE_NAME     PC597 2
 '@T6G_MB_LIB.T6G(SCH_1):PAGE173_I63@PURE_QUANTA.Q_CAPP(CHIPS)':
 'B': CDS_PINID='B';
NODE_NAME     PC601 2
 '@T6G_MB_LIB.T6G(SCH_1):PAGE173_I66@PURE_QUANTA.Q_CAPP(CHIPS)':
 'B': CDS_PINID='B';
NODE_NAME     PL63 3
 '@T6G_MB_LIB.T6G(SCH_1):PAGE173_I69@PURE_QUANTA.Q_INDUCTOR4P_14(CHIPS)':
 '3': CDS_PINID='\3\';
NODE_NAME     PC599 2
 '@T6G_MB_LIB.T6G(SCH_1):PAGE173_I79@PURE_QUANTA.Q_CAP(CHIPS)':
 'B': CDS_PINID='B';
NODE_NAME     PC604_1 2
 '@T6G_MB_LIB.T6G(SCH_1):PAGE173_I83@PURE_QUANTA.Q_CAP(CHIPS)':
 'B': CDS_PINID='B';
NODE_NAME     PR365 1
 '@T6G_MB_LIB.T6G(SCH_1):PAGE174_I7@PURE_QUANTA.Q_RES(CHIPS)':
 'A': CDS_PINID='A';
NODE_NAME     PC608_3 2
 '@T6G_MB_LIB.T6G(SCH_1):PAGE174_I21@PURE_QUANTA.Q_CAP(CHIPS)':
 'B': CDS_PINID='B';
NODE_NAME     PC610_3 2
 '@T6G_MB_LIB.T6G(SCH_1):PAGE174_I22@PURE_QUANTA.Q_CAP(CHIPS)':
 'B': CDS_PINID='B';
NODE_NAME     PC615_3 2
 '@T6G_MB_LIB.T6G(SCH_1):PAGE174_I29@PURE_QUANTA.Q_CAP(CHIPS)':
 'B': CDS_PINID='B';
NODE_NAME     PC611_3 2
 '@T6G_MB_LIB.T6G(SCH_1):PAGE174_I31@PURE_QUANTA.Q_CAP(CHIPS)':
 'B': CDS_PINID='B';
NODE_NAME     PC613_3 2
 '@T6G_MB_LIB.T6G(SCH_1):PAGE174_I32@PURE_QUANTA.Q_CAP(CHIPS)':
 'B': CDS_PINID='B';
NODE_NAME     PC609_3 2
 '@T6G_MB_LIB.T6G(SCH_1):PAGE174_I37@PURE_QUANTA.Q_CAP(CHIPS)':
 'B': CDS_PINID='B';
NODE_NAME     PU51 2
 '@T6G_MB_LIB.T6G(SCH_1):PAGE174_I38@PURE_QUANTA.ISL99390FRZTR5935(CHIPS)':
 'AGND': CDS_PINID='AGND';
NODE_NAME     PU51 5
 '@T6G_MB_LIB.T6G(SCH_1):PAGE174_I38@PURE_QUANTA.ISL99390FRZTR5935(CHIPS)':
 'PGND1': CDS_PINID='PGND1';
NODE_NAME     PU51 7_9-20_24
 '@T6G_MB_LIB.T6G(SCH_1):PAGE174_I38@PURE_QUANTA.ISL99390FRZTR5935(CHIPS)':
 'PGND2': CDS_PINID='PGND2';
NODE_NAME     PU51 40
 '@T6G_MB_LIB.T6G(SCH_1):PAGE174_I38@PURE_QUANTA.ISL99390FRZTR5935(CHIPS)':
 'PGND3': CDS_PINID='PGND3';
NODE_NAME     PC83_2 2
 '@T6G_MB_LIB.T6G(SCH_1):PAGE176_I2@PURE_QUANTA.Q_CAP(CHIPS)':
 'B': CDS_PINID='B';
NODE_NAME     PC79 2
 '@T6G_MB_LIB.T6G(SCH_1):PAGE176_I24@PURE_QUANTA.Q_CAP(CHIPS)':
 'B': CDS_PINID='B';
NODE_NAME     PC88_2 2
 '@T6G_MB_LIB.T6G(SCH_1):PAGE176_I47@PURE_QUANTA.Q_CAP(CHIPS)':
 'B': CDS_PINID='B';
NODE_NAME     PC95_1 2
 '@T6G_MB_LIB.T6G(SCH_1):PAGE176_I65@PURE_QUANTA.Q_CAP(CHIPS)':
 'B': CDS_PINID='B';
NODE_NAME     PC101 2
 '@T6G_MB_LIB.T6G(SCH_1):PAGE176_I66@PURE_QUANTA.Q_CAPP(CHIPS)':
 'B': CDS_PINID='B';
NODE_NAME     PC103 2
 '@T6G_MB_LIB.T6G(SCH_1):PAGE176_I75@PURE_QUANTA.Q_CAPP(CHIPS)':
 'B': CDS_PINID='B';
NODE_NAME     PC85 2
 '@T6G_MB_LIB.T6G(SCH_1):PAGE176_I87@PURE_QUANTA.Q_CAP(CHIPS)':
 'B': CDS_PINID='B';
NODE_NAME     PC113_4 2
 '@T6G_MB_LIB.T6G(SCH_1):PAGE177_I2@PURE_QUANTA.Q_CAP(CHIPS)':
 'B': CDS_PINID='B';
NODE_NAME     PL13 3
 '@T6G_MB_LIB.T6G(SCH_1):PAGE177_I42@PURE_QUANTA.Q_INDUCTOR4P_14(CHIPS)':
 '3': CDS_PINID='\3\';
NODE_NAME     PC128_4 2
 '@T6G_MB_LIB.T6G(SCH_1):PAGE177_I55@PURE_QUANTA.Q_CAP(CHIPS)':
 'B': CDS_PINID='B';
NODE_NAME     PC133_C1P0_5 2
 '@T6G_MB_LIB.T6G(SCH_1):PAGE178_I31@PURE_QUANTA.Q_CAP(CHIPS)':
 'B': CDS_PINID='B';
NODE_NAME     PC114_6 2
 '@T6G_MB_LIB.T6G(SCH_1):PAGE178_I40@PURE_QUANTA.Q_CAP(CHIPS)':
 'B': CDS_PINID='B';
NODE_NAME     PC135_5 2
 '@T6G_MB_LIB.T6G(SCH_1):PAGE178_I59@PURE_QUANTA.Q_CAP(CHIPS)':
 'B': CDS_PINID='B';
NODE_NAME     PC136_5 2
 '@T6G_MB_LIB.T6G(SCH_1):PAGE178_I60@PURE_QUANTA.Q_CAP(CHIPS)':
 'B': CDS_PINID='B';
NODE_NAME     PC182_4 2
 '@T6G_MB_LIB.T6G(SCH_1):PAGE181_I46@PURE_QUANTA.Q_CAP(CHIPS)':
 'B': CDS_PINID='B';
NODE_NAME     PR379 2
 '@T6G_MB_LIB.T6G(SCH_1):PAGE181_I55@PURE_QUANTA.Q_RES(CHIPS)':
 'B': CDS_PINID='B';
NODE_NAME     PC191_4 2
 '@T6G_MB_LIB.T6G(SCH_1):PAGE181_I68@PURE_QUANTA.Q_CAP(CHIPS)':
 'B': CDS_PINID='B';
NODE_NAME     PC192_3 2
 '@T6G_MB_LIB.T6G(SCH_1):PAGE181_I71@PURE_QUANTA.Q_CAP(CHIPS)':
 'B': CDS_PINID='B';
NODE_NAME     C196 2
 '@T6G_MB_LIB.T6G(SCH_1):PAGE182_I47@PURE_QUANTA.Q_CAP(CHIPS)':
 'B': CDS_PINID='B';
NODE_NAME     PC9 2
 '@T6G_MB_LIB.T6G(SCH_1):PAGE182_I77@PURE_QUANTA.Q_CAP(CHIPS)':
 'B': CDS_PINID='B';
NODE_NAME     PC200 2
 '@T6G_MB_LIB.T6G(SCH_1):PAGE182_I82@PURE_QUANTA.Q_CAP(CHIPS)':
 'B': CDS_PINID='B';
NODE_NAME     PR389 2
 '@T6G_MB_LIB.T6G(SCH_1):PAGE183_I24@PURE_QUANTA.Q_RES(CHIPS)':
 'B': CDS_PINID='B';
NODE_NAME     PC210_2 2
 '@T6G_MB_LIB.T6G(SCH_1):PAGE183_I27@PURE_QUANTA.Q_CAP(CHIPS)':
 'B': CDS_PINID='B';
NODE_NAME     PC208_2 2
 '@T6G_MB_LIB.T6G(SCH_1):PAGE183_I29@PURE_QUANTA.Q_CAP(CHIPS)':
 'B': CDS_PINID='B';
NODE_NAME     PC201_1 2
 '@T6G_MB_LIB.T6G(SCH_1):PAGE183_I34@PURE_QUANTA.Q_CAP(CHIPS)':
 'B': CDS_PINID='B';
NODE_NAME     PR133 1
 '@T6G_MB_LIB.T6G(SCH_1):PAGE183_I37@PURE_QUANTA.Q_RES(CHIPS)':
 'A': CDS_PINID='A';
NODE_NAME     PC209_1 2
 '@T6G_MB_LIB.T6G(SCH_1):PAGE183_I44@PURE_QUANTA.Q_CAP(CHIPS)':
 'B': CDS_PINID='B';
NODE_NAME     PC211_1 2
 '@T6G_MB_LIB.T6G(SCH_1):PAGE183_I48@PURE_QUANTA.Q_CAP(CHIPS)':
 'B': CDS_PINID='B';
NODE_NAME     PC229 2
 '@T6G_MB_LIB.T6G(SCH_1):PAGE183_I66@PURE_QUANTA.Q_CAPP(CHIPS)':
 'B': CDS_PINID='B';
NODE_NAME     PC230 2
 '@T6G_MB_LIB.T6G(SCH_1):PAGE183_I67@PURE_QUANTA.Q_CAPP(CHIPS)':
 'B': CDS_PINID='B';
NODE_NAME     PC801 2
 '@T6G_MB_LIB.T6G(SCH_1):PAGE183_I70@PURE_QUANTA.Q_CAPP(CHIPS)':
 'B': CDS_PINID='B';
NODE_NAME     PC6003 2
 '@T6G_MB_LIB.T6G(SCH_1):PAGE183_I79@PURE_QUANTA.Q_CAP(CHIPS)':
 'B': CDS_PINID='B';
NODE_NAME     PC224_1 2
 '@T6G_MB_LIB.T6G(SCH_1):PAGE183_I81@PURE_QUANTA.Q_CAP(CHIPS)':
 'B': CDS_PINID='B';
NODE_NAME     PR150 2
 '@T6G_MB_LIB.T6G(SCH_1):PAGE185_I4@PURE_QUANTA.Q_RES(CHIPS)':
 'B': CDS_PINID='B';
NODE_NAME     C242 2
 '@T6G_MB_LIB.T6G(SCH_1):PAGE185_I13@PURE_QUANTA.Q_CAP(CHIPS)':
 'B': CDS_PINID='B';
NODE_NAME     PR164 2
 '@T6G_MB_LIB.T6G(SCH_1):PAGE185_I36@PURE_QUANTA.Q_RES(CHIPS)':
 'B': CDS_PINID='B';
NODE_NAME     C295 2
 '@T6G_MB_LIB.T6G(SCH_1):PAGE185_I62@PURE_QUANTA.Q_CAP(CHIPS)':
 'B': CDS_PINID='B';
NODE_NAME     C249 2
 '@T6G_MB_LIB.T6G(SCH_1):PAGE185_I86@PURE_QUANTA.Q_CAP(CHIPS)':
 'B': CDS_PINID='B';
NODE_NAME     C248 2
 '@T6G_MB_LIB.T6G(SCH_1):PAGE185_I88@PURE_QUANTA.Q_CAP(CHIPS)':
 'B': CDS_PINID='B';
NODE_NAME     PC11 2
 '@T6G_MB_LIB.T6G(SCH_1):PAGE185_I114@PURE_QUANTA.Q_CAP(CHIPS)':
 'B': CDS_PINID='B';
NODE_NAME     PC259_C0P1_2 2
 '@T6G_MB_LIB.T6G(SCH_1):PAGE186_I13@PURE_QUANTA.Q_CAP(CHIPS)':
 'B': CDS_PINID='B';
NODE_NAME     PC254_1 2
 '@T6G_MB_LIB.T6G(SCH_1):PAGE186_I16@PURE_QUANTA.Q_CAP(CHIPS)':
 'B': CDS_PINID='B';
NODE_NAME     PC263_2 2
 '@T6G_MB_LIB.T6G(SCH_1):PAGE186_I26@PURE_QUANTA.Q_CAP(CHIPS)':
 'B': CDS_PINID='B';
NODE_NAME     PC269_2 2
 '@T6G_MB_LIB.T6G(SCH_1):PAGE186_I31@PURE_QUANTA.Q_CAP(CHIPS)':
 'B': CDS_PINID='B';
NODE_NAME     PC260_1 2
 '@T6G_MB_LIB.T6G(SCH_1):PAGE186_I46@PURE_QUANTA.Q_CAP(CHIPS)':
 'B': CDS_PINID='B';
NODE_NAME     PC282_2 2
 '@T6G_MB_LIB.T6G(SCH_1):PAGE186_I63@PURE_QUANTA.Q_CAP(CHIPS)':
 'B': CDS_PINID='B';
NODE_NAME     PC279 2
 '@T6G_MB_LIB.T6G(SCH_1):PAGE186_I66@PURE_QUANTA.Q_CAPP(CHIPS)':
 'B': CDS_PINID='B';
NODE_NAME     PC273 2
 '@T6G_MB_LIB.T6G(SCH_1):PAGE186_I71@PURE_QUANTA.Q_CAPP(CHIPS)':
 'B': CDS_PINID='B';
NODE_NAME     PC318_8 2
 '@T6G_MB_LIB.T6G(SCH_1):PAGE190_I4@PURE_QUANTA.Q_CAP(CHIPS)':
 'B': CDS_PINID='B';
NODE_NAME     PC326_2 2
 '@T6G_MB_LIB.T6G(SCH_1):PAGE190_I22@PURE_QUANTA.Q_CAP(CHIPS)':
 'B': CDS_PINID='B';
NODE_NAME     PC324_2 2
 '@T6G_MB_LIB.T6G(SCH_1):PAGE190_I25@PURE_QUANTA.Q_CAP(CHIPS)':
 'B': CDS_PINID='B';
NODE_NAME     PC328_2 2
 '@T6G_MB_LIB.T6G(SCH_1):PAGE190_I26@PURE_QUANTA.Q_CAP(CHIPS)':
 'B': CDS_PINID='B';
NODE_NAME     PR525 2
 '@T6G_MB_LIB.T6G(SCH_1):PAGE190_I29@PURE_QUANTA.Q_RES(CHIPS)':
 'B': CDS_PINID='B';
NODE_NAME     PC325_1 2
 '@T6G_MB_LIB.T6G(SCH_1):PAGE190_I43@PURE_QUANTA.Q_CAP(CHIPS)':
 'B': CDS_PINID='B';
NODE_NAME     PC323_1 2
 '@T6G_MB_LIB.T6G(SCH_1):PAGE190_I44@PURE_QUANTA.Q_CAP(CHIPS)':
 'B': CDS_PINID='B';
NODE_NAME     PC327_1 2
 '@T6G_MB_LIB.T6G(SCH_1):PAGE190_I48@PURE_QUANTA.Q_CAP(CHIPS)':
 'B': CDS_PINID='B';
NODE_NAME     PC340 2
 '@T6G_MB_LIB.T6G(SCH_1):PAGE190_I63@PURE_QUANTA.Q_CAPP(CHIPS)':
 'B': CDS_PINID='B';
NODE_NAME     PC343 2
 '@T6G_MB_LIB.T6G(SCH_1):PAGE190_I66@PURE_QUANTA.Q_CAPP(CHIPS)':
 'B': CDS_PINID='B';
NODE_NAME     PL35 3
 '@T6G_MB_LIB.T6G(SCH_1):PAGE190_I69@PURE_QUANTA.Q_INDUCTOR4P_14(CHIPS)':
 '3': CDS_PINID='\3\';
NODE_NAME     PC338 2
 '@T6G_MB_LIB.T6G(SCH_1):PAGE190_I79@PURE_QUANTA.Q_CAP(CHIPS)':
 'B': CDS_PINID='B';
NODE_NAME     PC344_1 2
 '@T6G_MB_LIB.T6G(SCH_1):PAGE190_I81@PURE_QUANTA.Q_CAP(CHIPS)':
 'B': CDS_PINID='B';
NODE_NAME     PR339 2
 '@T6G_MB_LIB.T6G(SCH_1):PAGE190_I83@PURE_QUANTA.Q_RES(CHIPS)':
 'B': CDS_PINID='B';
NODE_NAME     PR214 1
 '@T6G_MB_LIB.T6G(SCH_1):PAGE191_I7@PURE_QUANTA.Q_RES(CHIPS)':
 'A': CDS_PINID='A';
NODE_NAME     PC347_SOP1_3 2
 '@T6G_MB_LIB.T6G(SCH_1):PAGE191_I18@PURE_QUANTA.Q_CAP(CHIPS)':
 'B': CDS_PINID='B';
NODE_NAME     PC349_3 2
 '@T6G_MB_LIB.T6G(SCH_1):PAGE191_I20@PURE_QUANTA.Q_CAP(CHIPS)':
 'B': CDS_PINID='B';
NODE_NAME     PC350_3 2
 '@T6G_MB_LIB.T6G(SCH_1):PAGE191_I22@PURE_QUANTA.Q_CAP(CHIPS)':
 'B': CDS_PINID='B';
NODE_NAME     PL34 1
 '@T6G_MB_LIB.T6G(SCH_1):PAGE191_I25@PURE_QUANTA.Q_INDUCTOR(CHIPS)':
 '1': CDS_PINID='\1\';
NODE_NAME     PC351_3 2
 '@T6G_MB_LIB.T6G(SCH_1):PAGE191_I31@PURE_QUANTA.Q_CAP(CHIPS)':
 'B': CDS_PINID='B';
NODE_NAME     PC352_3 2
 '@T6G_MB_LIB.T6G(SCH_1):PAGE191_I32@PURE_QUANTA.Q_CAP(CHIPS)':
 'B': CDS_PINID='B';
NODE_NAME     PC353_3 2
 '@T6G_MB_LIB.T6G(SCH_1):PAGE191_I34@PURE_QUANTA.Q_CAP(CHIPS)':
 'B': CDS_PINID='B';
NODE_NAME     PU32 2
 '@T6G_MB_LIB.T6G(SCH_1):PAGE191_I38@PURE_QUANTA.ISL99390FRZTR5935(CHIPS)':
 'AGND': CDS_PINID='AGND';
NODE_NAME     PU32 5
 '@T6G_MB_LIB.T6G(SCH_1):PAGE191_I38@PURE_QUANTA.ISL99390FRZTR5935(CHIPS)':
 'PGND1': CDS_PINID='PGND1';
NODE_NAME     PU32 7_9-20_24
 '@T6G_MB_LIB.T6G(SCH_1):PAGE191_I38@PURE_QUANTA.ISL99390FRZTR5935(CHIPS)':
 'PGND2': CDS_PINID='PGND2';
NODE_NAME     PU32 40
 '@T6G_MB_LIB.T6G(SCH_1):PAGE191_I38@PURE_QUANTA.ISL99390FRZTR5935(CHIPS)':
 'PGND3': CDS_PINID='PGND3';
NODE_NAME     PC373_2 2
 '@T6G_MB_LIB.T6G(SCH_1):PAGE193_I2@PURE_QUANTA.Q_CAP(CHIPS)':
 'B': CDS_PINID='B';
NODE_NAME     PC369 2
 '@T6G_MB_LIB.T6G(SCH_1):PAGE193_I23@PURE_QUANTA.Q_CAP(CHIPS)':
 'B': CDS_PINID='B';
NODE_NAME     PC382_2 2
 '@T6G_MB_LIB.T6G(SCH_1):PAGE193_I46@PURE_QUANTA.Q_CAP(CHIPS)':
 'B': CDS_PINID='B';
NODE_NAME     PC106 2
 '@T6G_MB_LIB.T6G(SCH_1):PAGE193_I65@PURE_QUANTA.Q_CAPP(CHIPS)':
 'B': CDS_PINID='B';
NODE_NAME     PC387 2
 '@T6G_MB_LIB.T6G(SCH_1):PAGE193_I66@PURE_QUANTA.Q_CAPP(CHIPS)':
 'B': CDS_PINID='B';
NODE_NAME     PC388 2
 '@T6G_MB_LIB.T6G(SCH_1):PAGE193_I67@PURE_QUANTA.Q_CAPP(CHIPS)':
 'B': CDS_PINID='B';
NODE_NAME     PC391 2
 '@T6G_MB_LIB.T6G(SCH_1):PAGE193_I74@PURE_QUANTA.Q_CAPP(CHIPS)':
 'B': CDS_PINID='B';
NODE_NAME     PR342 2
 '@T6G_MB_LIB.T6G(SCH_1):PAGE193_I87@PURE_QUANTA.Q_RES(CHIPS)':
 'B': CDS_PINID='B';
NODE_NAME     PC403_4 2
 '@T6G_MB_LIB.T6G(SCH_1):PAGE194_I2@PURE_QUANTA.Q_CAP(CHIPS)':
 'B': CDS_PINID='B';
NODE_NAME     PC409_4 2
 '@T6G_MB_LIB.T6G(SCH_1):PAGE194_I42@PURE_QUANTA.Q_CAP(CHIPS)':
 'B': CDS_PINID='B';
NODE_NAME     PL43 3
 '@T6G_MB_LIB.T6G(SCH_1):PAGE194_I50@PURE_QUANTA.Q_INDUCTOR4P_14(CHIPS)':
 '3': CDS_PINID='\3\';
NODE_NAME     PC410_3 2
 '@T6G_MB_LIB.T6G(SCH_1):PAGE194_I55@PURE_QUANTA.Q_CAP(CHIPS)':
 'B': CDS_PINID='B';
NODE_NAME     PC423_C1P1_5 2
 '@T6G_MB_LIB.T6G(SCH_1):PAGE195_I31@PURE_QUANTA.Q_CAP(CHIPS)':
 'B': CDS_PINID='B';
NODE_NAME     PC140_6 2
 '@T6G_MB_LIB.T6G(SCH_1):PAGE195_I40@PURE_QUANTA.Q_CAP(CHIPS)':
 'B': CDS_PINID='B';
NODE_NAME     PC427_5 2
 '@T6G_MB_LIB.T6G(SCH_1):PAGE195_I60@PURE_QUANTA.Q_CAP(CHIPS)':
 'B': CDS_PINID='B';
NODE_NAME     PC621_10 2
 '@T6G_MB_LIB.T6G(SCH_1):PAGE198_I2@PURE_QUANTA.Q_CAP(CHIPS)':
 'B': CDS_PINID='B';
NODE_NAME     PU53 2
 '@T6G_MB_LIB.T6G(SCH_1):PAGE198_I15@PURE_QUANTA.ISL99390FRZTR5935(CHIPS)':
 'AGND': CDS_PINID='AGND';
NODE_NAME     PU53 5
 '@T6G_MB_LIB.T6G(SCH_1):PAGE198_I15@PURE_QUANTA.ISL99390FRZTR5935(CHIPS)':
 'PGND1': CDS_PINID='PGND1';
NODE_NAME     PU53 7_9-20_24
 '@T6G_MB_LIB.T6G(SCH_1):PAGE198_I15@PURE_QUANTA.ISL99390FRZTR5935(CHIPS)':
 'PGND2': CDS_PINID='PGND2';
NODE_NAME     PU53 40
 '@T6G_MB_LIB.T6G(SCH_1):PAGE198_I15@PURE_QUANTA.ISL99390FRZTR5935(CHIPS)':
 'PGND3': CDS_PINID='PGND3';
NODE_NAME     PC617 2
 '@T6G_MB_LIB.T6G(SCH_1):PAGE198_I28@PURE_QUANTA.Q_CAP(CHIPS)':
 'B': CDS_PINID='B';
NODE_NAME     PC629_4 2
 '@T6G_MB_LIB.T6G(SCH_1):PAGE198_I46@PURE_QUANTA.Q_CAP(CHIPS)':
 'B': CDS_PINID='B';
NODE_NAME     PC634_4 2
 '@T6G_MB_LIB.T6G(SCH_1):PAGE198_I51@PURE_QUANTA.Q_CAP(CHIPS)':
 'B': CDS_PINID='B';
NODE_NAME     PR492 2
 '@T6G_MB_LIB.T6G(SCH_1):PAGE198_I57@PURE_QUANTA.Q_RES(CHIPS)':
 'B': CDS_PINID='B';
NODE_NAME     PC632_3 2
 '@T6G_MB_LIB.T6G(SCH_1):PAGE198_I65@PURE_QUANTA.Q_CAP(CHIPS)':
 'B': CDS_PINID='B';
NODE_NAME     PC635_3 2
 '@T6G_MB_LIB.T6G(SCH_1):PAGE198_I68@PURE_QUANTA.Q_CAP(CHIPS)':
 'B': CDS_PINID='B';
NODE_NAME     R3118 2
 '@T6G_MB_LIB.T6G(SCH_1):PAGE245_I2@PURE_QUANTA.Q_RES(CHIPS)':
 'B': CDS_PINID='B';
NODE_NAME     PC1870 2
 '@T6G_MB_LIB.T6G(SCH_1):PAGE245_I8@PURE_QUANTA.Q_CAP(CHIPS)':
 'B': CDS_PINID='B';
NODE_NAME     PR833 2
 '@T6G_MB_LIB.T6G(SCH_1):PAGE245_I15@PURE_QUANTA.Q_RES(CHIPS)':
 'B': CDS_PINID='B';
NODE_NAME     PR834 2
 '@T6G_MB_LIB.T6G(SCH_1):PAGE245_I17@PURE_QUANTA.Q_RES(CHIPS)':
 'B': CDS_PINID='B';
NODE_NAME     PU9 32
 '@T6G_MB_LIB.T6G(SCH_1):PAGE245_I21@PURE_QUANTA.NCP3284AMNTXG(CHIPS)':
 'AGND': CDS_PINID='AGND';
NODE_NAME     PU9 7_10-19
 '@T6G_MB_LIB.T6G(SCH_1):PAGE245_I21@PURE_QUANTA.NCP3284AMNTXG(CHIPS)':
 'PGND': CDS_PINID='PGND';
NODE_NAME     PU9 31
 '@T6G_MB_LIB.T6G(SCH_1):PAGE245_I21@PURE_QUANTA.NCP3284AMNTXG(CHIPS)':
 'VSNS-': CDS_PINID='\vsns-\';
NODE_NAME     PC1649 2
 '@T6G_MB_LIB.T6G(SCH_1):PAGE245_I23@PURE_QUANTA.Q_CAP(CHIPS)':
 'B': CDS_PINID='B';
NODE_NAME     PC2260 2
 '@T6G_MB_LIB.T6G(SCH_1):PAGE245_I26@PURE_QUANTA.Q_CAP(CHIPS)':
 'B': CDS_PINID='B';
NODE_NAME     PC3 2
 '@T6G_MB_LIB.T6G(SCH_1):PAGE245_I29@PURE_QUANTA.Q_CAPP(CHIPS)':
 'B': CDS_PINID='B';
NODE_NAME     PC566 2
 '@T6G_MB_LIB.T6G(SCH_1):PAGE245_I30@PURE_QUANTA.Q_CAPP(CHIPS)':
 'B': CDS_PINID='B';
NODE_NAME     PC2262 2
 '@T6G_MB_LIB.T6G(SCH_1):PAGE245_I31@PURE_QUANTA.Q_CAP(CHIPS)':
 'B': CDS_PINID='B';
NODE_NAME     PC8567 2
 '@T6G_MB_LIB.T6G(SCH_1):PAGE245_I32@PURE_QUANTA.Q_CAP(CHIPS)':
 'B': CDS_PINID='B';
NODE_NAME     PC2263 2
 '@T6G_MB_LIB.T6G(SCH_1):PAGE245_I33@PURE_QUANTA.Q_CAP(CHIPS)':
 'B': CDS_PINID='B';
NODE_NAME     PC2342 2
 '@T6G_MB_LIB.T6G(SCH_1):PAGE245_I34@PURE_QUANTA.Q_CAP(CHIPS)':
 'B': CDS_PINID='B';
NODE_NAME     PC570 2
 '@T6G_MB_LIB.T6G(SCH_1):PAGE245_I35@PURE_QUANTA.Q_CAP(CHIPS)':
 'B': CDS_PINID='B';
NODE_NAME     PC571 2
 '@T6G_MB_LIB.T6G(SCH_1):PAGE245_I36@PURE_QUANTA.Q_CAP(CHIPS)':
 'B': CDS_PINID='B';
NODE_NAME     PC2343 2
 '@T6G_MB_LIB.T6G(SCH_1):PAGE245_I37@PURE_QUANTA.Q_CAP(CHIPS)':
 'B': CDS_PINID='B';
NODE_NAME     PC2344 2
 '@T6G_MB_LIB.T6G(SCH_1):PAGE245_I38@PURE_QUANTA.Q_CAP(CHIPS)':
 'B': CDS_PINID='B';
NODE_NAME     PC576 2
 '@T6G_MB_LIB.T6G(SCH_1):PAGE245_I39@PURE_QUANTA.Q_CAP(CHIPS)':
 'B': CDS_PINID='B';
NODE_NAME     PC8071 2
 '@T6G_MB_LIB.T6G(SCH_1):PAGE245_I40@PURE_QUANTA.Q_CAP(CHIPS)':
 'B': CDS_PINID='B';
NODE_NAME     PC577 2
 '@T6G_MB_LIB.T6G(SCH_1):PAGE245_I41@PURE_QUANTA.Q_CAP(CHIPS)':
 'B': CDS_PINID='B';
NODE_NAME     PR830 2
 '@T6G_MB_LIB.T6G(SCH_1):PAGE245_I51@PURE_QUANTA.Q_RES(CHIPS)':
 'B': CDS_PINID='B';
NODE_NAME     PC1866 2
 '@T6G_MB_LIB.T6G(SCH_1):PAGE245_I57@PURE_QUANTA.Q_CAPP(CHIPS)':
 'B': CDS_PINID='B';
NODE_NAME     PC1867 2
 '@T6G_MB_LIB.T6G(SCH_1):PAGE245_I58@PURE_QUANTA.Q_CAPP(CHIPS)':
 'B': CDS_PINID='B';
NODE_NAME     PC1868 2
 '@T6G_MB_LIB.T6G(SCH_1):PAGE245_I59@PURE_QUANTA.Q_CAP(CHIPS)':
 'B': CDS_PINID='B';
NODE_NAME     PC1600 2
 '@T6G_MB_LIB.T6G(SCH_1):PAGE245_I62@PURE_QUANTA.Q_CAP(CHIPS)':
 'B': CDS_PINID='B';
NODE_NAME     PC1869 2
 '@T6G_MB_LIB.T6G(SCH_1):PAGE245_I63@PURE_QUANTA.Q_CAP(CHIPS)':
 'B': CDS_PINID='B';
NODE_NAME     R3430 2
 '@T6G_MB_LIB.T6G(SCH_1):PAGE299_I3@PURE_QUANTA.Q_RES(CHIPS)':
 'B': CDS_PINID='B';
NODE_NAME     R3428 2
 '@T6G_MB_LIB.T6G(SCH_1):PAGE299_I17@PURE_QUANTA.Q_RES(CHIPS)':
 'B': CDS_PINID='B';
NODE_NAME     Q104 1
 '@T6G_MB_LIB.T6G(SCH_1):PAGE299_I21@PURE_QUANTA.MOSFET_NCH_DUAL(CHIPS)':
 'S1': CDS_PINID='S1';
NODE_NAME     Q104 4
 '@T6G_MB_LIB.T6G(SCH_1):PAGE299_I26@PURE_QUANTA.MOSFET_NCH_DUAL(CHIPS)':
 'S2': CDS_PINID='S2';
NODE_NAME     C1976 2
 '@T6G_MB_LIB.T6G(SCH_1):PAGE299_I30@PURE_QUANTA.Q_CAP(CHIPS)':
 'B': CDS_PINID='B';
NODE_NAME     Q103 1
 '@T6G_MB_LIB.T6G(SCH_1):PAGE299_I37@PURE_QUANTA.MOSFET_NCH_DUAL(CHIPS)':
 'S1': CDS_PINID='S1';
NODE_NAME     Q102 1
 '@T6G_MB_LIB.T6G(SCH_1):PAGE299_I40@PURE_QUANTA.MOSFET_NCH_DUAL(CHIPS)':
 'S1': CDS_PINID='S1';
NODE_NAME     Q103 4
 '@T6G_MB_LIB.T6G(SCH_1):PAGE299_I43@PURE_QUANTA.MOSFET_NCH_DUAL(CHIPS)':
 'S2': CDS_PINID='S2';
NODE_NAME     Q102 4
 '@T6G_MB_LIB.T6G(SCH_1):PAGE299_I48@PURE_QUANTA.MOSFET_NCH_DUAL(CHIPS)':
 'S2': CDS_PINID='S2';
NODE_NAME     Q101 1
 '@T6G_MB_LIB.T6G(SCH_1):PAGE299_I52@PURE_QUANTA.MOSFET_NCH_DUAL(CHIPS)':
 'S1': CDS_PINID='S1';
NODE_NAME     Q101 4
 '@T6G_MB_LIB.T6G(SCH_1):PAGE299_I57@PURE_QUANTA.MOSFET_NCH_DUAL(CHIPS)':
 'S2': CDS_PINID='S2';
NODE_NAME     C1973 2
 '@T6G_MB_LIB.T6G(SCH_1):PAGE299_I71@PURE_QUANTA.Q_CAP(CHIPS)':
 'B': CDS_PINID='B';
NODE_NAME     C1974 2
 '@T6G_MB_LIB.T6G(SCH_1):PAGE299_I74@PURE_QUANTA.Q_CAP(CHIPS)':
 'B': CDS_PINID='B';
NODE_NAME     C1975 2
 '@T6G_MB_LIB.T6G(SCH_1):PAGE299_I129@PURE_QUANTA.Q_CAP(CHIPS)':
 'B': CDS_PINID='B';
NODE_NAME     R3463 2
 '@T6G_MB_LIB.T6G(SCH_1):PAGE299_I131@PURE_QUANTA.Q_RES(CHIPS)':
 'B': CDS_PINID='B';
NODE_NAME     R3431 2
 '@T6G_MB_LIB.T6G(SCH_1):PAGE299_I133@PURE_QUANTA.Q_RES(CHIPS)':
 'B': CDS_PINID='B';
NODE_NAME     C1978 2
 '@T6G_MB_LIB.T6G(SCH_1):PAGE299_I152@PURE_QUANTA.Q_CAP(CHIPS)':
 'B': CDS_PINID='B';
NODE_NAME     Q107 4
 '@T6G_MB_LIB.T6G(SCH_1):PAGE299_I157@PURE_QUANTA.MOSFET_NCH_DUAL(CHIPS)':
 'S2': CDS_PINID='S2';
NODE_NAME     Q107 1
 '@T6G_MB_LIB.T6G(SCH_1):PAGE299_I160@PURE_QUANTA.MOSFET_NCH_DUAL(CHIPS)':
 'S1': CDS_PINID='S1';
NODE_NAME     R3473 2
 '@T6G_MB_LIB.T6G(SCH_1):PAGE299_I163@PURE_QUANTA.Q_RES(CHIPS)':
 'B': CDS_PINID='B';
NODE_NAME     Q108 4
 '@T6G_MB_LIB.T6G(SCH_1):PAGE299_I168@PURE_QUANTA.MOSFET_NCH_DUAL(CHIPS)':
 'S2': CDS_PINID='S2';
NODE_NAME     Q108 1
 '@T6G_MB_LIB.T6G(SCH_1):PAGE299_I169@PURE_QUANTA.MOSFET_NCH_DUAL(CHIPS)':
 'S1': CDS_PINID='S1';
NODE_NAME     C1988 2
 '@T6G_MB_LIB.T6G(SCH_1):PAGE299_I171@PURE_QUANTA.Q_CAP(CHIPS)':
 'B': CDS_PINID='B';
NODE_NAME     R3502 2
 '@T6G_MB_LIB.T6G(SCH_1):PAGE299_I181@PURE_QUANTA.Q_RES(CHIPS)':
 'B': CDS_PINID='B';
NODE_NAME     R4161 2
 '@T6G_MB_LIB.T6G(SCH_1):PAGE331_I2@PURE_QUANTA.Q_RES(CHIPS)':
 'B': CDS_PINID='B';
NODE_NAME     R4163 2
 '@T6G_MB_LIB.T6G(SCH_1):PAGE331_I8@PURE_QUANTA.Q_RES(CHIPS)':
 'B': CDS_PINID='B';
NODE_NAME     R4159 2
 '@T6G_MB_LIB.T6G(SCH_1):PAGE331_I13@PURE_QUANTA.Q_RES(CHIPS)':
 'B': CDS_PINID='B';
NODE_NAME     Q136 1
 '@T6G_MB_LIB.T6G(SCH_1):PAGE331_I17@PURE_QUANTA.MOSFET_NCH_DUAL(CHIPS)':
 'S1': CDS_PINID='S1';
NODE_NAME     Q137 1
 '@T6G_MB_LIB.T6G(SCH_1):PAGE331_I21@PURE_QUANTA.MOSFET_NCH_DUAL(CHIPS)':
 'S1': CDS_PINID='S1';
NODE_NAME     Q136 4
 '@T6G_MB_LIB.T6G(SCH_1):PAGE331_I22@PURE_QUANTA.MOSFET_NCH_DUAL(CHIPS)':
 'S2': CDS_PINID='S2';
NODE_NAME     Q135 1
 '@T6G_MB_LIB.T6G(SCH_1):PAGE331_I25@PURE_QUANTA.MOSFET_NCH_DUAL(CHIPS)':
 'S1': CDS_PINID='S1';
NODE_NAME     Q137 4
 '@T6G_MB_LIB.T6G(SCH_1):PAGE331_I28@PURE_QUANTA.MOSFET_NCH_DUAL(CHIPS)':
 'S2': CDS_PINID='S2';
NODE_NAME     Q135 4
 '@T6G_MB_LIB.T6G(SCH_1):PAGE331_I29@PURE_QUANTA.MOSFET_NCH_DUAL(CHIPS)':
 'S2': CDS_PINID='S2';
NODE_NAME     C5 2
 '@T6G_MB_LIB.T6G(SCH_1):PAGE331_I33@PURE_QUANTA.Q_CAP(CHIPS)':
 'B': CDS_PINID='B';
NODE_NAME     C7 2
 '@T6G_MB_LIB.T6G(SCH_1):PAGE331_I42@PURE_QUANTA.Q_CAP(CHIPS)':
 'B': CDS_PINID='B';
NODE_NAME     C4 2
 '@T6G_MB_LIB.T6G(SCH_1):PAGE331_I44@PURE_QUANTA.Q_CAP(CHIPS)':
 'B': CDS_PINID='B';
NODE_NAME     Q148 4
 '@T6G_MB_LIB.T6G(SCH_1):PAGE331_I55@PURE_QUANTA.MOSFET_NCH_DUAL(CHIPS)':
 'S2': CDS_PINID='S2';
NODE_NAME     Q148 1
 '@T6G_MB_LIB.T6G(SCH_1):PAGE331_I61@PURE_QUANTA.MOSFET_NCH_DUAL(CHIPS)':
 'S1': CDS_PINID='S1';
NODE_NAME     R4544 2
 '@T6G_MB_LIB.T6G(SCH_1):PAGE331_I62@PURE_QUANTA.Q_RES(CHIPS)':
 'B': CDS_PINID='B';
NODE_NAME     U316 3
 '@T6G_MB_LIB.T6G(SCH_1):PAGE331_I86@PURE_QUANTA.74LVC2G17GW(CHIPS)':
 'A1': CDS_PINID='A1';
NODE_NAME     U316 2
 '@T6G_MB_LIB.T6G(SCH_1):PAGE331_I86@PURE_QUANTA.74LVC2G17GW(CHIPS)':
 'GND': CDS_PINID='GND';
NODE_NAME     R4548 2
 '@T6G_MB_LIB.T6G(SCH_1):PAGE331_I87@PURE_QUANTA.Q_RES(CHIPS)':
 'B': CDS_PINID='B';
NODE_NAME     C8 2
 '@T6G_MB_LIB.T6G(SCH_1):PAGE331_I93@PURE_QUANTA.Q_CAP(CHIPS)':
 'B': CDS_PINID='B';
NODE_NAME     R4555 2
 '@T6G_MB_LIB.T6G(SCH_1):PAGE331_I99@PURE_QUANTA.Q_RES(CHIPS)':
 'B': CDS_PINID='B';
NODE_NAME     Q67 1
 '@T6G_MB_LIB.T6G(SCH_1):PAGE333_I33@PURE_QUANTA.MOSFET_NCH_DUAL(CHIPS)':
 'S1': CDS_PINID='S1';
NODE_NAME     Q70 1
 '@T6G_MB_LIB.T6G(SCH_1):PAGE333_I35@PURE_QUANTA.MOSFET_NCH_DUAL(CHIPS)':
 'S1': CDS_PINID='S1';
NODE_NAME     Q72 1
 '@T6G_MB_LIB.T6G(SCH_1):PAGE333_I37@PURE_QUANTA.MOSFET_NCH_DUAL(CHIPS)':
 'S1': CDS_PINID='S1';
NODE_NAME     R2831 2
 '@T6G_MB_LIB.T6G(SCH_1):PAGE333_I56@PURE_QUANTA.Q_RES(CHIPS)':
 'B': CDS_PINID='B';
NODE_NAME     R2829 2
 '@T6G_MB_LIB.T6G(SCH_1):PAGE333_I58@PURE_QUANTA.Q_RES(CHIPS)':
 'B': CDS_PINID='B';
NODE_NAME     R2833 2
 '@T6G_MB_LIB.T6G(SCH_1):PAGE333_I60@PURE_QUANTA.Q_RES(CHIPS)':
 'B': CDS_PINID='B';
NODE_NAME     R2838 2
 '@T6G_MB_LIB.T6G(SCH_1):PAGE333_I62@PURE_QUANTA.Q_RES(CHIPS)':
 'B': CDS_PINID='B';
NODE_NAME     Q67 4
 '@T6G_MB_LIB.T6G(SCH_1):PAGE333_I82@PURE_QUANTA.MOSFET_NCH_DUAL(CHIPS)':
 'S2': CDS_PINID='S2';
NODE_NAME     Q69 4
 '@T6G_MB_LIB.T6G(SCH_1):PAGE333_I88@PURE_QUANTA.MOSFET_NCH_DUAL(CHIPS)':
 'S2': CDS_PINID='S2';
NODE_NAME     C1754 2
 '@T6G_MB_LIB.T6G(SCH_1):PAGE333_I92@PURE_QUANTA.Q_CAP(CHIPS)':
 'B': CDS_PINID='B';
NODE_NAME     Q71 4
 '@T6G_MB_LIB.T6G(SCH_1):PAGE333_I100@PURE_QUANTA.MOSFET_NCH_DUAL(CHIPS)':
 'S2': CDS_PINID='S2';
NODE_NAME     C1756 2
 '@T6G_MB_LIB.T6G(SCH_1):PAGE333_I105@PURE_QUANTA.Q_CAP(CHIPS)':
 'B': CDS_PINID='B';
NODE_NAME     C1774 2
 '@T6G_MB_LIB.T6G(SCH_1):PAGE333_I111@PURE_QUANTA.Q_CAP(CHIPS)':
 'B': CDS_PINID='B';
NODE_NAME     C1773 2
 '@T6G_MB_LIB.T6G(SCH_1):PAGE333_I114@PURE_QUANTA.Q_CAP(CHIPS)':
 'B': CDS_PINID='B';
NODE_NAME     C1772 2
 '@T6G_MB_LIB.T6G(SCH_1):PAGE333_I116@PURE_QUANTA.Q_CAP(CHIPS)':
 'B': CDS_PINID='B';
NODE_NAME     Q69 1
 '@T6G_MB_LIB.T6G(SCH_1):PAGE333_I117@PURE_QUANTA.MOSFET_NCH_DUAL(CHIPS)':
 'S1': CDS_PINID='S1';
NODE_NAME     Q71 1
 '@T6G_MB_LIB.T6G(SCH_1):PAGE333_I118@PURE_QUANTA.MOSFET_NCH_DUAL(CHIPS)':
 'S1': CDS_PINID='S1';
NODE_NAME     Q72 4
 '@T6G_MB_LIB.T6G(SCH_1):PAGE333_I119@PURE_QUANTA.MOSFET_NCH_DUAL(CHIPS)':
 'S2': CDS_PINID='S2';
NODE_NAME     Q70 4
 '@T6G_MB_LIB.T6G(SCH_1):PAGE333_I120@PURE_QUANTA.MOSFET_NCH_DUAL(CHIPS)':
 'S2': CDS_PINID='S2';
NODE_NAME     Q74 1
 '@T6G_MB_LIB.T6G(SCH_1):PAGE333_I121@PURE_QUANTA.MOSFET_NCH_DUAL(CHIPS)':
 'S1': CDS_PINID='S1';
NODE_NAME     Q74 4
 '@T6G_MB_LIB.T6G(SCH_1):PAGE333_I122@PURE_QUANTA.MOSFET_NCH_DUAL(CHIPS)':
 'S2': CDS_PINID='S2';
NODE_NAME     C1804 2
 '@T6G_MB_LIB.T6G(SCH_1):PAGE333_I125@PURE_QUANTA.Q_CAP(CHIPS)':
 'B': CDS_PINID='B';
NODE_NAME     R3032 2
 '@T6G_MB_LIB.T6G(SCH_1):PAGE333_I134@PURE_QUANTA.Q_RES(CHIPS)':
 'B': CDS_PINID='B';
NODE_NAME     R3028 2
 '@T6G_MB_LIB.T6G(SCH_1):PAGE333_I139@PURE_QUANTA.Q_RES(CHIPS)':
 'B': CDS_PINID='B';
NODE_NAME     C1802 2
 '@T6G_MB_LIB.T6G(SCH_1):PAGE333_I148@PURE_QUANTA.Q_CAP(CHIPS)':
 'B': CDS_PINID='B';
NODE_NAME     Q75 4
 '@T6G_MB_LIB.T6G(SCH_1):PAGE333_I151@PURE_QUANTA.MOSFET_NCH_DUAL(CHIPS)':
 'S2': CDS_PINID='S2';
NODE_NAME     Q75 1
 '@T6G_MB_LIB.T6G(SCH_1):PAGE333_I152@PURE_QUANTA.MOSFET_NCH_DUAL(CHIPS)':
 'S1': CDS_PINID='S1';
NODE_NAME     Q96 1
 '@T6G_MB_LIB.T6G(SCH_1):PAGE333_I154@PURE_QUANTA.MOSFET_NCH_DUAL(CHIPS)':
 'S1': CDS_PINID='S1';
NODE_NAME     C1881 2
 '@T6G_MB_LIB.T6G(SCH_1):PAGE333_I156@PURE_QUANTA.Q_CAP(CHIPS)':
 'B': CDS_PINID='B';
NODE_NAME     Q96 4
 '@T6G_MB_LIB.T6G(SCH_1):PAGE333_I159@PURE_QUANTA.MOSFET_NCH_DUAL(CHIPS)':
 'S2': CDS_PINID='S2';
NODE_NAME     R3511 2
 '@T6G_MB_LIB.T6G(SCH_1):PAGE333_I172@PURE_QUANTA.Q_RES(CHIPS)':
 'B': CDS_PINID='B';
NODE_NAME     R3513 2
 '@T6G_MB_LIB.T6G(SCH_1):PAGE333_I173@PURE_QUANTA.Q_RES(CHIPS)':
 'B': CDS_PINID='B';
NODE_NAME     U253 2
 '@T6G_MB_LIB.T6G(SCH_1):PAGE334_I26@PURE_QUANTA.74LVC2G17GW(CHIPS)':
 'GND': CDS_PINID='GND';
NODE_NAME     C1958 2
 '@T6G_MB_LIB.T6G(SCH_1):PAGE334_I29@PURE_QUANTA.Q_CAP(CHIPS)':
 'B': CDS_PINID='B';
NODE_NAME     R3452 2
 '@T6G_MB_LIB.T6G(SCH_1):PAGE334_I95@PURE_QUANTA.Q_RES(CHIPS)':
 'B': CDS_PINID='B';
NODE_NAME     R3457 2
 '@T6G_MB_LIB.T6G(SCH_1):PAGE334_I123@PURE_QUANTA.Q_RES(CHIPS)':
 'B': CDS_PINID='B';
NODE_NAME     R3455 2
 '@T6G_MB_LIB.T6G(SCH_1):PAGE334_I139@PURE_QUANTA.Q_RES(CHIPS)':
 'B': CDS_PINID='B';
NODE_NAME     C1957 2
 '@T6G_MB_LIB.T6G(SCH_1):PAGE334_I148@PURE_QUANTA.Q_CAP(CHIPS)':
 'B': CDS_PINID='B';
NODE_NAME     U252 2
 '@T6G_MB_LIB.T6G(SCH_1):PAGE334_I153@PURE_QUANTA.74LVC2G17GW(CHIPS)':
 'GND': CDS_PINID='GND';
NODE_NAME     R3454 2
 '@T6G_MB_LIB.T6G(SCH_1):PAGE334_I165@PURE_QUANTA.Q_RES(CHIPS)':
 'B': CDS_PINID='B';
NODE_NAME     R3449 2
 '@T6G_MB_LIB.T6G(SCH_1):PAGE334_I170@PURE_QUANTA.Q_RES(CHIPS)':
 'B': CDS_PINID='B';
NODE_NAME     U256 2
 '@T6G_MB_LIB.T6G(SCH_1):PAGE334_I173@PURE_QUANTA.74LVC2G17GW(CHIPS)':
 'GND': CDS_PINID='GND';
NODE_NAME     C1977 2
 '@T6G_MB_LIB.T6G(SCH_1):PAGE334_I175@PURE_QUANTA.Q_CAP(CHIPS)':
 'B': CDS_PINID='B';
NODE_NAME     R3467 2
 '@T6G_MB_LIB.T6G(SCH_1):PAGE334_I181@PURE_QUANTA.Q_RES(CHIPS)':
 'B': CDS_PINID='B';
NODE_NAME     R3466 2
 '@T6G_MB_LIB.T6G(SCH_1):PAGE334_I184@PURE_QUANTA.Q_RES(CHIPS)':
 'B': CDS_PINID='B';
NODE_NAME     R2918 2
 '@T6G_MB_LIB.T6G(SCH_1):PAGE334_I188@PURE_QUANTA.Q_RES(CHIPS)':
 'B': CDS_PINID='B';
NODE_NAME     R2932 2
 '@T6G_MB_LIB.T6G(SCH_1):PAGE334_I195@PURE_QUANTA.Q_RES(CHIPS)':
 'B': CDS_PINID='B';
NODE_NAME     C1963 2
 '@T6G_MB_LIB.T6G(SCH_1):PAGE255_I13@PURE_QUANTA.Q_CAP(CHIPS)':
 'B': CDS_PINID='B';
NODE_NAME     U255 2
 '@T6G_MB_LIB.T6G(SCH_1):PAGE255_I16@PURE_QUANTA.74LVC2G07DW7(CHIPS)':
 'GND': CDS_PINID='GND';
NODE_NAME     R3460 2
 '@T6G_MB_LIB.T6G(SCH_1):PAGE255_I31@PURE_QUANTA.Q_RES(CHIPS)':
 'B': CDS_PINID='B';
NODE_NAME     R3462 2
 '@T6G_MB_LIB.T6G(SCH_1):PAGE255_I33@PURE_QUANTA.Q_RES(CHIPS)':
 'B': CDS_PINID='B';
NODE_NAME     R3489 2
 '@T6G_MB_LIB.T6G(SCH_1):PAGE255_I42@PURE_QUANTA.Q_RES(CHIPS)':
 'B': CDS_PINID='B';
NODE_NAME     R3493 2
 '@T6G_MB_LIB.T6G(SCH_1):PAGE255_I48@PURE_QUANTA.Q_RES(CHIPS)':
 'B': CDS_PINID='B';
NODE_NAME     U257 3
 '@T6G_MB_LIB.T6G(SCH_1):PAGE255_I50@PURE_QUANTA.74LVC2G07DW7(CHIPS)':
 '2A': CDS_PINID='\2a\';
NODE_NAME     U257 2
 '@T6G_MB_LIB.T6G(SCH_1):PAGE255_I50@PURE_QUANTA.74LVC2G07DW7(CHIPS)':
 'GND': CDS_PINID='GND';
NODE_NAME     R3495 2
 '@T6G_MB_LIB.T6G(SCH_1):PAGE255_I62@PURE_QUANTA.Q_RES(CHIPS)':
 'B': CDS_PINID='B';
NODE_NAME     C1979 2
 '@T6G_MB_LIB.T6G(SCH_1):PAGE255_I67@PURE_QUANTA.Q_CAP(CHIPS)':
 'B': CDS_PINID='B';
NODE_NAME     R3491 2
 '@T6G_MB_LIB.T6G(SCH_1):PAGE255_I70@PURE_QUANTA.Q_RES(CHIPS)':
 'B': CDS_PINID='B';
NODE_NAME     U195 2
 '@T6G_MB_LIB.T6G(SCH_1):PAGE256_I65@PURE_QUANTA.74LVC2G17GW(CHIPS)':
 'GND': CDS_PINID='GND';
NODE_NAME     C1769 2
 '@T6G_MB_LIB.T6G(SCH_1):PAGE256_I89@PURE_QUANTA.Q_CAP(CHIPS)':
 'B': CDS_PINID='B';
NODE_NAME     R2915 2
 '@T6G_MB_LIB.T6G(SCH_1):PAGE256_I92@PURE_QUANTA.Q_RES(CHIPS)':
 'B': CDS_PINID='B';
NODE_NAME     R2916 2
 '@T6G_MB_LIB.T6G(SCH_1):PAGE256_I93@PURE_QUANTA.Q_RES(CHIPS)':
 'B': CDS_PINID='B';
NODE_NAME     R2926 2
 '@T6G_MB_LIB.T6G(SCH_1):PAGE256_I121@PURE_QUANTA.Q_RES(CHIPS)':
 'B': CDS_PINID='B';
NODE_NAME     U196 2
 '@T6G_MB_LIB.T6G(SCH_1):PAGE256_I127@PURE_QUANTA.74LVC2G17GW(CHIPS)':
 'GND': CDS_PINID='GND';
NODE_NAME     C1770 2
 '@T6G_MB_LIB.T6G(SCH_1):PAGE256_I140@PURE_QUANTA.Q_CAP(CHIPS)':
 'B': CDS_PINID='B';
NODE_NAME     R2937 2
 '@T6G_MB_LIB.T6G(SCH_1):PAGE256_I160@PURE_QUANTA.Q_RES(CHIPS)':
 'B': CDS_PINID='B';
NODE_NAME     C1803 2
 '@T6G_MB_LIB.T6G(SCH_1):PAGE256_I166@PURE_QUANTA.Q_CAP(CHIPS)':
 'B': CDS_PINID='B';
NODE_NAME     R3509 2
 '@T6G_MB_LIB.T6G(SCH_1):PAGE256_I191@PURE_QUANTA.Q_RES(CHIPS)':
 'B': CDS_PINID='B';
NODE_NAME     R3507 2
 '@T6G_MB_LIB.T6G(SCH_1):PAGE256_I192@PURE_QUANTA.Q_RES(CHIPS)':
 'B': CDS_PINID='B';
NODE_NAME     R3508 2
 '@T6G_MB_LIB.T6G(SCH_1):PAGE256_I194@PURE_QUANTA.Q_RES(CHIPS)':
 'B': CDS_PINID='B';
NODE_NAME     U204 3
 '@T6G_MB_LIB.T6G(SCH_1):PAGE256_I195@PURE_QUANTA.74LVC1G126SE7(CHIPS)':
 'GND': CDS_PINID='GND';
NODE_NAME     R2927 2
 '@T6G_MB_LIB.T6G(SCH_1):PAGE256_I203@PURE_QUANTA.Q_RES(CHIPS)':
 'B': CDS_PINID='B';
NODE_NAME     R3207 2
 '@T6G_MB_LIB.T6G(SCH_1):PAGE307_I15@PURE_QUANTA.Q_RES(CHIPS)':
 'B': CDS_PINID='B';
NODE_NAME     C1825 2
 '@T6G_MB_LIB.T6G(SCH_1):PAGE307_I17@PURE_QUANTA.Q_CAP(CHIPS)':
 'B': CDS_PINID='B';
NODE_NAME     U222 7
 '@T6G_MB_LIB.T6G(SCH_1):PAGE307_I32@PURE_QUANTA.74CBTLV3126PW(CHIPS)':
 'GND': CDS_PINID='GND';
NODE_NAME     C1826 2
 '@T6G_MB_LIB.T6G(SCH_1):PAGE307_I33@PURE_QUANTA.Q_CAP(CHIPS)':
 'B': CDS_PINID='B';
NODE_NAME     R3208 2
 '@T6G_MB_LIB.T6G(SCH_1):PAGE307_I37@PURE_QUANTA.Q_RES(CHIPS)':
 'B': CDS_PINID='B';
NODE_NAME     R3216 2
 '@T6G_MB_LIB.T6G(SCH_1):PAGE307_I38@PURE_QUANTA.Q_RES(CHIPS)':
 'B': CDS_PINID='B';
NODE_NAME     R3217 2
 '@T6G_MB_LIB.T6G(SCH_1):PAGE307_I40@PURE_QUANTA.Q_RES(CHIPS)':
 'B': CDS_PINID='B';
NODE_NAME     C1827 2
 '@T6G_MB_LIB.T6G(SCH_1):PAGE307_I77@PURE_QUANTA.Q_CAP(CHIPS)':
 'B': CDS_PINID='B';
NODE_NAME     U223 7
 '@T6G_MB_LIB.T6G(SCH_1):PAGE307_I78@PURE_QUANTA.74CBTLV3126PW(CHIPS)':
 'GND': CDS_PINID='GND';
NODE_NAME     U286 3
 '@T6G_MB_LIB.T6G(SCH_1):PAGE307_I80@PURE_QUANTA.74LVC1G126SE7(CHIPS)':
 'GND': CDS_PINID='GND';
NODE_NAME     R32 2
 '@T6G_MB_LIB.T6G(SCH_1):PAGE335_I2@PURE_QUANTA.Q_RES(CHIPS)':
 'B': CDS_PINID='B';
NODE_NAME     R3132 1
 '@T6G_MB_LIB.T6G(SCH_1):PAGE335_I6@PURE_QUANTA.Q_RES(CHIPS)':
 'A': CDS_PINID='A';
NODE_NAME     C21 2
 '@T6G_MB_LIB.T6G(SCH_1):PAGE335_I89@PURE_QUANTA.Q_CAP(CHIPS)':
 'B': CDS_PINID='B';
NODE_NAME     C1235 2
 '@T6G_MB_LIB.T6G(SCH_1):PAGE335_I90@PURE_QUANTA.Q_CAP(CHIPS)':
 'B': CDS_PINID='B';
NODE_NAME     C1237 2
 '@T6G_MB_LIB.T6G(SCH_1):PAGE335_I110@PURE_QUANTA.Q_CAP(CHIPS)':
 'B': CDS_PINID='B';
NODE_NAME     C1238 2
 '@T6G_MB_LIB.T6G(SCH_1):PAGE335_I111@PURE_QUANTA.Q_CAP(CHIPS)':
 'B': CDS_PINID='B';
NODE_NAME     C1240 2
 '@T6G_MB_LIB.T6G(SCH_1):PAGE335_I114@PURE_QUANTA.Q_CAP(CHIPS)':
 'B': CDS_PINID='B';
NODE_NAME     J38 G1
 '@T6G_MB_LIB.T6G(SCH_1):PAGE335_I168@PURE_QUANTA.SCONN168_ME1016810202011(CHIPS)':
 'G1': CDS_PINID='G1';
NODE_NAME     J38 G2
 '@T6G_MB_LIB.T6G(SCH_1):PAGE335_I168@PURE_QUANTA.SCONN168_ME1016810202011(CHIPS)':
 'G2': CDS_PINID='G2';
NODE_NAME     J38 G3
 '@T6G_MB_LIB.T6G(SCH_1):PAGE335_I168@PURE_QUANTA.SCONN168_ME1016810202011(CHIPS)':
 'G3': CDS_PINID='G3';
NODE_NAME     J38 G4
 '@T6G_MB_LIB.T6G(SCH_1):PAGE335_I168@PURE_QUANTA.SCONN168_ME1016810202011(CHIPS)':
 'G4': CDS_PINID='G4';
NODE_NAME     J38 G5
 '@T6G_MB_LIB.T6G(SCH_1):PAGE335_I168@PURE_QUANTA.SCONN168_ME1016810202011(CHIPS)':
 'G5': CDS_PINID='G5';
NODE_NAME     J38 A1
 '@T6G_MB_LIB.T6G(SCH_1):PAGE335_I168@PURE_QUANTA.SCONN168_ME1016810202011(CHIPS)':
 'GND_A1': CDS_PINID='GND_A1';
NODE_NAME     J38 A2
 '@T6G_MB_LIB.T6G(SCH_1):PAGE335_I168@PURE_QUANTA.SCONN168_ME1016810202011(CHIPS)':
 'GND_A2': CDS_PINID='GND_A2';
NODE_NAME     J38 A3
 '@T6G_MB_LIB.T6G(SCH_1):PAGE335_I168@PURE_QUANTA.SCONN168_ME1016810202011(CHIPS)':
 'GND_A3': CDS_PINID='GND_A3';
NODE_NAME     J38 A4
 '@T6G_MB_LIB.T6G(SCH_1):PAGE335_I168@PURE_QUANTA.SCONN168_ME1016810202011(CHIPS)':
 'GND_A4': CDS_PINID='GND_A4';
NODE_NAME     J38 A5
 '@T6G_MB_LIB.T6G(SCH_1):PAGE335_I168@PURE_QUANTA.SCONN168_ME1016810202011(CHIPS)':
 'GND_A5': CDS_PINID='GND_A5';
NODE_NAME     J38 A6
 '@T6G_MB_LIB.T6G(SCH_1):PAGE335_I168@PURE_QUANTA.SCONN168_ME1016810202011(CHIPS)':
 'GND_A6': CDS_PINID='GND_A6';
NODE_NAME     J38 A13
 '@T6G_MB_LIB.T6G(SCH_1):PAGE335_I168@PURE_QUANTA.SCONN168_ME1016810202011(CHIPS)':
 'GND_A13': CDS_PINID='GND_A13';
NODE_NAME     J38 A16
 '@T6G_MB_LIB.T6G(SCH_1):PAGE335_I168@PURE_QUANTA.SCONN168_ME1016810202011(CHIPS)':
 'GND_A16': CDS_PINID='GND_A16';
NODE_NAME     J38 A19
 '@T6G_MB_LIB.T6G(SCH_1):PAGE335_I168@PURE_QUANTA.SCONN168_ME1016810202011(CHIPS)':
 'GND_A19': CDS_PINID='GND_A19';
NODE_NAME     J38 A22
 '@T6G_MB_LIB.T6G(SCH_1):PAGE335_I168@PURE_QUANTA.SCONN168_ME1016810202011(CHIPS)':
 'GND_A22': CDS_PINID='GND_A22';
NODE_NAME     J38 A25
 '@T6G_MB_LIB.T6G(SCH_1):PAGE335_I168@PURE_QUANTA.SCONN168_ME1016810202011(CHIPS)':
 'GND_A25': CDS_PINID='GND_A25';
NODE_NAME     J38 A28
 '@T6G_MB_LIB.T6G(SCH_1):PAGE335_I168@PURE_QUANTA.SCONN168_ME1016810202011(CHIPS)':
 'GND_A28': CDS_PINID='GND_A28';
NODE_NAME     J38 A29
 '@T6G_MB_LIB.T6G(SCH_1):PAGE335_I168@PURE_QUANTA.SCONN168_ME1016810202011(CHIPS)':
 'GND_A29': CDS_PINID='GND_A29';
NODE_NAME     J38 A32
 '@T6G_MB_LIB.T6G(SCH_1):PAGE335_I168@PURE_QUANTA.SCONN168_ME1016810202011(CHIPS)':
 'GND_A32': CDS_PINID='GND_A32';
NODE_NAME     J38 A35
 '@T6G_MB_LIB.T6G(SCH_1):PAGE335_I168@PURE_QUANTA.SCONN168_ME1016810202011(CHIPS)':
 'GND_A35': CDS_PINID='GND_A35';
NODE_NAME     J38 A38
 '@T6G_MB_LIB.T6G(SCH_1):PAGE335_I168@PURE_QUANTA.SCONN168_ME1016810202011(CHIPS)':
 'GND_A38': CDS_PINID='GND_A38';
NODE_NAME     J38 A41
 '@T6G_MB_LIB.T6G(SCH_1):PAGE335_I168@PURE_QUANTA.SCONN168_ME1016810202011(CHIPS)':
 'GND_A41': CDS_PINID='GND_A41';
NODE_NAME     J38 A43
 '@T6G_MB_LIB.T6G(SCH_1):PAGE335_I168@PURE_QUANTA.SCONN168_ME1016810202011(CHIPS)':
 'GND_A43': CDS_PINID='GND_A43';
NODE_NAME     J38 A46
 '@T6G_MB_LIB.T6G(SCH_1):PAGE335_I168@PURE_QUANTA.SCONN168_ME1016810202011(CHIPS)':
 'GND_A46': CDS_PINID='GND_A46';
NODE_NAME     J38 A49
 '@T6G_MB_LIB.T6G(SCH_1):PAGE335_I168@PURE_QUANTA.SCONN168_ME1016810202011(CHIPS)':
 'GND_A49': CDS_PINID='GND_A49';
NODE_NAME     J38 A52
 '@T6G_MB_LIB.T6G(SCH_1):PAGE335_I168@PURE_QUANTA.SCONN168_ME1016810202011(CHIPS)':
 'GND_A52': CDS_PINID='GND_A52';
NODE_NAME     J38 A55
 '@T6G_MB_LIB.T6G(SCH_1):PAGE335_I168@PURE_QUANTA.SCONN168_ME1016810202011(CHIPS)':
 'GND_A55': CDS_PINID='GND_A55';
NODE_NAME     J38 A58
 '@T6G_MB_LIB.T6G(SCH_1):PAGE335_I168@PURE_QUANTA.SCONN168_ME1016810202011(CHIPS)':
 'GND_A58': CDS_PINID='GND_A58';
NODE_NAME     J38 A61
 '@T6G_MB_LIB.T6G(SCH_1):PAGE335_I168@PURE_QUANTA.SCONN168_ME1016810202011(CHIPS)':
 'GND_A61': CDS_PINID='GND_A61';
NODE_NAME     J38 A64
 '@T6G_MB_LIB.T6G(SCH_1):PAGE335_I168@PURE_QUANTA.SCONN168_ME1016810202011(CHIPS)':
 'GND_A64': CDS_PINID='GND_A64';
NODE_NAME     J38 A67
 '@T6G_MB_LIB.T6G(SCH_1):PAGE335_I168@PURE_QUANTA.SCONN168_ME1016810202011(CHIPS)':
 'GND_A67': CDS_PINID='GND_A67';
NODE_NAME     J38 B13
 '@T6G_MB_LIB.T6G(SCH_1):PAGE335_I168@PURE_QUANTA.SCONN168_ME1016810202011(CHIPS)':
 'GND_B13': CDS_PINID='GND_B13';
NODE_NAME     J38 B16
 '@T6G_MB_LIB.T6G(SCH_1):PAGE335_I168@PURE_QUANTA.SCONN168_ME1016810202011(CHIPS)':
 'GND_B16': CDS_PINID='GND_B16';
NODE_NAME     J38 B19
 '@T6G_MB_LIB.T6G(SCH_1):PAGE335_I168@PURE_QUANTA.SCONN168_ME1016810202011(CHIPS)':
 'GND_B19': CDS_PINID='GND_B19';
NODE_NAME     J38 B22
 '@T6G_MB_LIB.T6G(SCH_1):PAGE335_I168@PURE_QUANTA.SCONN168_ME1016810202011(CHIPS)':
 'GND_B22': CDS_PINID='GND_B22';
NODE_NAME     J38 B25
 '@T6G_MB_LIB.T6G(SCH_1):PAGE335_I168@PURE_QUANTA.SCONN168_ME1016810202011(CHIPS)':
 'GND_B25': CDS_PINID='GND_B25';
NODE_NAME     J38 B28
 '@T6G_MB_LIB.T6G(SCH_1):PAGE335_I168@PURE_QUANTA.SCONN168_ME1016810202011(CHIPS)':
 'GND_B28': CDS_PINID='GND_B28';
NODE_NAME     J38 B29
 '@T6G_MB_LIB.T6G(SCH_1):PAGE335_I168@PURE_QUANTA.SCONN168_ME1016810202011(CHIPS)':
 'GND_B29': CDS_PINID='GND_B29';
NODE_NAME     J38 B32
 '@T6G_MB_LIB.T6G(SCH_1):PAGE335_I168@PURE_QUANTA.SCONN168_ME1016810202011(CHIPS)':
 'GND_B32': CDS_PINID='GND_B32';
NODE_NAME     J38 B35
 '@T6G_MB_LIB.T6G(SCH_1):PAGE335_I168@PURE_QUANTA.SCONN168_ME1016810202011(CHIPS)':
 'GND_B35': CDS_PINID='GND_B35';
NODE_NAME     J38 B38
 '@T6G_MB_LIB.T6G(SCH_1):PAGE335_I168@PURE_QUANTA.SCONN168_ME1016810202011(CHIPS)':
 'GND_B38': CDS_PINID='GND_B38';
NODE_NAME     J38 B41
 '@T6G_MB_LIB.T6G(SCH_1):PAGE335_I168@PURE_QUANTA.SCONN168_ME1016810202011(CHIPS)':
 'GND_B41': CDS_PINID='GND_B41';
NODE_NAME     J38 B43
 '@T6G_MB_LIB.T6G(SCH_1):PAGE335_I168@PURE_QUANTA.SCONN168_ME1016810202011(CHIPS)':
 'GND_B43': CDS_PINID='GND_B43';
NODE_NAME     J38 B46
 '@T6G_MB_LIB.T6G(SCH_1):PAGE335_I168@PURE_QUANTA.SCONN168_ME1016810202011(CHIPS)':
 'GND_B46': CDS_PINID='GND_B46';
NODE_NAME     J38 B49
 '@T6G_MB_LIB.T6G(SCH_1):PAGE335_I168@PURE_QUANTA.SCONN168_ME1016810202011(CHIPS)':
 'GND_B49': CDS_PINID='GND_B49';
NODE_NAME     J38 B52
 '@T6G_MB_LIB.T6G(SCH_1):PAGE335_I168@PURE_QUANTA.SCONN168_ME1016810202011(CHIPS)':
 'GND_B52': CDS_PINID='GND_B52';
NODE_NAME     J38 B55
 '@T6G_MB_LIB.T6G(SCH_1):PAGE335_I168@PURE_QUANTA.SCONN168_ME1016810202011(CHIPS)':
 'GND_B55': CDS_PINID='GND_B55';
NODE_NAME     J38 B58
 '@T6G_MB_LIB.T6G(SCH_1):PAGE335_I168@PURE_QUANTA.SCONN168_ME1016810202011(CHIPS)':
 'GND_B58': CDS_PINID='GND_B58';
NODE_NAME     J38 B61
 '@T6G_MB_LIB.T6G(SCH_1):PAGE335_I168@PURE_QUANTA.SCONN168_ME1016810202011(CHIPS)':
 'GND_B61': CDS_PINID='GND_B61';
NODE_NAME     J38 B64
 '@T6G_MB_LIB.T6G(SCH_1):PAGE335_I168@PURE_QUANTA.SCONN168_ME1016810202011(CHIPS)':
 'GND_B64': CDS_PINID='GND_B64';
NODE_NAME     J38 B67
 '@T6G_MB_LIB.T6G(SCH_1):PAGE335_I168@PURE_QUANTA.SCONN168_ME1016810202011(CHIPS)':
 'GND_B67': CDS_PINID='GND_B67';
NODE_NAME     J38 OA10
 '@T6G_MB_LIB.T6G(SCH_1):PAGE335_I168@PURE_QUANTA.SCONN168_ME1016810202011(CHIPS)':
 'GND_OA10': CDS_PINID='GND_OA10';
NODE_NAME     J38 OA13
 '@T6G_MB_LIB.T6G(SCH_1):PAGE335_I168@PURE_QUANTA.SCONN168_ME1016810202011(CHIPS)':
 'GND_OA13': CDS_PINID='GND_OA13';
NODE_NAME     J38 OB10
 '@T6G_MB_LIB.T6G(SCH_1):PAGE335_I168@PURE_QUANTA.SCONN168_ME1016810202011(CHIPS)':
 'GND_OB10': CDS_PINID='GND_OB10';
NODE_NAME     J38 OB13
 '@T6G_MB_LIB.T6G(SCH_1):PAGE335_I168@PURE_QUANTA.SCONN168_ME1016810202011(CHIPS)':
 'GND_OB13': CDS_PINID='GND_OB13';
NODE_NAME     U67 7
 '@T6G_MB_LIB.T6G(SCH_1):PAGE336_I1@PURE_QUANTA.74CBTLV3126PW(CHIPS)':
 'GND': CDS_PINID='GND';
NODE_NAME     U7 7
 '@T6G_MB_LIB.T6G(SCH_1):PAGE336_I2@PURE_QUANTA.74CBTLV3126PW(CHIPS)':
 'GND': CDS_PINID='GND';
NODE_NAME     C641 2
 '@T6G_MB_LIB.T6G(SCH_1):PAGE336_I16@PURE_QUANTA.Q_CAP(CHIPS)':
 'B': CDS_PINID='B';
NODE_NAME     C640 2
 '@T6G_MB_LIB.T6G(SCH_1):PAGE336_I47@PURE_QUANTA.Q_CAP(CHIPS)':
 'B': CDS_PINID='B';
NODE_NAME     R1289 2
 '@T6G_MB_LIB.T6G(SCH_1):PAGE336_I56@PURE_QUANTA.Q_RES(CHIPS)':
 'B': CDS_PINID='B';
NODE_NAME     C639 2
 '@T6G_MB_LIB.T6G(SCH_1):PAGE336_I59@PURE_QUANTA.Q_CAP(CHIPS)':
 'B': CDS_PINID='B';
NODE_NAME     R1898 2
 '@T6G_MB_LIB.T6G(SCH_1):PAGE336_I122@PURE_QUANTA.Q_RES(CHIPS)':
 'B': CDS_PINID='B';
NODE_NAME     R1896 2
 '@T6G_MB_LIB.T6G(SCH_1):PAGE336_I123@PURE_QUANTA.Q_RES(CHIPS)':
 'B': CDS_PINID='B';
NODE_NAME     R1897 2
 '@T6G_MB_LIB.T6G(SCH_1):PAGE336_I124@PURE_QUANTA.Q_RES(CHIPS)':
 'B': CDS_PINID='B';
NODE_NAME     R84 2
 '@T6G_MB_LIB.T6G(SCH_1):PAGE336_I129@PURE_QUANTA.Q_RES(CHIPS)':
 'B': CDS_PINID='B';
NODE_NAME     R77 2
 '@T6G_MB_LIB.T6G(SCH_1):PAGE336_I131@PURE_QUANTA.Q_RES(CHIPS)':
 'B': CDS_PINID='B';
NODE_NAME     R79 2
 '@T6G_MB_LIB.T6G(SCH_1):PAGE336_I132@PURE_QUANTA.Q_RES(CHIPS)':
 'B': CDS_PINID='B';
NODE_NAME     R80 2
 '@T6G_MB_LIB.T6G(SCH_1):PAGE336_I133@PURE_QUANTA.Q_RES(CHIPS)':
 'B': CDS_PINID='B';
NODE_NAME     R82 2
 '@T6G_MB_LIB.T6G(SCH_1):PAGE336_I134@PURE_QUANTA.Q_RES(CHIPS)':
 'B': CDS_PINID='B';
NODE_NAME     R83 2
 '@T6G_MB_LIB.T6G(SCH_1):PAGE336_I135@PURE_QUANTA.Q_RES(CHIPS)':
 'B': CDS_PINID='B';
NODE_NAME     R87 2
 '@T6G_MB_LIB.T6G(SCH_1):PAGE336_I136@PURE_QUANTA.Q_RES(CHIPS)':
 'B': CDS_PINID='B';
NODE_NAME     C1840 2
 '@T6G_MB_LIB.T6G(SCH_1):PAGE336_I147@PURE_QUANTA.Q_CAP(CHIPS)':
 'B': CDS_PINID='B';
NODE_NAME     R3232 2
 '@T6G_MB_LIB.T6G(SCH_1):PAGE336_I152@PURE_QUANTA.Q_RES(CHIPS)':
 'B': CDS_PINID='B';
NODE_NAME     U66 3
 '@T6G_MB_LIB.T6G(SCH_1):PAGE336_I157@PURE_QUANTA.74LVC1G126SE7(CHIPS)':
 'GND': CDS_PINID='GND';
NODE_NAME     U224 3
 '@T6G_MB_LIB.T6G(SCH_1):PAGE336_I159@PURE_QUANTA.74LVC1G126SE7(CHIPS)':
 'GND': CDS_PINID='GND';
NODE_NAME     C72 2
 '@T6G_MB_LIB.T6G(SCH_1):PAGE337_I40@PURE_QUANTA.Q_CAP(CHIPS)':
 'B': CDS_PINID='B';
NODE_NAME     C2344 2
 '@T6G_MB_LIB.T6G(SCH_1):PAGE337_I53@PURE_QUANTA.Q_CAP(CHIPS)':
 'B': CDS_PINID='B';
NODE_NAME     C1834 2
 '@T6G_MB_LIB.T6G(SCH_1):PAGE341_I20@PURE_QUANTA.Q_CAP(CHIPS)':
 'B': CDS_PINID='B';
NODE_NAME     C1837 2
 '@T6G_MB_LIB.T6G(SCH_1):PAGE341_I23@PURE_QUANTA.Q_CAP(CHIPS)':
 'B': CDS_PINID='B';
NODE_NAME     R3165 1
 '@T6G_MB_LIB.T6G(SCH_1):PAGE341_I32@PURE_QUANTA.Q_RES(CHIPS)':
 'A': CDS_PINID='A';
NODE_NAME     R8413 1
 '@T6G_MB_LIB.T6G(SCH_1):PAGE341_I33@PURE_QUANTA.Q_RES(CHIPS)':
 'A': CDS_PINID='A';
NODE_NAME     J35 G1
 '@T6G_MB_LIB.T6G(SCH_1):PAGE341_I168@PURE_QUANTA.SCONN168_ME1016810202011(CHIPS)':
 'G1': CDS_PINID='G1';
NODE_NAME     J35 G2
 '@T6G_MB_LIB.T6G(SCH_1):PAGE341_I168@PURE_QUANTA.SCONN168_ME1016810202011(CHIPS)':
 'G2': CDS_PINID='G2';
NODE_NAME     J35 G3
 '@T6G_MB_LIB.T6G(SCH_1):PAGE341_I168@PURE_QUANTA.SCONN168_ME1016810202011(CHIPS)':
 'G3': CDS_PINID='G3';
NODE_NAME     J35 G4
 '@T6G_MB_LIB.T6G(SCH_1):PAGE341_I168@PURE_QUANTA.SCONN168_ME1016810202011(CHIPS)':
 'G4': CDS_PINID='G4';
NODE_NAME     J35 G5
 '@T6G_MB_LIB.T6G(SCH_1):PAGE341_I168@PURE_QUANTA.SCONN168_ME1016810202011(CHIPS)':
 'G5': CDS_PINID='G5';
NODE_NAME     J35 A1
 '@T6G_MB_LIB.T6G(SCH_1):PAGE341_I168@PURE_QUANTA.SCONN168_ME1016810202011(CHIPS)':
 'GND_A1': CDS_PINID='GND_A1';
NODE_NAME     J35 A2
 '@T6G_MB_LIB.T6G(SCH_1):PAGE341_I168@PURE_QUANTA.SCONN168_ME1016810202011(CHIPS)':
 'GND_A2': CDS_PINID='GND_A2';
NODE_NAME     J35 A3
 '@T6G_MB_LIB.T6G(SCH_1):PAGE341_I168@PURE_QUANTA.SCONN168_ME1016810202011(CHIPS)':
 'GND_A3': CDS_PINID='GND_A3';
NODE_NAME     J35 A4
 '@T6G_MB_LIB.T6G(SCH_1):PAGE341_I168@PURE_QUANTA.SCONN168_ME1016810202011(CHIPS)':
 'GND_A4': CDS_PINID='GND_A4';
NODE_NAME     J35 A5
 '@T6G_MB_LIB.T6G(SCH_1):PAGE341_I168@PURE_QUANTA.SCONN168_ME1016810202011(CHIPS)':
 'GND_A5': CDS_PINID='GND_A5';
NODE_NAME     J35 A6
 '@T6G_MB_LIB.T6G(SCH_1):PAGE341_I168@PURE_QUANTA.SCONN168_ME1016810202011(CHIPS)':
 'GND_A6': CDS_PINID='GND_A6';
NODE_NAME     J35 A13
 '@T6G_MB_LIB.T6G(SCH_1):PAGE341_I168@PURE_QUANTA.SCONN168_ME1016810202011(CHIPS)':
 'GND_A13': CDS_PINID='GND_A13';
NODE_NAME     J35 A16
 '@T6G_MB_LIB.T6G(SCH_1):PAGE341_I168@PURE_QUANTA.SCONN168_ME1016810202011(CHIPS)':
 'GND_A16': CDS_PINID='GND_A16';
NODE_NAME     J35 A19
 '@T6G_MB_LIB.T6G(SCH_1):PAGE341_I168@PURE_QUANTA.SCONN168_ME1016810202011(CHIPS)':
 'GND_A19': CDS_PINID='GND_A19';
NODE_NAME     J35 A22
 '@T6G_MB_LIB.T6G(SCH_1):PAGE341_I168@PURE_QUANTA.SCONN168_ME1016810202011(CHIPS)':
 'GND_A22': CDS_PINID='GND_A22';
NODE_NAME     J35 A25
 '@T6G_MB_LIB.T6G(SCH_1):PAGE341_I168@PURE_QUANTA.SCONN168_ME1016810202011(CHIPS)':
 'GND_A25': CDS_PINID='GND_A25';
NODE_NAME     J35 A28
 '@T6G_MB_LIB.T6G(SCH_1):PAGE341_I168@PURE_QUANTA.SCONN168_ME1016810202011(CHIPS)':
 'GND_A28': CDS_PINID='GND_A28';
NODE_NAME     J35 A29
 '@T6G_MB_LIB.T6G(SCH_1):PAGE341_I168@PURE_QUANTA.SCONN168_ME1016810202011(CHIPS)':
 'GND_A29': CDS_PINID='GND_A29';
NODE_NAME     J35 A32
 '@T6G_MB_LIB.T6G(SCH_1):PAGE341_I168@PURE_QUANTA.SCONN168_ME1016810202011(CHIPS)':
 'GND_A32': CDS_PINID='GND_A32';
NODE_NAME     J35 A35
 '@T6G_MB_LIB.T6G(SCH_1):PAGE341_I168@PURE_QUANTA.SCONN168_ME1016810202011(CHIPS)':
 'GND_A35': CDS_PINID='GND_A35';
NODE_NAME     J35 A38
 '@T6G_MB_LIB.T6G(SCH_1):PAGE341_I168@PURE_QUANTA.SCONN168_ME1016810202011(CHIPS)':
 'GND_A38': CDS_PINID='GND_A38';
NODE_NAME     J35 A41
 '@T6G_MB_LIB.T6G(SCH_1):PAGE341_I168@PURE_QUANTA.SCONN168_ME1016810202011(CHIPS)':
 'GND_A41': CDS_PINID='GND_A41';
NODE_NAME     J35 A43
 '@T6G_MB_LIB.T6G(SCH_1):PAGE341_I168@PURE_QUANTA.SCONN168_ME1016810202011(CHIPS)':
 'GND_A43': CDS_PINID='GND_A43';
NODE_NAME     J35 A46
 '@T6G_MB_LIB.T6G(SCH_1):PAGE341_I168@PURE_QUANTA.SCONN168_ME1016810202011(CHIPS)':
 'GND_A46': CDS_PINID='GND_A46';
NODE_NAME     J35 A49
 '@T6G_MB_LIB.T6G(SCH_1):PAGE341_I168@PURE_QUANTA.SCONN168_ME1016810202011(CHIPS)':
 'GND_A49': CDS_PINID='GND_A49';
NODE_NAME     J35 A52
 '@T6G_MB_LIB.T6G(SCH_1):PAGE341_I168@PURE_QUANTA.SCONN168_ME1016810202011(CHIPS)':
 'GND_A52': CDS_PINID='GND_A52';
NODE_NAME     J35 A55
 '@T6G_MB_LIB.T6G(SCH_1):PAGE341_I168@PURE_QUANTA.SCONN168_ME1016810202011(CHIPS)':
 'GND_A55': CDS_PINID='GND_A55';
NODE_NAME     J35 A58
 '@T6G_MB_LIB.T6G(SCH_1):PAGE341_I168@PURE_QUANTA.SCONN168_ME1016810202011(CHIPS)':
 'GND_A58': CDS_PINID='GND_A58';
NODE_NAME     J35 A61
 '@T6G_MB_LIB.T6G(SCH_1):PAGE341_I168@PURE_QUANTA.SCONN168_ME1016810202011(CHIPS)':
 'GND_A61': CDS_PINID='GND_A61';
NODE_NAME     J35 A64
 '@T6G_MB_LIB.T6G(SCH_1):PAGE341_I168@PURE_QUANTA.SCONN168_ME1016810202011(CHIPS)':
 'GND_A64': CDS_PINID='GND_A64';
NODE_NAME     J35 A67
 '@T6G_MB_LIB.T6G(SCH_1):PAGE341_I168@PURE_QUANTA.SCONN168_ME1016810202011(CHIPS)':
 'GND_A67': CDS_PINID='GND_A67';
NODE_NAME     J35 B13
 '@T6G_MB_LIB.T6G(SCH_1):PAGE341_I168@PURE_QUANTA.SCONN168_ME1016810202011(CHIPS)':
 'GND_B13': CDS_PINID='GND_B13';
NODE_NAME     J35 B16
 '@T6G_MB_LIB.T6G(SCH_1):PAGE341_I168@PURE_QUANTA.SCONN168_ME1016810202011(CHIPS)':
 'GND_B16': CDS_PINID='GND_B16';
NODE_NAME     J35 B19
 '@T6G_MB_LIB.T6G(SCH_1):PAGE341_I168@PURE_QUANTA.SCONN168_ME1016810202011(CHIPS)':
 'GND_B19': CDS_PINID='GND_B19';
NODE_NAME     J35 B22
 '@T6G_MB_LIB.T6G(SCH_1):PAGE341_I168@PURE_QUANTA.SCONN168_ME1016810202011(CHIPS)':
 'GND_B22': CDS_PINID='GND_B22';
NODE_NAME     J35 B25
 '@T6G_MB_LIB.T6G(SCH_1):PAGE341_I168@PURE_QUANTA.SCONN168_ME1016810202011(CHIPS)':
 'GND_B25': CDS_PINID='GND_B25';
NODE_NAME     J35 B28
 '@T6G_MB_LIB.T6G(SCH_1):PAGE341_I168@PURE_QUANTA.SCONN168_ME1016810202011(CHIPS)':
 'GND_B28': CDS_PINID='GND_B28';
NODE_NAME     J35 B29
 '@T6G_MB_LIB.T6G(SCH_1):PAGE341_I168@PURE_QUANTA.SCONN168_ME1016810202011(CHIPS)':
 'GND_B29': CDS_PINID='GND_B29';
NODE_NAME     J35 B32
 '@T6G_MB_LIB.T6G(SCH_1):PAGE341_I168@PURE_QUANTA.SCONN168_ME1016810202011(CHIPS)':
 'GND_B32': CDS_PINID='GND_B32';
NODE_NAME     J35 B35
 '@T6G_MB_LIB.T6G(SCH_1):PAGE341_I168@PURE_QUANTA.SCONN168_ME1016810202011(CHIPS)':
 'GND_B35': CDS_PINID='GND_B35';
NODE_NAME     J35 B38
 '@T6G_MB_LIB.T6G(SCH_1):PAGE341_I168@PURE_QUANTA.SCONN168_ME1016810202011(CHIPS)':
 'GND_B38': CDS_PINID='GND_B38';
NODE_NAME     J35 B41
 '@T6G_MB_LIB.T6G(SCH_1):PAGE341_I168@PURE_QUANTA.SCONN168_ME1016810202011(CHIPS)':
 'GND_B41': CDS_PINID='GND_B41';
NODE_NAME     J35 B43
 '@T6G_MB_LIB.T6G(SCH_1):PAGE341_I168@PURE_QUANTA.SCONN168_ME1016810202011(CHIPS)':
 'GND_B43': CDS_PINID='GND_B43';
NODE_NAME     J35 B46
 '@T6G_MB_LIB.T6G(SCH_1):PAGE341_I168@PURE_QUANTA.SCONN168_ME1016810202011(CHIPS)':
 'GND_B46': CDS_PINID='GND_B46';
NODE_NAME     J35 B49
 '@T6G_MB_LIB.T6G(SCH_1):PAGE341_I168@PURE_QUANTA.SCONN168_ME1016810202011(CHIPS)':
 'GND_B49': CDS_PINID='GND_B49';
NODE_NAME     J35 B52
 '@T6G_MB_LIB.T6G(SCH_1):PAGE341_I168@PURE_QUANTA.SCONN168_ME1016810202011(CHIPS)':
 'GND_B52': CDS_PINID='GND_B52';
NODE_NAME     J35 B55
 '@T6G_MB_LIB.T6G(SCH_1):PAGE341_I168@PURE_QUANTA.SCONN168_ME1016810202011(CHIPS)':
 'GND_B55': CDS_PINID='GND_B55';
NODE_NAME     J35 B58
 '@T6G_MB_LIB.T6G(SCH_1):PAGE341_I168@PURE_QUANTA.SCONN168_ME1016810202011(CHIPS)':
 'GND_B58': CDS_PINID='GND_B58';
NODE_NAME     J35 B61
 '@T6G_MB_LIB.T6G(SCH_1):PAGE341_I168@PURE_QUANTA.SCONN168_ME1016810202011(CHIPS)':
 'GND_B61': CDS_PINID='GND_B61';
NODE_NAME     J35 B64
 '@T6G_MB_LIB.T6G(SCH_1):PAGE341_I168@PURE_QUANTA.SCONN168_ME1016810202011(CHIPS)':
 'GND_B64': CDS_PINID='GND_B64';
NODE_NAME     J35 B67
 '@T6G_MB_LIB.T6G(SCH_1):PAGE341_I168@PURE_QUANTA.SCONN168_ME1016810202011(CHIPS)':
 'GND_B67': CDS_PINID='GND_B67';
NODE_NAME     J35 OA10
 '@T6G_MB_LIB.T6G(SCH_1):PAGE341_I168@PURE_QUANTA.SCONN168_ME1016810202011(CHIPS)':
 'GND_OA10': CDS_PINID='GND_OA10';
NODE_NAME     J35 OA13
 '@T6G_MB_LIB.T6G(SCH_1):PAGE341_I168@PURE_QUANTA.SCONN168_ME1016810202011(CHIPS)':
 'GND_OA13': CDS_PINID='GND_OA13';
NODE_NAME     J35 OB10
 '@T6G_MB_LIB.T6G(SCH_1):PAGE341_I168@PURE_QUANTA.SCONN168_ME1016810202011(CHIPS)':
 'GND_OB10': CDS_PINID='GND_OB10';
NODE_NAME     J35 OB13
 '@T6G_MB_LIB.T6G(SCH_1):PAGE341_I168@PURE_QUANTA.SCONN168_ME1016810202011(CHIPS)':
 'GND_OB13': CDS_PINID='GND_OB13';
NODE_NAME     C1841 2
 '@T6G_MB_LIB.T6G(SCH_1):PAGE342_I12@PURE_QUANTA.Q_CAP(CHIPS)':
 'B': CDS_PINID='B';
NODE_NAME     R3235 2
 '@T6G_MB_LIB.T6G(SCH_1):PAGE342_I24@PURE_QUANTA.Q_RES(CHIPS)':
 'B': CDS_PINID='B';
NODE_NAME     C1823 2
 '@T6G_MB_LIB.T6G(SCH_1):PAGE342_I31@PURE_QUANTA.Q_CAP(CHIPS)':
 'B': CDS_PINID='B';
NODE_NAME     C1824 2
 '@T6G_MB_LIB.T6G(SCH_1):PAGE342_I41@PURE_QUANTA.Q_CAP(CHIPS)':
 'B': CDS_PINID='B';
NODE_NAME     C38 2
 '@T6G_MB_LIB.T6G(SCH_1):PAGE342_I47@PURE_QUANTA.Q_CAP(CHIPS)':
 'B': CDS_PINID='B';
NODE_NAME     Q118 1
 '@T6G_MB_LIB.T6G(SCH_1):PAGE343_I10@PURE_QUANTA.MOSFET_NCH_DUAL(CHIPS)':
 'S1': CDS_PINID='S1';
NODE_NAME     Q118 4
 '@T6G_MB_LIB.T6G(SCH_1):PAGE343_I19@PURE_QUANTA.MOSFET_NCH_DUAL(CHIPS)':
 'S2': CDS_PINID='S2';
NODE_NAME     U58 2
 '@T6G_MB_LIB.T6G(SCH_1):PAGE343_I28@PURE_QUANTA.74LVC2G07DW7(CHIPS)':
 'GND': CDS_PINID='GND';
NODE_NAME     Q119 1
 '@T6G_MB_LIB.T6G(SCH_1):PAGE343_I42@PURE_QUANTA.MOSFET_NCH_DUAL(CHIPS)':
 'S1': CDS_PINID='S1';
NODE_NAME     Q119 4
 '@T6G_MB_LIB.T6G(SCH_1):PAGE343_I45@PURE_QUANTA.MOSFET_NCH_DUAL(CHIPS)':
 'S2': CDS_PINID='S2';
NODE_NAME     PD107 A
 '@T6G_MB_LIB.T6G(SCH_1):PAGE343_I47@PURE_QUANTA.DIODE_TVS(CHIPS)':
 'A': CDS_PINID='A';
NODE_NAME     PC2139 2
 '@T6G_MB_LIB.T6G(SCH_1):PAGE343_I49@PURE_QUANTA.Q_CAP(CHIPS)':
 'B': CDS_PINID='B';
NODE_NAME     PR3812 2
 '@T6G_MB_LIB.T6G(SCH_1):PAGE343_I51@PURE_QUANTA.Q_RES(CHIPS)':
 'B': CDS_PINID='B';
NODE_NAME     PR3821 2
 '@T6G_MB_LIB.T6G(SCH_1):PAGE343_I63@PURE_QUANTA.Q_RES(CHIPS)':
 'B': CDS_PINID='B';
NODE_NAME     PC2098 2
 '@T6G_MB_LIB.T6G(SCH_1):PAGE343_I65@PURE_QUANTA.Q_CAP(CHIPS)':
 'B': CDS_PINID='B';
NODE_NAME     PC2146 1
 '@T6G_MB_LIB.T6G(SCH_1):PAGE343_I66@PURE_QUANTA.Q_CAP(CHIPS)':
 'A': CDS_PINID='A';
NODE_NAME     PU201 A7
 '@T6G_MB_LIB.T6G(SCH_1):PAGE343_I67@PURE_QUANTA.MAX15090BEWIT(CHIPS)':
 'CDLY': CDS_PINID='CDLY';
NODE_NAME     PU201 B7
 '@T6G_MB_LIB.T6G(SCH_1):PAGE343_I67@PURE_QUANTA.MAX15090BEWIT(CHIPS)':
 'EN#': CDS_PINID='\en#\';
NODE_NAME     PU201 B2
 '@T6G_MB_LIB.T6G(SCH_1):PAGE343_I67@PURE_QUANTA.MAX15090BEWIT(CHIPS)':
 'GND_B2': CDS_PINID='GND_B2';
NODE_NAME     PU201 C1
 '@T6G_MB_LIB.T6G(SCH_1):PAGE343_I67@PURE_QUANTA.MAX15090BEWIT(CHIPS)':
 'GND_C1': CDS_PINID='GND_C1';
NODE_NAME     PU201 C2
 '@T6G_MB_LIB.T6G(SCH_1):PAGE343_I67@PURE_QUANTA.MAX15090BEWIT(CHIPS)':
 'GND_C2': CDS_PINID='GND_C2';
NODE_NAME     PR3823 2
 '@T6G_MB_LIB.T6G(SCH_1):PAGE343_I71@PURE_QUANTA.Q_RES(CHIPS)':
 'B': CDS_PINID='B';
NODE_NAME     PC2147 1
 '@T6G_MB_LIB.T6G(SCH_1):PAGE343_I86@PURE_QUANTA.Q_CAP(CHIPS)':
 'A': CDS_PINID='A';
NODE_NAME     PR3822 2
 '@T6G_MB_LIB.T6G(SCH_1):PAGE343_I88@PURE_QUANTA.Q_RES(CHIPS)':
 'B': CDS_PINID='B';
NODE_NAME     PU200 A7
 '@T6G_MB_LIB.T6G(SCH_1):PAGE343_I89@PURE_QUANTA.MAX15090BEWIT(CHIPS)':
 'CDLY': CDS_PINID='CDLY';
NODE_NAME     PU200 B7
 '@T6G_MB_LIB.T6G(SCH_1):PAGE343_I89@PURE_QUANTA.MAX15090BEWIT(CHIPS)':
 'EN#': CDS_PINID='\en#\';
NODE_NAME     PU200 B2
 '@T6G_MB_LIB.T6G(SCH_1):PAGE343_I89@PURE_QUANTA.MAX15090BEWIT(CHIPS)':
 'GND_B2': CDS_PINID='GND_B2';
NODE_NAME     PU200 C1
 '@T6G_MB_LIB.T6G(SCH_1):PAGE343_I89@PURE_QUANTA.MAX15090BEWIT(CHIPS)':
 'GND_C1': CDS_PINID='GND_C1';
NODE_NAME     PU200 C2
 '@T6G_MB_LIB.T6G(SCH_1):PAGE343_I89@PURE_QUANTA.MAX15090BEWIT(CHIPS)':
 'GND_C2': CDS_PINID='GND_C2';
NODE_NAME     C39 2
 '@T6G_MB_LIB.T6G(SCH_1):PAGE343_I90@PURE_QUANTA.Q_CAP(CHIPS)':
 'B': CDS_PINID='B';
NODE_NAME     PD108 A
 '@T6G_MB_LIB.T6G(SCH_1):PAGE343_I92@PURE_QUANTA.SCHOTTKY_AC(CHIPS)':
 'A': CDS_PINID='A';
NODE_NAME     PR3824 2
 '@T6G_MB_LIB.T6G(SCH_1):PAGE343_I94@PURE_QUANTA.Q_RES(CHIPS)':
 'B': CDS_PINID='B';
NODE_NAME     PC2152 2
 '@T6G_MB_LIB.T6G(SCH_1):PAGE343_I97@PURE_QUANTA.Q_CAP(CHIPS)':
 'B': CDS_PINID='B';
NODE_NAME     PC2141 2
 '@T6G_MB_LIB.T6G(SCH_1):PAGE343_I99@PURE_QUANTA.Q_CAP(CHIPS)':
 'B': CDS_PINID='B';
NODE_NAME     PC2143 2
 '@T6G_MB_LIB.T6G(SCH_1):PAGE343_I101@PURE_QUANTA.Q_CAP(CHIPS)':
 'B': CDS_PINID='B';
NODE_NAME     PC2164 2
 '@T6G_MB_LIB.T6G(SCH_1):PAGE344_I2@PURE_QUANTA.Q_CAP(CHIPS)':
 'B': CDS_PINID='B';
NODE_NAME     PR3847 2
 '@T6G_MB_LIB.T6G(SCH_1):PAGE344_I4@PURE_QUANTA.Q_RES(CHIPS)':
 'B': CDS_PINID='B';
NODE_NAME     PC2166 2
 '@T6G_MB_LIB.T6G(SCH_1):PAGE344_I6@PURE_QUANTA.Q_CAP(CHIPS)':
 'B': CDS_PINID='B';
NODE_NAME     PC2165 2
 '@T6G_MB_LIB.T6G(SCH_1):PAGE344_I13@PURE_QUANTA.Q_CAP(CHIPS)':
 'B': CDS_PINID='B';
NODE_NAME     PR3849 2
 '@T6G_MB_LIB.T6G(SCH_1):PAGE344_I15@PURE_QUANTA.Q_RES(CHIPS)':
 'B': CDS_PINID='B';
NODE_NAME     PR3854 2
 '@T6G_MB_LIB.T6G(SCH_1):PAGE344_I20@PURE_QUANTA.Q_RES(CHIPS)':
 'B': CDS_PINID='B';
NODE_NAME     PC1320 2
 '@T6G_MB_LIB.T6G(SCH_1):PAGE344_I24@PURE_QUANTA.Q_CAP(CHIPS)':
 'B': CDS_PINID='B';
NODE_NAME     PC2168 2
 '@T6G_MB_LIB.T6G(SCH_1):PAGE344_I35@PURE_QUANTA.Q_CAP(CHIPS)':
 'B': CDS_PINID='B';
NODE_NAME     PC2174 2
 '@T6G_MB_LIB.T6G(SCH_1):PAGE344_I40@PURE_QUANTA.Q_CAP(CHIPS)':
 'B': CDS_PINID='B';
NODE_NAME     PR3855 2
 '@T6G_MB_LIB.T6G(SCH_1):PAGE344_I43@PURE_QUANTA.Q_RES(CHIPS)':
 'B': CDS_PINID='B';
NODE_NAME     PR3856 1
 '@T6G_MB_LIB.T6G(SCH_1):PAGE344_I46@PURE_QUANTA.Q_RES(CHIPS)':
 'A': CDS_PINID='A';
NODE_NAME     PC2169 2
 '@T6G_MB_LIB.T6G(SCH_1):PAGE344_I48@PURE_QUANTA.Q_CAP(CHIPS)':
 'B': CDS_PINID='B';
NODE_NAME     PC1321 2
 '@T6G_MB_LIB.T6G(SCH_1):PAGE344_I50@PURE_QUANTA.Q_CAP(CHIPS)':
 'B': CDS_PINID='B';
NODE_NAME     PU207 3
 '@T6G_MB_LIB.T6G(SCH_1):PAGE344_I51@PURE_QUANTA.MP5016GQHLZ(CHIPS)':
 'GND': CDS_PINID='GND';
NODE_NAME     PC1322 2
 '@T6G_MB_LIB.T6G(SCH_1):PAGE344_I54@PURE_QUANTA.Q_CAP(CHIPS)':
 'B': CDS_PINID='B';
NODE_NAME     PC2173 2
 '@T6G_MB_LIB.T6G(SCH_1):PAGE344_I56@PURE_QUANTA.Q_CAP(CHIPS)':
 'B': CDS_PINID='B';
NODE_NAME     U241 4
 '@T6G_MB_LIB.T6G(SCH_1):PAGE258_I1@PURE_QUANTA.74LVC2G08DP(CHIPS)':
 'GND': CDS_PINID='GND';
NODE_NAME     U240 4
 '@T6G_MB_LIB.T6G(SCH_1):PAGE258_I11@PURE_QUANTA.74LVC2G08DP(CHIPS)':
 'GND': CDS_PINID='GND';
NODE_NAME     U242 4
 '@T6G_MB_LIB.T6G(SCH_1):PAGE258_I13@PURE_QUANTA.74LVC2G08DP(CHIPS)':
 'GND': CDS_PINID='GND';
NODE_NAME     U243 2
 '@T6G_MB_LIB.T6G(SCH_1):PAGE258_I15@PURE_QUANTA.NC7SB3157(CHIPS)':
 'GND': CDS_PINID='GND';
NODE_NAME     U244 2
 '@T6G_MB_LIB.T6G(SCH_1):PAGE258_I16@PURE_QUANTA.NC7SB3157(CHIPS)':
 'GND': CDS_PINID='GND';
NODE_NAME     U246 2
 '@T6G_MB_LIB.T6G(SCH_1):PAGE258_I17@PURE_QUANTA.NC7SB3157(CHIPS)':
 'GND': CDS_PINID='GND';
NODE_NAME     U245 2
 '@T6G_MB_LIB.T6G(SCH_1):PAGE258_I18@PURE_QUANTA.NC7SB3157(CHIPS)':
 'GND': CDS_PINID='GND';
NODE_NAME     C1875 2
 '@T6G_MB_LIB.T6G(SCH_1):PAGE258_I21@PURE_QUANTA.Q_CAP(CHIPS)':
 'B': CDS_PINID='B';
NODE_NAME     C1874 2
 '@T6G_MB_LIB.T6G(SCH_1):PAGE258_I22@PURE_QUANTA.Q_CAP(CHIPS)':
 'B': CDS_PINID='B';
NODE_NAME     C1880 2
 '@T6G_MB_LIB.T6G(SCH_1):PAGE258_I27@PURE_QUANTA.Q_CAP(CHIPS)':
 'B': CDS_PINID='B';
NODE_NAME     C1879 2
 '@T6G_MB_LIB.T6G(SCH_1):PAGE258_I31@PURE_QUANTA.Q_CAP(CHIPS)':
 'B': CDS_PINID='B';
NODE_NAME     C1877 2
 '@T6G_MB_LIB.T6G(SCH_1):PAGE258_I34@PURE_QUANTA.Q_CAP(CHIPS)':
 'B': CDS_PINID='B';
NODE_NAME     C1878 2
 '@T6G_MB_LIB.T6G(SCH_1):PAGE258_I37@PURE_QUANTA.Q_CAP(CHIPS)':
 'B': CDS_PINID='B';
NODE_NAME     C1876 2
 '@T6G_MB_LIB.T6G(SCH_1):PAGE258_I41@PURE_QUANTA.Q_CAP(CHIPS)':
 'B': CDS_PINID='B';
NODE_NAME     PC2197 2
 '@T6G_MB_LIB.T6G(SCH_1):PAGE323_I3@PURE_QUANTA.Q_CAP(CHIPS)':
 'B': CDS_PINID='B';
NODE_NAME     PR3945 2
 '@T6G_MB_LIB.T6G(SCH_1):PAGE323_I4@PURE_QUANTA.Q_RES(CHIPS)':
 'B': CDS_PINID='B';
NODE_NAME     PR3947 1
 '@T6G_MB_LIB.T6G(SCH_1):PAGE323_I6@PURE_QUANTA.Q_RES(CHIPS)':
 'A': CDS_PINID='A';
NODE_NAME     PC2200 2
 '@T6G_MB_LIB.T6G(SCH_1):PAGE323_I9@PURE_QUANTA.Q_CAP(CHIPS)':
 'B': CDS_PINID='B';
NODE_NAME     PC2196 2
 '@T6G_MB_LIB.T6G(SCH_1):PAGE323_I13@PURE_QUANTA.Q_CAP(CHIPS)':
 'B': CDS_PINID='B';
NODE_NAME     PR3944 2
 '@T6G_MB_LIB.T6G(SCH_1):PAGE323_I15@PURE_QUANTA.Q_RES(CHIPS)':
 'B': CDS_PINID='B';
NODE_NAME     PC2341 2
 '@T6G_MB_LIB.T6G(SCH_1):PAGE323_I17@PURE_QUANTA.Q_CAP(CHIPS)':
 'B': CDS_PINID='B';
NODE_NAME     PC2281 2
 '@T6G_MB_LIB.T6G(SCH_1):PAGE323_I22@PURE_QUANTA.Q_CAP(CHIPS)':
 'B': CDS_PINID='B';
NODE_NAME     PC2198 2
 '@T6G_MB_LIB.T6G(SCH_1):PAGE323_I25@PURE_QUANTA.Q_CAP(CHIPS)':
 'B': CDS_PINID='B';
NODE_NAME     PC2201 2
 '@T6G_MB_LIB.T6G(SCH_1):PAGE323_I30@PURE_QUANTA.Q_CAP(CHIPS)':
 'B': CDS_PINID='B';
NODE_NAME     PU293 3
 '@T6G_MB_LIB.T6G(SCH_1):PAGE323_I31@PURE_QUANTA.MP5016GQHLZ(CHIPS)':
 'GND': CDS_PINID='GND';
NODE_NAME     PC2203 2
 '@T6G_MB_LIB.T6G(SCH_1):PAGE323_I32@PURE_QUANTA.Q_CAP(CHIPS)':
 'B': CDS_PINID='B';
NODE_NAME     PC2204 2
 '@T6G_MB_LIB.T6G(SCH_1):PAGE323_I34@PURE_QUANTA.Q_CAP(CHIPS)':
 'B': CDS_PINID='B';
NODE_NAME     PR3949 2
 '@T6G_MB_LIB.T6G(SCH_1):PAGE323_I36@PURE_QUANTA.Q_RES(CHIPS)':
 'B': CDS_PINID='B';
NODE_NAME     PC2202 2
 '@T6G_MB_LIB.T6G(SCH_1):PAGE323_I39@PURE_QUANTA.Q_CAP(CHIPS)':
 'B': CDS_PINID='B';
NODE_NAME     PR3954 2
 '@T6G_MB_LIB.T6G(SCH_1):PAGE323_I49@PURE_QUANTA.Q_RES(CHIPS)':
 'B': CDS_PINID='B';
NODE_NAME     PC2205 2
 '@T6G_MB_LIB.T6G(SCH_1):PAGE323_I51@PURE_QUANTA.Q_CAP(CHIPS)':
 'B': CDS_PINID='B';
NODE_NAME     PC2206 2
 '@T6G_MB_LIB.T6G(SCH_1):PAGE323_I56@PURE_QUANTA.Q_CAP(CHIPS)':
 'B': CDS_PINID='B';
NODE_NAME     R6049 2
 '@T6G_MB_LIB.T6G(SCH_1):PAGE324_I4@PURE_QUANTA.Q_RES(CHIPS)':
 'B': CDS_PINID='B';
NODE_NAME     Q126 1
 '@T6G_MB_LIB.T6G(SCH_1):PAGE324_I6@PURE_QUANTA.MOSFET_NCH_DUAL(CHIPS)':
 'S1': CDS_PINID='S1';
NODE_NAME     R4073 2
 '@T6G_MB_LIB.T6G(SCH_1):PAGE324_I11@PURE_QUANTA.Q_RES(CHIPS)':
 'B': CDS_PINID='B';
NODE_NAME     PR3965 2
 '@T6G_MB_LIB.T6G(SCH_1):PAGE324_I16@PURE_QUANTA.Q_RES(CHIPS)':
 'B': CDS_PINID='B';
NODE_NAME     PC2208 2
 '@T6G_MB_LIB.T6G(SCH_1):PAGE324_I20@PURE_QUANTA.Q_CAP(CHIPS)':
 'B': CDS_PINID='B';
NODE_NAME     Q127 4
 '@T6G_MB_LIB.T6G(SCH_1):PAGE324_I27@PURE_QUANTA.MOSFET_NCH_DUAL(CHIPS)':
 'S2': CDS_PINID='S2';
NODE_NAME     PR3962 2
 '@T6G_MB_LIB.T6G(SCH_1):PAGE324_I31@PURE_QUANTA.Q_RES(CHIPS)':
 'B': CDS_PINID='B';
NODE_NAME     PD114 A
 '@T6G_MB_LIB.T6G(SCH_1):PAGE324_I33@PURE_QUANTA.DIODE_TVS(CHIPS)':
 'A': CDS_PINID='A';
NODE_NAME     PC2207 2
 '@T6G_MB_LIB.T6G(SCH_1):PAGE324_I36@PURE_QUANTA.Q_CAP(CHIPS)':
 'B': CDS_PINID='B';
NODE_NAME     PR3969 2
 '@T6G_MB_LIB.T6G(SCH_1):PAGE324_I39@PURE_QUANTA.Q_RES(CHIPS)':
 'B': CDS_PINID='B';
NODE_NAME     PC2210 2
 '@T6G_MB_LIB.T6G(SCH_1):PAGE324_I41@PURE_QUANTA.Q_CAP(CHIPS)':
 'B': CDS_PINID='B';
NODE_NAME     PR3971 2
 '@T6G_MB_LIB.T6G(SCH_1):PAGE324_I45@PURE_QUANTA.Q_RES(CHIPS)':
 'B': CDS_PINID='B';
NODE_NAME     PD113 A
 '@T6G_MB_LIB.T6G(SCH_1):PAGE324_I50@PURE_QUANTA.SCHOTTKY_AC(CHIPS)':
 'A': CDS_PINID='A';
NODE_NAME     PC2220 2
 '@T6G_MB_LIB.T6G(SCH_1):PAGE324_I58@PURE_QUANTA.Q_CAP(CHIPS)':
 'B': CDS_PINID='B';
NODE_NAME     PC2211 1
 '@T6G_MB_LIB.T6G(SCH_1):PAGE324_I61@PURE_QUANTA.Q_CAP(CHIPS)':
 'A': CDS_PINID='A';
NODE_NAME     PR3968 2
 '@T6G_MB_LIB.T6G(SCH_1):PAGE324_I63@PURE_QUANTA.Q_RES(CHIPS)':
 'B': CDS_PINID='B';
NODE_NAME     PU294 A7
 '@T6G_MB_LIB.T6G(SCH_1):PAGE324_I66@PURE_QUANTA.MAX15090BEWIT(CHIPS)':
 'CDLY': CDS_PINID='CDLY';
NODE_NAME     PU294 B7
 '@T6G_MB_LIB.T6G(SCH_1):PAGE324_I66@PURE_QUANTA.MAX15090BEWIT(CHIPS)':
 'EN#': CDS_PINID='\en#\';
NODE_NAME     PU294 B2
 '@T6G_MB_LIB.T6G(SCH_1):PAGE324_I66@PURE_QUANTA.MAX15090BEWIT(CHIPS)':
 'GND_B2': CDS_PINID='GND_B2';
NODE_NAME     PU294 C1
 '@T6G_MB_LIB.T6G(SCH_1):PAGE324_I66@PURE_QUANTA.MAX15090BEWIT(CHIPS)':
 'GND_C1': CDS_PINID='GND_C1';
NODE_NAME     PU294 C2
 '@T6G_MB_LIB.T6G(SCH_1):PAGE324_I66@PURE_QUANTA.MAX15090BEWIT(CHIPS)':
 'GND_C2': CDS_PINID='GND_C2';
NODE_NAME     PR3970 2
 '@T6G_MB_LIB.T6G(SCH_1):PAGE324_I68@PURE_QUANTA.Q_RES(CHIPS)':
 'B': CDS_PINID='B';
NODE_NAME     PC2215 2
 '@T6G_MB_LIB.T6G(SCH_1):PAGE324_I69@PURE_QUANTA.Q_CAP(CHIPS)':
 'B': CDS_PINID='B';
NODE_NAME     PD112 A
 '@T6G_MB_LIB.T6G(SCH_1):PAGE324_I74@PURE_QUANTA.SCHOTTKY_AC(CHIPS)':
 'A': CDS_PINID='A';
NODE_NAME     PC2217 2
 '@T6G_MB_LIB.T6G(SCH_1):PAGE324_I78@PURE_QUANTA.Q_CAP(CHIPS)':
 'B': CDS_PINID='B';
NODE_NAME     PC2280 2
 '@T6G_MB_LIB.T6G(SCH_1):PAGE324_I80@PURE_QUANTA.Q_CAP(CHIPS)':
 'B': CDS_PINID='B';
NODE_NAME     J59 G1
 '@T6G_MB_LIB.T6G(SCH_1):PAGE345_I88@PURE_QUANTA.SCONN75K_APCI0155P004A(CHIPS)':
 'G1': CDS_PINID='G1';
NODE_NAME     J59 G2
 '@T6G_MB_LIB.T6G(SCH_1):PAGE345_I88@PURE_QUANTA.SCONN75K_APCI0155P004A(CHIPS)':
 'G2': CDS_PINID='G2';
NODE_NAME     J59 3
 '@T6G_MB_LIB.T6G(SCH_1):PAGE345_I88@PURE_QUANTA.SCONN75K_APCI0155P004A(CHIPS)':
 'GND2': CDS_PINID='GND2';
NODE_NAME     J59 9
 '@T6G_MB_LIB.T6G(SCH_1):PAGE345_I88@PURE_QUANTA.SCONN75K_APCI0155P004A(CHIPS)':
 'GND3': CDS_PINID='GND3';
NODE_NAME     J59 15
 '@T6G_MB_LIB.T6G(SCH_1):PAGE345_I88@PURE_QUANTA.SCONN75K_APCI0155P004A(CHIPS)':
 'GND4': CDS_PINID='GND4';
NODE_NAME     J59 21
 '@T6G_MB_LIB.T6G(SCH_1):PAGE345_I88@PURE_QUANTA.SCONN75K_APCI0155P004A(CHIPS)':
 'GND5': CDS_PINID='GND5';
NODE_NAME     J59 27
 '@T6G_MB_LIB.T6G(SCH_1):PAGE345_I88@PURE_QUANTA.SCONN75K_APCI0155P004A(CHIPS)':
 'GND6': CDS_PINID='GND6';
NODE_NAME     J59 33
 '@T6G_MB_LIB.T6G(SCH_1):PAGE345_I88@PURE_QUANTA.SCONN75K_APCI0155P004A(CHIPS)':
 'GND7': CDS_PINID='GND7';
NODE_NAME     J59 39
 '@T6G_MB_LIB.T6G(SCH_1):PAGE345_I88@PURE_QUANTA.SCONN75K_APCI0155P004A(CHIPS)':
 'GND8': CDS_PINID='GND8';
NODE_NAME     J59 45
 '@T6G_MB_LIB.T6G(SCH_1):PAGE345_I88@PURE_QUANTA.SCONN75K_APCI0155P004A(CHIPS)':
 'GND9': CDS_PINID='GND9';
NODE_NAME     J59 51
 '@T6G_MB_LIB.T6G(SCH_1):PAGE345_I88@PURE_QUANTA.SCONN75K_APCI0155P004A(CHIPS)':
 'GND10': CDS_PINID='GND10';
NODE_NAME     J59 57
 '@T6G_MB_LIB.T6G(SCH_1):PAGE345_I88@PURE_QUANTA.SCONN75K_APCI0155P004A(CHIPS)':
 'GND11': CDS_PINID='GND11';
NODE_NAME     J59 71
 '@T6G_MB_LIB.T6G(SCH_1):PAGE345_I88@PURE_QUANTA.SCONN75K_APCI0155P004A(CHIPS)':
 'GND12': CDS_PINID='GND12';
NODE_NAME     J59 73
 '@T6G_MB_LIB.T6G(SCH_1):PAGE345_I88@PURE_QUANTA.SCONN75K_APCI0155P004A(CHIPS)':
 'GND13': CDS_PINID='GND13';
NODE_NAME     J59 75
 '@T6G_MB_LIB.T6G(SCH_1):PAGE345_I88@PURE_QUANTA.SCONN75K_APCI0155P004A(CHIPS)':
 'GND14': CDS_PINID='GND14';
NODE_NAME     U98 1
 '@T6G_MB_LIB.T6G(SCH_1):PAGE346_I27@PURE_QUANTA.PCA9306DP1(CHIPS)':
 'GND': CDS_PINID='GND';
NODE_NAME     C1323 2
 '@T6G_MB_LIB.T6G(SCH_1):PAGE346_I28@PURE_QUANTA.Q_CAP(CHIPS)':
 'B': CDS_PINID='B';
NODE_NAME     C1305 2
 '@T6G_MB_LIB.T6G(SCH_1):PAGE346_I52@PURE_QUANTA.Q_CAP(CHIPS)':
 'B': CDS_PINID='B';
NODE_NAME     C1998 2
 '@T6G_MB_LIB.T6G(SCH_1):PAGE346_I82@PURE_QUANTA.Q_CAP(CHIPS)':
 'B': CDS_PINID='B';
NODE_NAME     C1997 2
 '@T6G_MB_LIB.T6G(SCH_1):PAGE346_I89@PURE_QUANTA.Q_CAP(CHIPS)':
 'B': CDS_PINID='B';
NODE_NAME     U279 4
 '@T6G_MB_LIB.T6G(SCH_1):PAGE346_I93@PURE_QUANTA.PCA9617ADP(CHIPS)':
 'GND': CDS_PINID='GND';
NODE_NAME     PC2229 2
 '@T6G_MB_LIB.T6G(SCH_1):PAGE350_I8@PURE_QUANTA.Q_CAP(CHIPS)':
 'B': CDS_PINID='B';
NODE_NAME     PR3999 2
 '@T6G_MB_LIB.T6G(SCH_1):PAGE350_I11@PURE_QUANTA.Q_RES(CHIPS)':
 'B': CDS_PINID='B';
NODE_NAME     PC2230 2
 '@T6G_MB_LIB.T6G(SCH_1):PAGE350_I31@PURE_QUANTA.Q_CAP(CHIPS)':
 'B': CDS_PINID='B';
NODE_NAME     PC2232 2
 '@T6G_MB_LIB.T6G(SCH_1):PAGE350_I33@PURE_QUANTA.Q_CAP(CHIPS)':
 'B': CDS_PINID='B';
NODE_NAME     PC2231 2
 '@T6G_MB_LIB.T6G(SCH_1):PAGE350_I37@PURE_QUANTA.Q_CAP(CHIPS)':
 'B': CDS_PINID='B';
NODE_NAME     PC2235 2
 '@T6G_MB_LIB.T6G(SCH_1):PAGE350_I45@PURE_QUANTA.Q_CAP(CHIPS)':
 'B': CDS_PINID='B';
NODE_NAME     PC2239 2
 '@T6G_MB_LIB.T6G(SCH_1):PAGE350_I52@PURE_QUANTA.Q_CAP(CHIPS)':
 'B': CDS_PINID='B';
NODE_NAME     PR4004 2
 '@T6G_MB_LIB.T6G(SCH_1):PAGE350_I62@PURE_QUANTA.Q_RES(CHIPS)':
 'B': CDS_PINID='B';
NODE_NAME     PC2233 2
 '@T6G_MB_LIB.T6G(SCH_1):PAGE350_I66@PURE_QUANTA.Q_CAP(CHIPS)':
 'B': CDS_PINID='B';
NODE_NAME     PC2234 1
 '@T6G_MB_LIB.T6G(SCH_1):PAGE350_I67@PURE_QUANTA.Q_CAP(CHIPS)':
 'A': CDS_PINID='A';
NODE_NAME     PR4008 2
 '@T6G_MB_LIB.T6G(SCH_1):PAGE350_I70@PURE_QUANTA.Q_RES(CHIPS)':
 'B': CDS_PINID='B';
NODE_NAME     PC2237 2
 '@T6G_MB_LIB.T6G(SCH_1):PAGE350_I72@PURE_QUANTA.Q_CAP(CHIPS)':
 'B': CDS_PINID='B';
NODE_NAME     PD116 A
 '@T6G_MB_LIB.T6G(SCH_1):PAGE350_I79@PURE_QUANTA.SCHOTTKY_AC(CHIPS)':
 'A': CDS_PINID='A';
NODE_NAME     PC2238 2
 '@T6G_MB_LIB.T6G(SCH_1):PAGE350_I80@PURE_QUANTA.Q_CAP(CHIPS)':
 'B': CDS_PINID='B';
NODE_NAME     Q37 1
 '@T6G_MB_LIB.T6G(SCH_1):PAGE273_I9@PURE_QUANTA.MOSFET_NCH_DUAL(CHIPS)':
 'S1': CDS_PINID='S1';
NODE_NAME     Q37 4
 '@T6G_MB_LIB.T6G(SCH_1):PAGE273_I14@PURE_QUANTA.MOSFET_NCH_DUAL(CHIPS)':
 'S2': CDS_PINID='S2';
NODE_NAME     C1227 2
 '@T6G_MB_LIB.T6G(SCH_1):PAGE273_I41@PURE_QUANTA.Q_CAP(CHIPS)':
 'B': CDS_PINID='B';
NODE_NAME     C1332 2
 '@T6G_MB_LIB.T6G(SCH_1):PAGE273_I48@PURE_QUANTA.Q_CAP(CHIPS)':
 'B': CDS_PINID='B';
NODE_NAME     C1333 2
 '@T6G_MB_LIB.T6G(SCH_1):PAGE273_I49@PURE_QUANTA.Q_CAP(CHIPS)':
 'B': CDS_PINID='B';
NODE_NAME     C60 2
 '@T6G_MB_LIB.T6G(SCH_1):PAGE273_I51@PURE_QUANTA.Q_CAP(CHIPS)':
 'B': CDS_PINID='B';
NODE_NAME     C1340 2
 '@T6G_MB_LIB.T6G(SCH_1):PAGE273_I61@PURE_QUANTA.Q_CAP(CHIPS)':
 'B': CDS_PINID='B';
NODE_NAME     U266 10
 '@T6G_MB_LIB.T6G(SCH_1):PAGE295_I30@PURE_QUANTA.ISL28022FRZT(CHIPS)':
 'GND': CDS_PINID='GND';
NODE_NAME     U266 TH
 '@T6G_MB_LIB.T6G(SCH_1):PAGE295_I30@PURE_QUANTA.ISL28022FRZT(CHIPS)':
 'TH_GND': CDS_PINID='TH_GND';
NODE_NAME     R3616 1
 '@T6G_MB_LIB.T6G(SCH_1):PAGE295_I31@PURE_QUANTA.Q_RES(CHIPS)':
 'A': CDS_PINID='A';
NODE_NAME     C2015 2
 '@T6G_MB_LIB.T6G(SCH_1):PAGE295_I34@PURE_QUANTA.Q_CAP(CHIPS)':
 'B': CDS_PINID='B';
NODE_NAME     R3617 1
 '@T6G_MB_LIB.T6G(SCH_1):PAGE295_I40@PURE_QUANTA.Q_RES(CHIPS)':
 'A': CDS_PINID='A';
NODE_NAME     C2024 2
 '@T6G_MB_LIB.T6G(SCH_1):PAGE295_I50@PURE_QUANTA.Q_CAP(CHIPS)':
 'B': CDS_PINID='B';
NODE_NAME     C2067 2
 '@T6G_MB_LIB.T6G(SCH_1):PAGE295_I125@PURE_QUANTA.Q_CAP(CHIPS)':
 'B': CDS_PINID='B';
NODE_NAME     U276 10
 '@T6G_MB_LIB.T6G(SCH_1):PAGE295_I129@PURE_QUANTA.ISL28022FRZT(CHIPS)':
 'GND': CDS_PINID='GND';
NODE_NAME     U276 TH
 '@T6G_MB_LIB.T6G(SCH_1):PAGE295_I129@PURE_QUANTA.ISL28022FRZT(CHIPS)':
 'TH_GND': CDS_PINID='TH_GND';
NODE_NAME     R3764 1
 '@T6G_MB_LIB.T6G(SCH_1):PAGE295_I135@PURE_QUANTA.Q_RES(CHIPS)':
 'A': CDS_PINID='A';
NODE_NAME     R3763 1
 '@T6G_MB_LIB.T6G(SCH_1):PAGE295_I136@PURE_QUANTA.Q_RES(CHIPS)':
 'A': CDS_PINID='A';
NODE_NAME     C2069 2
 '@T6G_MB_LIB.T6G(SCH_1):PAGE295_I142@PURE_QUANTA.Q_CAP(CHIPS)':
 'B': CDS_PINID='B';
NODE_NAME     C5232 2
 '@T6G_MB_LIB.T6G(SCH_1):PAGE358_I81@PURE_QUANTA.Q_CAP(CHIPS)':
 'B': CDS_PINID='B';
NODE_NAME     R5238 2
 '@T6G_MB_LIB.T6G(SCH_1):PAGE358_I83@PURE_QUANTA.Q_RES(CHIPS)':
 'B': CDS_PINID='B';
NODE_NAME     U5201 10
 '@T6G_MB_LIB.T6G(SCH_1):PAGE358_I84@PURE_QUANTA.TUSB211IRWBR(CHIPS)':
 'GND': CDS_PINID='GND';
NODE_NAME     C5236 2
 '@T6G_MB_LIB.T6G(SCH_1):PAGE358_I87@PURE_QUANTA.Q_CAP(CHIPS)':
 'B': CDS_PINID='B';
NODE_NAME     C5229 2
 '@T6G_MB_LIB.T6G(SCH_1):PAGE358_I88@PURE_QUANTA.Q_CAP(CHIPS)':
 'B': CDS_PINID='B';
NODE_NAME     C5234 2
 '@T6G_MB_LIB.T6G(SCH_1):PAGE358_I92@PURE_QUANTA.Q_CAP(CHIPS)':
 'B': CDS_PINID='B';
NODE_NAME     U268 TH
 '@T6G_MB_LIB.T6G(SCH_1):PAGE358_I100@PURE_QUANTA.GL852GOHY60(CHIPS)':
 'TH': CDS_PINID='TH';
NODE_NAME     R3653 2
 '@T6G_MB_LIB.T6G(SCH_1):PAGE358_I139@PURE_QUANTA.Q_RES(CHIPS)':
 'B': CDS_PINID='B';
NODE_NAME     C2034 2
 '@T6G_MB_LIB.T6G(SCH_1):PAGE358_I142@PURE_QUANTA.Q_CAP(CHIPS)':
 'B': CDS_PINID='B';
NODE_NAME     C2033 2
 '@T6G_MB_LIB.T6G(SCH_1):PAGE358_I143@PURE_QUANTA.Q_CAP(CHIPS)':
 'B': CDS_PINID='B';
NODE_NAME     C2032 2
 '@T6G_MB_LIB.T6G(SCH_1):PAGE358_I145@PURE_QUANTA.Q_CAP(CHIPS)':
 'B': CDS_PINID='B';
NODE_NAME     C2035 2
 '@T6G_MB_LIB.T6G(SCH_1):PAGE358_I147@PURE_QUANTA.Q_CAP(CHIPS)':
 'B': CDS_PINID='B';
NODE_NAME     C2031 2
 '@T6G_MB_LIB.T6G(SCH_1):PAGE358_I148@PURE_QUANTA.Q_CAP(CHIPS)':
 'B': CDS_PINID='B';
NODE_NAME     C2041 2
 '@T6G_MB_LIB.T6G(SCH_1):PAGE358_I158@PURE_QUANTA.Q_CAP(CHIPS)':
 'B': CDS_PINID='B';
NODE_NAME     C2040 2
 '@T6G_MB_LIB.T6G(SCH_1):PAGE358_I162@PURE_QUANTA.Q_CAP(CHIPS)':
 'B': CDS_PINID='B';
NODE_NAME     C2039 2
 '@T6G_MB_LIB.T6G(SCH_1):PAGE358_I163@PURE_QUANTA.Q_CAP(CHIPS)':
 'B': CDS_PINID='B';
NODE_NAME     C2038 2
 '@T6G_MB_LIB.T6G(SCH_1):PAGE358_I164@PURE_QUANTA.Q_CAP(CHIPS)':
 'B': CDS_PINID='B';
NODE_NAME     R3665 2
 '@T6G_MB_LIB.T6G(SCH_1):PAGE358_I182@PURE_QUANTA.Q_RES(CHIPS)':
 'B': CDS_PINID='B';
NODE_NAME     R3664 2
 '@T6G_MB_LIB.T6G(SCH_1):PAGE358_I187@PURE_QUANTA.Q_RES(CHIPS)':
 'B': CDS_PINID='B';
NODE_NAME     R3666 2
 '@T6G_MB_LIB.T6G(SCH_1):PAGE358_I199@PURE_QUANTA.Q_RES(CHIPS)':
 'B': CDS_PINID='B';
NODE_NAME     R3661 1
 '@T6G_MB_LIB.T6G(SCH_1):PAGE358_I201@PURE_QUANTA.Q_RES(CHIPS)':
 'A': CDS_PINID='A';
NODE_NAME     R4420 2
 '@T6G_MB_LIB.T6G(SCH_1):PAGE358_I202@PURE_QUANTA.Q_RES(CHIPS)':
 'B': CDS_PINID='B';
NODE_NAME     R4419 2
 '@T6G_MB_LIB.T6G(SCH_1):PAGE358_I203@PURE_QUANTA.Q_RES(CHIPS)':
 'B': CDS_PINID='B';
NODE_NAME     R4483 2
 '@T6G_MB_LIB.T6G(SCH_1):PAGE358_I206@PURE_QUANTA.Q_RES(CHIPS)':
 'B': CDS_PINID='B';
NODE_NAME     R4482 2
 '@T6G_MB_LIB.T6G(SCH_1):PAGE358_I208@PURE_QUANTA.Q_RES(CHIPS)':
 'B': CDS_PINID='B';
NODE_NAME     C2010 2
 '@T6G_MB_LIB.T6G(SCH_1):PAGE359_I16@PURE_QUANTA.Q_CAP(CHIPS)':
 'B': CDS_PINID='B';
NODE_NAME     R4199 2
 '@T6G_MB_LIB.T6G(SCH_1):PAGE359_I81@PURE_QUANTA.Q_RES(CHIPS)':
 'B': CDS_PINID='B';
NODE_NAME     R4207 2
 '@T6G_MB_LIB.T6G(SCH_1):PAGE359_I85@PURE_QUANTA.Q_RES(CHIPS)':
 'B': CDS_PINID='B';
NODE_NAME     R4191 2
 '@T6G_MB_LIB.T6G(SCH_1):PAGE359_I89@PURE_QUANTA.Q_RES(CHIPS)':
 'B': CDS_PINID='B';
NODE_NAME     R4205 2
 '@T6G_MB_LIB.T6G(SCH_1):PAGE359_I96@PURE_QUANTA.Q_RES(CHIPS)':
 'B': CDS_PINID='B';
NODE_NAME     R4197 2
 '@T6G_MB_LIB.T6G(SCH_1):PAGE359_I98@PURE_QUANTA.Q_RES(CHIPS)':
 'B': CDS_PINID='B';
NODE_NAME     R4189 2
 '@T6G_MB_LIB.T6G(SCH_1):PAGE359_I102@PURE_QUANTA.Q_RES(CHIPS)':
 'B': CDS_PINID='B';
NODE_NAME     C73 2
 '@T6G_MB_LIB.T6G(SCH_1):PAGE359_I104@PURE_QUANTA.Q_CAP(CHIPS)':
 'B': CDS_PINID='B';
NODE_NAME     C32 2
 '@T6G_MB_LIB.T6G(SCH_1):PAGE359_I119@PURE_QUANTA.Q_CAP(CHIPS)':
 'B': CDS_PINID='B';
NODE_NAME     R4187 2
 '@T6G_MB_LIB.T6G(SCH_1):PAGE359_I121@PURE_QUANTA.Q_RES(CHIPS)':
 'B': CDS_PINID='B';
NODE_NAME     R4195 2
 '@T6G_MB_LIB.T6G(SCH_1):PAGE359_I125@PURE_QUANTA.Q_RES(CHIPS)':
 'B': CDS_PINID='B';
NODE_NAME     R4203 2
 '@T6G_MB_LIB.T6G(SCH_1):PAGE359_I127@PURE_QUANTA.Q_RES(CHIPS)':
 'B': CDS_PINID='B';
NODE_NAME     C31 2
 '@T6G_MB_LIB.T6G(SCH_1):PAGE359_I139@PURE_QUANTA.Q_CAP(CHIPS)':
 'B': CDS_PINID='B';
NODE_NAME     R4185 2
 '@T6G_MB_LIB.T6G(SCH_1):PAGE359_I141@PURE_QUANTA.Q_RES(CHIPS)':
 'B': CDS_PINID='B';
NODE_NAME     R4193 2
 '@T6G_MB_LIB.T6G(SCH_1):PAGE359_I145@PURE_QUANTA.Q_RES(CHIPS)':
 'B': CDS_PINID='B';
NODE_NAME     R4201 2
 '@T6G_MB_LIB.T6G(SCH_1):PAGE359_I147@PURE_QUANTA.Q_RES(CHIPS)':
 'B': CDS_PINID='B';
NODE_NAME     U270 4
 '@T6G_MB_LIB.T6G(SCH_1):PAGE359_I164@PURE_QUANTA.LM75BD(CHIPS)':
 'GND': CDS_PINID='GND';
NODE_NAME     U271 4
 '@T6G_MB_LIB.T6G(SCH_1):PAGE359_I165@PURE_QUANTA.LM75BD(CHIPS)':
 'GND': CDS_PINID='GND';
NODE_NAME     U272 4
 '@T6G_MB_LIB.T6G(SCH_1):PAGE359_I166@PURE_QUANTA.LM75BD(CHIPS)':
 'GND': CDS_PINID='GND';
NODE_NAME     U273 4
 '@T6G_MB_LIB.T6G(SCH_1):PAGE359_I167@PURE_QUANTA.LM75BD(CHIPS)':
 'GND': CDS_PINID='GND';
NODE_NAME     C2018 2
 '@T6G_MB_LIB.T6G(SCH_1):PAGE360_I26@PURE_QUANTA.Q_CAP(CHIPS)':
 'B': CDS_PINID='B';
NODE_NAME     R3611 1
 '@T6G_MB_LIB.T6G(SCH_1):PAGE360_I36@PURE_QUANTA.Q_RES(CHIPS)':
 'A': CDS_PINID='A';
NODE_NAME     C2013 2
 '@T6G_MB_LIB.T6G(SCH_1):PAGE360_I42@PURE_QUANTA.Q_CAP(CHIPS)':
 'B': CDS_PINID='B';
NODE_NAME     R3610 1
 '@T6G_MB_LIB.T6G(SCH_1):PAGE360_I45@PURE_QUANTA.Q_RES(CHIPS)':
 'A': CDS_PINID='A';
NODE_NAME     U264 10
 '@T6G_MB_LIB.T6G(SCH_1):PAGE360_I46@PURE_QUANTA.ISL28022FRZT(CHIPS)':
 'GND': CDS_PINID='GND';
NODE_NAME     U264 TH
 '@T6G_MB_LIB.T6G(SCH_1):PAGE360_I46@PURE_QUANTA.ISL28022FRZT(CHIPS)':
 'TH_GND': CDS_PINID='TH_GND';
NODE_NAME     C2019 2
 '@T6G_MB_LIB.T6G(SCH_1):PAGE360_I49@PURE_QUANTA.Q_CAP(CHIPS)':
 'B': CDS_PINID='B';
NODE_NAME     R3613 1
 '@T6G_MB_LIB.T6G(SCH_1):PAGE360_I59@PURE_QUANTA.Q_RES(CHIPS)':
 'A': CDS_PINID='A';
NODE_NAME     C2014 2
 '@T6G_MB_LIB.T6G(SCH_1):PAGE360_I65@PURE_QUANTA.Q_CAP(CHIPS)':
 'B': CDS_PINID='B';
NODE_NAME     R3612 1
 '@T6G_MB_LIB.T6G(SCH_1):PAGE360_I68@PURE_QUANTA.Q_RES(CHIPS)':
 'A': CDS_PINID='A';
NODE_NAME     U265 10
 '@T6G_MB_LIB.T6G(SCH_1):PAGE360_I69@PURE_QUANTA.ISL28022FRZT(CHIPS)':
 'GND': CDS_PINID='GND';
NODE_NAME     U265 TH
 '@T6G_MB_LIB.T6G(SCH_1):PAGE360_I69@PURE_QUANTA.ISL28022FRZT(CHIPS)':
 'TH_GND': CDS_PINID='TH_GND';
NODE_NAME     U263 10
 '@T6G_MB_LIB.T6G(SCH_1):PAGE360_I94@PURE_QUANTA.ISL28022FRZT(CHIPS)':
 'GND': CDS_PINID='GND';
NODE_NAME     U263 TH
 '@T6G_MB_LIB.T6G(SCH_1):PAGE360_I94@PURE_QUANTA.ISL28022FRZT(CHIPS)':
 'TH_GND': CDS_PINID='TH_GND';
NODE_NAME     C2012 2
 '@T6G_MB_LIB.T6G(SCH_1):PAGE360_I98@PURE_QUANTA.Q_CAP(CHIPS)':
 'B': CDS_PINID='B';
NODE_NAME     R3608 1
 '@T6G_MB_LIB.T6G(SCH_1):PAGE360_I103@PURE_QUANTA.Q_RES(CHIPS)':
 'A': CDS_PINID='A';
NODE_NAME     R3609 1
 '@T6G_MB_LIB.T6G(SCH_1):PAGE360_I104@PURE_QUANTA.Q_RES(CHIPS)':
 'A': CDS_PINID='A';
NODE_NAME     C2017 2
 '@T6G_MB_LIB.T6G(SCH_1):PAGE360_I114@PURE_QUANTA.Q_CAP(CHIPS)':
 'B': CDS_PINID='B';
NODE_NAME     U64 4
 '@T6G_MB_LIB.T6G(SCH_1):PAGE361_I35@PURE_QUANTA.M24128BWMN6TP(CHIPS)':
 'VSS': CDS_PINID='VSS';
NODE_NAME     R718 2
 '@T6G_MB_LIB.T6G(SCH_1):PAGE361_I50@PURE_QUANTA.Q_RES(CHIPS)':
 'B': CDS_PINID='B';
NODE_NAME     R714 2
 '@T6G_MB_LIB.T6G(SCH_1):PAGE361_I52@PURE_QUANTA.Q_RES(CHIPS)':
 'B': CDS_PINID='B';
NODE_NAME     C629 2
 '@T6G_MB_LIB.T6G(SCH_1):PAGE361_I55@PURE_QUANTA.Q_CAP(CHIPS)':
 'B': CDS_PINID='B';
NODE_NAME     R710 2
 '@T6G_MB_LIB.T6G(SCH_1):PAGE361_I57@PURE_QUANTA.Q_RES(CHIPS)':
 'B': CDS_PINID='B';
NODE_NAME     R722 2
 '@T6G_MB_LIB.T6G(SCH_1):PAGE361_I61@PURE_QUANTA.Q_RES(CHIPS)':
 'B': CDS_PINID='B';
NODE_NAME     U190 S
 '@T6G_MB_LIB.T6G(SCH_1):PAGE363_I392@PURE_QUANTA.MOSFET_NCH_GDS_ESD_PROTECTED(CHIPS)':
 'S': CDS_PINID='S';
NODE_NAME     U192 4
 '@T6G_MB_LIB.T6G(SCH_1):PAGE363_I398@PURE_QUANTA.LTC4307CMS8(CHIPS)':
 'GND': CDS_PINID='GND';
NODE_NAME     C1751 2
 '@T6G_MB_LIB.T6G(SCH_1):PAGE363_I412@PURE_QUANTA.Q_CAP(CHIPS)':
 'B': CDS_PINID='B';
NODE_NAME     C74 2
 '@T6G_MB_LIB.T6G(SCH_1):PAGE363_I452@PURE_QUANTA.Q_CAP(CHIPS)':
 'B': CDS_PINID='B';
NODE_NAME     C64 2
 '@T6G_MB_LIB.T6G(SCH_1):PAGE363_I453@PURE_QUANTA.Q_CAP(CHIPS)':
 'B': CDS_PINID='B';
NODE_NAME     C65 2
 '@T6G_MB_LIB.T6G(SCH_1):PAGE363_I454@PURE_QUANTA.Q_CAP(CHIPS)':
 'B': CDS_PINID='B';
NODE_NAME     C66 2
 '@T6G_MB_LIB.T6G(SCH_1):PAGE363_I455@PURE_QUANTA.Q_CAP(CHIPS)':
 'B': CDS_PINID='B';
NODE_NAME     C67 2
 '@T6G_MB_LIB.T6G(SCH_1):PAGE363_I456@PURE_QUANTA.Q_CAP(CHIPS)':
 'B': CDS_PINID='B';
NODE_NAME     C1775 2
 '@T6G_MB_LIB.T6G(SCH_1):PAGE364_I14@PURE_QUANTA.Q_CAP(CHIPS)':
 'B': CDS_PINID='B';
NODE_NAME     R2941 2
 '@T6G_MB_LIB.T6G(SCH_1):PAGE364_I29@PURE_QUANTA.Q_RES(CHIPS)':
 'B': CDS_PINID='B';
NODE_NAME     R2948 2
 '@T6G_MB_LIB.T6G(SCH_1):PAGE364_I30@PURE_QUANTA.Q_RES(CHIPS)':
 'B': CDS_PINID='B';
NODE_NAME     U278 3
 '@T6G_MB_LIB.T6G(SCH_1):PAGE364_I31@PURE_QUANTA.74LVC1G08W57(CHIPS)':
 'GND': CDS_PINID='GND';
NODE_NAME     U308 2
 '@T6G_MB_LIB.T6G(SCH_1):PAGE364_I37@PURE_QUANTA.74LVC2G07DW7(CHIPS)':
 'GND': CDS_PINID='GND';
NODE_NAME     C69 2
 '@T6G_MB_LIB.T6G(SCH_1):PAGE364_I40@PURE_QUANTA.Q_CAP(CHIPS)':
 'B': CDS_PINID='B';
NODE_NAME     R4265 2
 '@T6G_MB_LIB.T6G(SCH_1):PAGE364_I43@PURE_QUANTA.Q_RES(CHIPS)':
 'B': CDS_PINID='B';
NODE_NAME     R4552 2
 '@T6G_MB_LIB.T6G(SCH_1):PAGE364_I50@PURE_QUANTA.Q_RES(CHIPS)':
 'B': CDS_PINID='B';
NODE_NAME     Q145 1
 '@T6G_MB_LIB.T6G(SCH_1):PAGE364_I53@PURE_QUANTA.MOSFET_NCH_DUAL(CHIPS)':
 'S1': CDS_PINID='S1';
NODE_NAME     Q145 4
 '@T6G_MB_LIB.T6G(SCH_1):PAGE364_I58@PURE_QUANTA.MOSFET_NCH_DUAL(CHIPS)':
 'S2': CDS_PINID='S2';
NODE_NAME     C70 2
 '@T6G_MB_LIB.T6G(SCH_1):PAGE364_I62@PURE_QUANTA.Q_CAP(CHIPS)':
 'B': CDS_PINID='B';
NODE_NAME     U158 S
 '@T6G_MB_LIB.T6G(SCH_1):PAGE365_I6@PURE_QUANTA.MOSFET_NCH_GDS_ESD_PROTECTED(CHIPS)':
 'S': CDS_PINID='S';
NODE_NAME     Q54 S
 '@T6G_MB_LIB.T6G(SCH_1):PAGE365_I14@PURE_QUANTA.MOSFET_NCH_GDS_ESD_PROTECTED(CHIPS)':
 'S': CDS_PINID='S';
NODE_NAME     R6035 2
 '@T6G_MB_LIB.T6G(SCH_1):PAGE348_I17@PURE_QUANTA.Q_RES(CHIPS)':
 'B': CDS_PINID='B';
NODE_NAME     R1801 2
 '@T6G_MB_LIB.T6G(SCH_1):PAGE348_I171@PURE_QUANTA.Q_RES(CHIPS)':
 'B': CDS_PINID='B';
NODE_NAME     J41 OB4
 '@T6G_MB_LIB.T6G(SCH_1):PAGE348_I176@PURE_QUANTA.SCONN168_ME1016810202011(CHIPS)':
 'DATA_IN': CDS_PINID='DATA_IN';
NODE_NAME     J41 G1
 '@T6G_MB_LIB.T6G(SCH_1):PAGE348_I176@PURE_QUANTA.SCONN168_ME1016810202011(CHIPS)':
 'G1': CDS_PINID='G1';
NODE_NAME     J41 G2
 '@T6G_MB_LIB.T6G(SCH_1):PAGE348_I176@PURE_QUANTA.SCONN168_ME1016810202011(CHIPS)':
 'G2': CDS_PINID='G2';
NODE_NAME     J41 G3
 '@T6G_MB_LIB.T6G(SCH_1):PAGE348_I176@PURE_QUANTA.SCONN168_ME1016810202011(CHIPS)':
 'G3': CDS_PINID='G3';
NODE_NAME     J41 G4
 '@T6G_MB_LIB.T6G(SCH_1):PAGE348_I176@PURE_QUANTA.SCONN168_ME1016810202011(CHIPS)':
 'G4': CDS_PINID='G4';
NODE_NAME     J41 G5
 '@T6G_MB_LIB.T6G(SCH_1):PAGE348_I176@PURE_QUANTA.SCONN168_ME1016810202011(CHIPS)':
 'G5': CDS_PINID='G5';
NODE_NAME     J41 A13
 '@T6G_MB_LIB.T6G(SCH_1):PAGE348_I176@PURE_QUANTA.SCONN168_ME1016810202011(CHIPS)':
 'GND_A13': CDS_PINID='GND_A13';
NODE_NAME     J41 A16
 '@T6G_MB_LIB.T6G(SCH_1):PAGE348_I176@PURE_QUANTA.SCONN168_ME1016810202011(CHIPS)':
 'GND_A16': CDS_PINID='GND_A16';
NODE_NAME     J41 A19
 '@T6G_MB_LIB.T6G(SCH_1):PAGE348_I176@PURE_QUANTA.SCONN168_ME1016810202011(CHIPS)':
 'GND_A19': CDS_PINID='GND_A19';
NODE_NAME     J41 A22
 '@T6G_MB_LIB.T6G(SCH_1):PAGE348_I176@PURE_QUANTA.SCONN168_ME1016810202011(CHIPS)':
 'GND_A22': CDS_PINID='GND_A22';
NODE_NAME     J41 A58
 '@T6G_MB_LIB.T6G(SCH_1):PAGE348_I176@PURE_QUANTA.SCONN168_ME1016810202011(CHIPS)':
 'GND_A58': CDS_PINID='GND_A58';
NODE_NAME     J41 A61
 '@T6G_MB_LIB.T6G(SCH_1):PAGE348_I176@PURE_QUANTA.SCONN168_ME1016810202011(CHIPS)':
 'GND_A61': CDS_PINID='GND_A61';
NODE_NAME     J41 A64
 '@T6G_MB_LIB.T6G(SCH_1):PAGE348_I176@PURE_QUANTA.SCONN168_ME1016810202011(CHIPS)':
 'GND_A64': CDS_PINID='GND_A64';
NODE_NAME     J41 A67
 '@T6G_MB_LIB.T6G(SCH_1):PAGE348_I176@PURE_QUANTA.SCONN168_ME1016810202011(CHIPS)':
 'GND_A67': CDS_PINID='GND_A67';
NODE_NAME     J41 B38
 '@T6G_MB_LIB.T6G(SCH_1):PAGE348_I176@PURE_QUANTA.SCONN168_ME1016810202011(CHIPS)':
 'GND_B38': CDS_PINID='GND_B38';
NODE_NAME     J41 B49
 '@T6G_MB_LIB.T6G(SCH_1):PAGE348_I176@PURE_QUANTA.SCONN168_ME1016810202011(CHIPS)':
 'GND_B49': CDS_PINID='GND_B49';
NODE_NAME     J41 B52
 '@T6G_MB_LIB.T6G(SCH_1):PAGE348_I176@PURE_QUANTA.SCONN168_ME1016810202011(CHIPS)':
 'GND_B52': CDS_PINID='GND_B52';
NODE_NAME     J41 B55
 '@T6G_MB_LIB.T6G(SCH_1):PAGE348_I176@PURE_QUANTA.SCONN168_ME1016810202011(CHIPS)':
 'GND_B55': CDS_PINID='GND_B55';
NODE_NAME     J41 B58
 '@T6G_MB_LIB.T6G(SCH_1):PAGE348_I176@PURE_QUANTA.SCONN168_ME1016810202011(CHIPS)':
 'GND_B58': CDS_PINID='GND_B58';
NODE_NAME     J41 B61
 '@T6G_MB_LIB.T6G(SCH_1):PAGE348_I176@PURE_QUANTA.SCONN168_ME1016810202011(CHIPS)':
 'GND_B61': CDS_PINID='GND_B61';
NODE_NAME     J41 B64
 '@T6G_MB_LIB.T6G(SCH_1):PAGE348_I176@PURE_QUANTA.SCONN168_ME1016810202011(CHIPS)':
 'GND_B64': CDS_PINID='GND_B64';
NODE_NAME     J41 B67
 '@T6G_MB_LIB.T6G(SCH_1):PAGE348_I176@PURE_QUANTA.SCONN168_ME1016810202011(CHIPS)':
 'GND_B67': CDS_PINID='GND_B67';
NODE_NAME     J41 OA13
 '@T6G_MB_LIB.T6G(SCH_1):PAGE348_I176@PURE_QUANTA.SCONN168_ME1016810202011(CHIPS)':
 'GND_OA13': CDS_PINID='GND_OA13';
NODE_NAME     J41 OB10
 '@T6G_MB_LIB.T6G(SCH_1):PAGE348_I176@PURE_QUANTA.SCONN168_ME1016810202011(CHIPS)':
 'GND_OB10': CDS_PINID='GND_OB10';
NODE_NAME     J41 A33
 '@T6G_MB_LIB.T6G(SCH_1):PAGE348_I176@PURE_QUANTA.SCONN168_ME1016810202011(CHIPS)':
 'PERN5': CDS_PINID='PERN5';
NODE_NAME     J41 B10
 '@T6G_MB_LIB.T6G(SCH_1):PAGE348_I176@PURE_QUANTA.SCONN168_ME1016810202011(CHIPS)':
 'PERST0#': CDS_PINID='\perst0#\';
NODE_NAME     J41 B17
 '@T6G_MB_LIB.T6G(SCH_1):PAGE348_I176@PURE_QUANTA.SCONN168_ME1016810202011(CHIPS)':
 'PETN0': CDS_PINID='PETN0';
NODE_NAME     J41 B26
 '@T6G_MB_LIB.T6G(SCH_1):PAGE348_I176@PURE_QUANTA.SCONN168_ME1016810202011(CHIPS)':
 'PETN3': CDS_PINID='PETN3';
NODE_NAME     J41 B33
 '@T6G_MB_LIB.T6G(SCH_1):PAGE348_I176@PURE_QUANTA.SCONN168_ME1016810202011(CHIPS)':
 'PETN5': CDS_PINID='PETN5';
NODE_NAME     J41 A42
 '@T6G_MB_LIB.T6G(SCH_1):PAGE348_I176@PURE_QUANTA.SCONN168_ME1016810202011(CHIPS)':
 'PRSNTB1#': CDS_PINID='\prsntb1#\';
NODE_NAME     J41 B70
 '@T6G_MB_LIB.T6G(SCH_1):PAGE348_I176@PURE_QUANTA.SCONN168_ME1016810202011(CHIPS)':
 'PRSNTB3#': CDS_PINID='\prsntb3#\';
NODE_NAME     J41 A70
 '@T6G_MB_LIB.T6G(SCH_1):PAGE348_I176@PURE_QUANTA.SCONN168_ME1016810202011(CHIPS)':
 'PWRBRK0#': CDS_PINID='\pwrbrk0#\';
NODE_NAME     J41 OA4
 '@T6G_MB_LIB.T6G(SCH_1):PAGE348_I176@PURE_QUANTA.SCONN168_ME1016810202011(CHIPS)':
 'RBT_ARB_IN': CDS_PINID='RBT_ARB_IN';
NODE_NAME     J41 OB7
 '@T6G_MB_LIB.T6G(SCH_1):PAGE348_I176@PURE_QUANTA.SCONN168_ME1016810202011(CHIPS)':
 'SLOT_ID0': CDS_PINID='SLOT_ID0';
NODE_NAME     J41 OA3
 '@T6G_MB_LIB.T6G(SCH_1):PAGE348_I176@PURE_QUANTA.SCONN168_ME1016810202011(CHIPS)':
 'WAKE#': CDS_PINID='\wake#\';
NODE_NAME     R6027 2
 '@T6G_MB_LIB.T6G(SCH_1):PAGE349_I32@PURE_QUANTA.Q_RES(CHIPS)':
 'B': CDS_PINID='B';
NODE_NAME     C63 2
 '@T6G_MB_LIB.T6G(SCH_1):PAGE349_I112@PURE_QUANTA.Q_CAP(CHIPS)':
 'B': CDS_PINID='B';
NODE_NAME     J8 4
 '@T6G_MB_LIB.T6G(SCH_1):PAGE349_I148@PURE_QUANTA.CONN4_HFK1040L0P1L7H(CHIPS)':
 '4': CDS_PINID='\4\';
NODE_NAME     R2694 2
 '@T6G_MB_LIB.T6G(SCH_1):PAGE246_I2@PURE_QUANTA.Q_RES(CHIPS)':
 'B': CDS_PINID='B';
NODE_NAME     R2696 2
 '@T6G_MB_LIB.T6G(SCH_1):PAGE246_I6@PURE_QUANTA.Q_RES(CHIPS)':
 'B': CDS_PINID='B';
NODE_NAME     R4514 2
 '@T6G_MB_LIB.T6G(SCH_1):PAGE232_I8@PURE_QUANTA.Q_RES(CHIPS)':
 'B': CDS_PINID='B';
NODE_NAME     Y8003 2
 '@T6G_MB_LIB.T6G(SCH_1):PAGE232_I14@PURE_QUANTA.Q_XTAL_4P_13BI_24GND(CHIPS)':
 'G1': CDS_PINID='G1';
NODE_NAME     Y8003 4
 '@T6G_MB_LIB.T6G(SCH_1):PAGE232_I14@PURE_QUANTA.Q_XTAL_4P_13BI_24GND(CHIPS)':
 'G2': CDS_PINID='G2';
NODE_NAME     U248 3
 '@T6G_MB_LIB.T6G(SCH_1):PAGE232_I26@PURE_QUANTA.74LVC1G32GW(CHIPS)':
 'GND': CDS_PINID='GND';
NODE_NAME     C1882 2
 '@T6G_MB_LIB.T6G(SCH_1):PAGE232_I28@PURE_QUANTA.Q_CAP(CHIPS)':
 'B': CDS_PINID='B';
NODE_NAME     C1883 2
 '@T6G_MB_LIB.T6G(SCH_1):PAGE232_I36@PURE_QUANTA.Q_CAP(CHIPS)':
 'B': CDS_PINID='B';
NODE_NAME     C2257 2
 '@T6G_MB_LIB.T6G(SCH_1):PAGE232_I37@PURE_QUANTA.Q_CAP(CHIPS)':
 'B': CDS_PINID='B';
NODE_NAME     C1886 2
 '@T6G_MB_LIB.T6G(SCH_1):PAGE232_I40@PURE_QUANTA.Q_CAP(CHIPS)':
 'B': CDS_PINID='B';
NODE_NAME     C1889 2
 '@T6G_MB_LIB.T6G(SCH_1):PAGE232_I41@PURE_QUANTA.Q_CAP(CHIPS)':
 'B': CDS_PINID='B';
NODE_NAME     C95 2
 '@T6G_MB_LIB.T6G(SCH_1):PAGE232_I42@PURE_QUANTA.Q_CAP(CHIPS)':
 'B': CDS_PINID='B';
NODE_NAME     R4079 2
 '@T6G_MB_LIB.T6G(SCH_1):PAGE232_I46@PURE_QUANTA.Q_RES(CHIPS)':
 'B': CDS_PINID='B';
NODE_NAME     R4082 2
 '@T6G_MB_LIB.T6G(SCH_1):PAGE232_I55@PURE_QUANTA.Q_RES(CHIPS)':
 'B': CDS_PINID='B';
NODE_NAME     C1884 2
 '@T6G_MB_LIB.T6G(SCH_1):PAGE232_I68@PURE_QUANTA.Q_CAP(CHIPS)':
 'B': CDS_PINID='B';
NODE_NAME     C97 2
 '@T6G_MB_LIB.T6G(SCH_1):PAGE232_I69@PURE_QUANTA.Q_CAP(CHIPS)':
 'B': CDS_PINID='B';
NODE_NAME     C1859 2
 '@T6G_MB_LIB.T6G(SCH_1):PAGE248_I4@PURE_QUANTA.Q_CAP(CHIPS)':
 'B': CDS_PINID='B';
NODE_NAME     U235 4
 '@T6G_MB_LIB.T6G(SCH_1):PAGE248_I6@PURE_QUANTA.PCA9617ADP(CHIPS)':
 'GND': CDS_PINID='GND';
NODE_NAME     C1861 2
 '@T6G_MB_LIB.T6G(SCH_1):PAGE248_I9@PURE_QUANTA.Q_CAP(CHIPS)':
 'B': CDS_PINID='B';
NODE_NAME     U236 4
 '@T6G_MB_LIB.T6G(SCH_1):PAGE248_I14@PURE_QUANTA.PCA9617ADP(CHIPS)':
 'GND': CDS_PINID='GND';
NODE_NAME     C1860 2
 '@T6G_MB_LIB.T6G(SCH_1):PAGE248_I15@PURE_QUANTA.Q_CAP(CHIPS)':
 'B': CDS_PINID='B';
NODE_NAME     C1862 2
 '@T6G_MB_LIB.T6G(SCH_1):PAGE248_I19@PURE_QUANTA.Q_CAP(CHIPS)':
 'B': CDS_PINID='B';
NODE_NAME     R2666 2
 '@T6G_MB_LIB.T6G(SCH_1):PAGE249_I8@PURE_QUANTA.Q_RES(CHIPS)':
 'B': CDS_PINID='B';
NODE_NAME     U200 4
 '@T6G_MB_LIB.T6G(SCH_1):PAGE249_I15@PURE_QUANTA.LTC4307CMS8(CHIPS)':
 'GND': CDS_PINID='GND';
NODE_NAME     R4603 2
 '@T6G_MB_LIB.T6G(SCH_1):PAGE249_I23@PURE_QUANTA.Q_RES(CHIPS)':
 'B': CDS_PINID='B';
NODE_NAME     U176 4
 '@T6G_MB_LIB.T6G(SCH_1):PAGE249_I30@PURE_QUANTA.LTC4307CMS8(CHIPS)':
 'GND': CDS_PINID='GND';
NODE_NAME     C1796 2
 '@T6G_MB_LIB.T6G(SCH_1):PAGE249_I32@PURE_QUANTA.Q_CAP(CHIPS)':
 'B': CDS_PINID='B';
NODE_NAME     U194 4
 '@T6G_MB_LIB.T6G(SCH_1):PAGE249_I42@PURE_QUANTA.LTC4307CMS8(CHIPS)':
 'GND': CDS_PINID='GND';
NODE_NAME     U175 4
 '@T6G_MB_LIB.T6G(SCH_1):PAGE249_I49@PURE_QUANTA.LTC4307CMS8(CHIPS)':
 'GND': CDS_PINID='GND';
NODE_NAME     C1707 2
 '@T6G_MB_LIB.T6G(SCH_1):PAGE249_I52@PURE_QUANTA.Q_CAP(CHIPS)':
 'B': CDS_PINID='B';
NODE_NAME     C1708 2
 '@T6G_MB_LIB.T6G(SCH_1):PAGE249_I61@PURE_QUANTA.Q_CAP(CHIPS)':
 'B': CDS_PINID='B';
NODE_NAME     C1766 2
 '@T6G_MB_LIB.T6G(SCH_1):PAGE249_I78@PURE_QUANTA.Q_CAP(CHIPS)':
 'B': CDS_PINID='B';
NODE_NAME     C611 2
 '@T6G_MB_LIB.T6G(SCH_1):PAGE137_I6@PURE_QUANTA.Q_CAP(CHIPS)':
 'B': CDS_PINID='B';
NODE_NAME     C612 2
 '@T6G_MB_LIB.T6G(SCH_1):PAGE137_I8@PURE_QUANTA.Q_CAP(CHIPS)':
 'B': CDS_PINID='B';
NODE_NAME     C23 2
 '@T6G_MB_LIB.T6G(SCH_1):PAGE137_I26@PURE_QUANTA.Q_CAP(CHIPS)':
 'B': CDS_PINID='B';
NODE_NAME     C26 2
 '@T6G_MB_LIB.T6G(SCH_1):PAGE137_I29@PURE_QUANTA.Q_CAP(CHIPS)':
 'B': CDS_PINID='B';
NODE_NAME     U5 4
 '@T6G_MB_LIB.T6G(SCH_1):PAGE137_I48@PURE_QUANTA.PCA9617ADP(CHIPS)':
 'GND': CDS_PINID='GND';
NODE_NAME     R3704 2
 '@T6G_MB_LIB.T6G(SCH_1):PAGE251_I1@PURE_QUANTA.Q_RES(CHIPS)':
 'B': CDS_PINID='B';
NODE_NAME     R3707 2
 '@T6G_MB_LIB.T6G(SCH_1):PAGE251_I4@PURE_QUANTA.Q_RES(CHIPS)':
 'B': CDS_PINID='B';
NODE_NAME     R3709 2
 '@T6G_MB_LIB.T6G(SCH_1):PAGE251_I6@PURE_QUANTA.Q_RES(CHIPS)':
 'B': CDS_PINID='B';
NODE_NAME     C2056 2
 '@T6G_MB_LIB.T6G(SCH_1):PAGE251_I38@PURE_QUANTA.Q_CAP(CHIPS)':
 'B': CDS_PINID='B';
NODE_NAME     U39 12
 '@T6G_MB_LIB.T6G(SCH_1):PAGE251_I74@PURE_QUANTA.TCA9548APWR(CHIPS)':
 'GND': CDS_PINID='GND';
NODE_NAME     R317 2
 '@T6G_MB_LIB.T6G(SCH_1):PAGE252_I2@PURE_QUANTA.Q_RES(CHIPS)':
 'B': CDS_PINID='B';
NODE_NAME     R319 2
 '@T6G_MB_LIB.T6G(SCH_1):PAGE252_I4@PURE_QUANTA.Q_RES(CHIPS)':
 'B': CDS_PINID='B';
NODE_NAME     R587 2
 '@T6G_MB_LIB.T6G(SCH_1):PAGE252_I6@PURE_QUANTA.Q_RES(CHIPS)':
 'B': CDS_PINID='B';
NODE_NAME     U36 12
 '@T6G_MB_LIB.T6G(SCH_1):PAGE252_I33@PURE_QUANTA.TCA9548APWR(CHIPS)':
 'GND': CDS_PINID='GND';
NODE_NAME     C106 2
 '@T6G_MB_LIB.T6G(SCH_1):PAGE252_I34@PURE_QUANTA.Q_CAP(CHIPS)':
 'B': CDS_PINID='B';
NODE_NAME     U134 2
 '@T6G_MB_LIB.T6G(SCH_1):PAGE297_I4@PURE_QUANTA.74LVC2G07DW7(CHIPS)':
 'GND': CDS_PINID='GND';
NODE_NAME     R10296 2
 '@T6G_MB_LIB.T6G(SCH_1):PAGE297_I6@PURE_QUANTA.Q_RES(CHIPS)':
 'B': CDS_PINID='B';
NODE_NAME     C1592 2
 '@T6G_MB_LIB.T6G(SCH_1):PAGE297_I36@PURE_QUANTA.Q_CAP(CHIPS)':
 'B': CDS_PINID='B';
NODE_NAME     C1276 2
 '@T6G_MB_LIB.T6G(SCH_1):PAGE297_I66@PURE_QUANTA.Q_CAP(CHIPS)':
 'B': CDS_PINID='B';
NODE_NAME     C1277 2
 '@T6G_MB_LIB.T6G(SCH_1):PAGE297_I67@PURE_QUANTA.Q_CAP(CHIPS)':
 'B': CDS_PINID='B';
NODE_NAME     C1278 2
 '@T6G_MB_LIB.T6G(SCH_1):PAGE297_I68@PURE_QUANTA.Q_CAP(CHIPS)':
 'B': CDS_PINID='B';
NODE_NAME     C1279 2
 '@T6G_MB_LIB.T6G(SCH_1):PAGE297_I74@PURE_QUANTA.Q_CAP(CHIPS)':
 'B': CDS_PINID='B';
NODE_NAME     R2426 2
 '@T6G_MB_LIB.T6G(SCH_1):PAGE297_I75@PURE_QUANTA.Q_RES(CHIPS)':
 'B': CDS_PINID='B';
NODE_NAME     C1282 2
 '@T6G_MB_LIB.T6G(SCH_1):PAGE297_I87@PURE_QUANTA.Q_CAP(CHIPS)':
 'B': CDS_PINID='B';
NODE_NAME     C1283 2
 '@T6G_MB_LIB.T6G(SCH_1):PAGE297_I88@PURE_QUANTA.Q_CAP(CHIPS)':
 'B': CDS_PINID='B';
NODE_NAME     J90 G1
 '@T6G_MB_LIB.T6G(SCH_1):PAGE297_I90@PURE_QUANTA.SCONN56_123276793(CHIPS)':
 'G1': CDS_PINID='G1';
NODE_NAME     J90 G2
 '@T6G_MB_LIB.T6G(SCH_1):PAGE297_I90@PURE_QUANTA.SCONN56_123276793(CHIPS)':
 'G2': CDS_PINID='G2';
NODE_NAME     J90 A1
 '@T6G_MB_LIB.T6G(SCH_1):PAGE297_I90@PURE_QUANTA.SCONN56_123276793(CHIPS)':
 'GND_A1': CDS_PINID='GND_A1';
NODE_NAME     J90 A2
 '@T6G_MB_LIB.T6G(SCH_1):PAGE297_I90@PURE_QUANTA.SCONN56_123276793(CHIPS)':
 'GND_A2': CDS_PINID='GND_A2';
NODE_NAME     J90 A3
 '@T6G_MB_LIB.T6G(SCH_1):PAGE297_I90@PURE_QUANTA.SCONN56_123276793(CHIPS)':
 'GND_A3': CDS_PINID='GND_A3';
NODE_NAME     J90 A4
 '@T6G_MB_LIB.T6G(SCH_1):PAGE297_I90@PURE_QUANTA.SCONN56_123276793(CHIPS)':
 'GND_A4': CDS_PINID='GND_A4';
NODE_NAME     J90 A5
 '@T6G_MB_LIB.T6G(SCH_1):PAGE297_I90@PURE_QUANTA.SCONN56_123276793(CHIPS)':
 'GND_A5': CDS_PINID='GND_A5';
NODE_NAME     J90 A6
 '@T6G_MB_LIB.T6G(SCH_1):PAGE297_I90@PURE_QUANTA.SCONN56_123276793(CHIPS)':
 'GND_A6': CDS_PINID='GND_A6';
NODE_NAME     J90 A13
 '@T6G_MB_LIB.T6G(SCH_1):PAGE297_I90@PURE_QUANTA.SCONN56_123276793(CHIPS)':
 'GND_A13': CDS_PINID='GND_A13';
NODE_NAME     J90 A16
 '@T6G_MB_LIB.T6G(SCH_1):PAGE297_I90@PURE_QUANTA.SCONN56_123276793(CHIPS)':
 'GND_A16': CDS_PINID='GND_A16';
NODE_NAME     J90 A19
 '@T6G_MB_LIB.T6G(SCH_1):PAGE297_I90@PURE_QUANTA.SCONN56_123276793(CHIPS)':
 'GND_A19': CDS_PINID='GND_A19';
NODE_NAME     J90 A22
 '@T6G_MB_LIB.T6G(SCH_1):PAGE297_I90@PURE_QUANTA.SCONN56_123276793(CHIPS)':
 'GND_A22': CDS_PINID='GND_A22';
NODE_NAME     J90 A25
 '@T6G_MB_LIB.T6G(SCH_1):PAGE297_I90@PURE_QUANTA.SCONN56_123276793(CHIPS)':
 'GND_A25': CDS_PINID='GND_A25';
NODE_NAME     J90 A28
 '@T6G_MB_LIB.T6G(SCH_1):PAGE297_I90@PURE_QUANTA.SCONN56_123276793(CHIPS)':
 'GND_A28': CDS_PINID='GND_A28';
NODE_NAME     J90 B13
 '@T6G_MB_LIB.T6G(SCH_1):PAGE297_I90@PURE_QUANTA.SCONN56_123276793(CHIPS)':
 'GND_B13': CDS_PINID='GND_B13';
NODE_NAME     J90 B16
 '@T6G_MB_LIB.T6G(SCH_1):PAGE297_I90@PURE_QUANTA.SCONN56_123276793(CHIPS)':
 'GND_B16': CDS_PINID='GND_B16';
NODE_NAME     J90 B19
 '@T6G_MB_LIB.T6G(SCH_1):PAGE297_I90@PURE_QUANTA.SCONN56_123276793(CHIPS)':
 'GND_B19': CDS_PINID='GND_B19';
NODE_NAME     J90 B22
 '@T6G_MB_LIB.T6G(SCH_1):PAGE297_I90@PURE_QUANTA.SCONN56_123276793(CHIPS)':
 'GND_B22': CDS_PINID='GND_B22';
NODE_NAME     J90 B25
 '@T6G_MB_LIB.T6G(SCH_1):PAGE297_I90@PURE_QUANTA.SCONN56_123276793(CHIPS)':
 'GND_B25': CDS_PINID='GND_B25';
NODE_NAME     J90 B28
 '@T6G_MB_LIB.T6G(SCH_1):PAGE297_I90@PURE_QUANTA.SCONN56_123276793(CHIPS)':
 'GND_B28': CDS_PINID='GND_B28';
NODE_NAME     U259 2
 '@T6G_MB_LIB.T6G(SCH_1):PAGE345_I5@PURE_QUANTA.SN74LVC2G07DCKR(CHIPS)':
 'GND': CDS_PINID='GND';
NODE_NAME     C2007 2
 '@T6G_MB_LIB.T6G(SCH_1):PAGE345_I6@PURE_QUANTA.Q_CAP(CHIPS)':
 'B': CDS_PINID='B';
NODE_NAME     Q95 1
 '@T6G_MB_LIB.T6G(SCH_1):PAGE345_I8@PURE_QUANTA.MOSFET_NCH_DUAL(CHIPS)':
 'S1': CDS_PINID='S1';
NODE_NAME     R138 2
 '@T6G_MB_LIB.T6G(SCH_1):PAGE345_I15@PURE_QUANTA.Q_RES(CHIPS)':
 'B': CDS_PINID='B';
NODE_NAME     U239 3
 '@T6G_MB_LIB.T6G(SCH_1):PAGE345_I53@PURE_QUANTA.74LVC1G126SE7(CHIPS)':
 'GND': CDS_PINID='GND';
NODE_NAME     C1873 2
 '@T6G_MB_LIB.T6G(SCH_1):PAGE345_I56@PURE_QUANTA.Q_CAP(CHIPS)':
 'B': CDS_PINID='B';
NODE_NAME     R3297 2
 '@T6G_MB_LIB.T6G(SCH_1):PAGE345_I60@PURE_QUANTA.Q_RES(CHIPS)':
 'B': CDS_PINID='B';
NODE_NAME     C1920 2
 '@T6G_MB_LIB.T6G(SCH_1):PAGE345_I77@PURE_QUANTA.Q_CAP(CHIPS)':
 'B': CDS_PINID='B';
NODE_NAME     C1921 2
 '@T6G_MB_LIB.T6G(SCH_1):PAGE345_I78@PURE_QUANTA.Q_CAP(CHIPS)':
 'B': CDS_PINID='B';
NODE_NAME     C9922 2
 '@T6G_MB_LIB.T6G(SCH_1):PAGE345_I79@PURE_QUANTA.Q_CAP(CHIPS)':
 'B': CDS_PINID='B';
NODE_NAME     R1605 2
 '@T6G_MB_LIB.T6G(SCH_1):PAGE345_I83@PURE_QUANTA.Q_RES(CHIPS)':
 'B': CDS_PINID='B';
NODE_NAME     C1923 2
 '@T6G_MB_LIB.T6G(SCH_1):PAGE345_I84@PURE_QUANTA.Q_CAP(CHIPS)':
 'B': CDS_PINID='B';
NODE_NAME     C1924 2
 '@T6G_MB_LIB.T6G(SCH_1):PAGE345_I85@PURE_QUANTA.Q_CAP(CHIPS)':
 'B': CDS_PINID='B';
NODE_NAME     C1925 2
 '@T6G_MB_LIB.T6G(SCH_1):PAGE345_I86@PURE_QUANTA.Q_CAP(CHIPS)':
 'B': CDS_PINID='B';
NODE_NAME     R3163 2
 '@T6G_MB_LIB.T6G(SCH_1):PAGE341_I2@PURE_QUANTA.Q_RES(CHIPS)':
 'B': CDS_PINID='B';
NODE_NAME     R3167 2
 '@T6G_MB_LIB.T6G(SCH_1):PAGE341_I3@PURE_QUANTA.Q_RES(CHIPS)':
 'B': CDS_PINID='B';
NODE_NAME     R3175 2
 '@T6G_MB_LIB.T6G(SCH_1):PAGE341_I11@PURE_QUANTA.Q_RES(CHIPS)':
 'B': CDS_PINID='B';
NODE_NAME     C1829 2
 '@T6G_MB_LIB.T6G(SCH_1):PAGE341_I13@PURE_QUANTA.Q_CAP(CHIPS)':
 'B': CDS_PINID='B';
NODE_NAME     C1830 2
 '@T6G_MB_LIB.T6G(SCH_1):PAGE341_I14@PURE_QUANTA.Q_CAP(CHIPS)':
 'B': CDS_PINID='B';
NODE_NAME     C1831 2
 '@T6G_MB_LIB.T6G(SCH_1):PAGE341_I15@PURE_QUANTA.Q_CAP(CHIPS)':
 'B': CDS_PINID='B';
NODE_NAME     C1832 2
 '@T6G_MB_LIB.T6G(SCH_1):PAGE341_I16@PURE_QUANTA.Q_CAP(CHIPS)':
 'B': CDS_PINID='B';
NODE_NAME     C1833 2
 '@T6G_MB_LIB.T6G(SCH_1):PAGE341_I17@PURE_QUANTA.Q_CAP(CHIPS)':
 'B': CDS_PINID='B';
NODE_NAME     C1839 2
 '@T6G_MB_LIB.T6G(SCH_1):PAGE341_I18@PURE_QUANTA.Q_CAP(CHIPS)':
 'B': CDS_PINID='B';
NODE_NAME     C1835 2
 '@T6G_MB_LIB.T6G(SCH_1):PAGE341_I21@PURE_QUANTA.Q_CAP(CHIPS)':
 'B': CDS_PINID='B';
NODE_NAME     C1836 2
 '@T6G_MB_LIB.T6G(SCH_1):PAGE341_I22@PURE_QUANTA.Q_CAP(CHIPS)':
 'B': CDS_PINID='B';
NODE_NAME     C1838 2
 '@T6G_MB_LIB.T6G(SCH_1):PAGE341_I24@PURE_QUANTA.Q_CAP(CHIPS)':
 'B': CDS_PINID='B';
NODE_NAME     R3164 1
 '@T6G_MB_LIB.T6G(SCH_1):PAGE341_I34@PURE_QUANTA.Q_RES(CHIPS)':
 'A': CDS_PINID='A';
NODE_NAME     R3180 2
 '@T6G_MB_LIB.T6G(SCH_1):PAGE341_I150@PURE_QUANTA.Q_RES(CHIPS)':
 'B': CDS_PINID='B';
NODE_NAME     R3268 2
 '@T6G_MB_LIB.T6G(SCH_1):PAGE110_I2@PURE_QUANTA.Q_RES(CHIPS)':
 'B': CDS_PINID='B';
NODE_NAME     R3272 2
 '@T6G_MB_LIB.T6G(SCH_1):PAGE110_I4@PURE_QUANTA.Q_RES(CHIPS)':
 'B': CDS_PINID='B';
NODE_NAME     R3267 2
 '@T6G_MB_LIB.T6G(SCH_1):PAGE110_I8@PURE_QUANTA.Q_RES(CHIPS)':
 'B': CDS_PINID='B';
NODE_NAME     R3270 2
 '@T6G_MB_LIB.T6G(SCH_1):PAGE110_I9@PURE_QUANTA.Q_RES(CHIPS)':
 'B': CDS_PINID='B';
NODE_NAME     R3273 2
 '@T6G_MB_LIB.T6G(SCH_1):PAGE110_I12@PURE_QUANTA.Q_RES(CHIPS)':
 'B': CDS_PINID='B';
NODE_NAME     R3274 2
 '@T6G_MB_LIB.T6G(SCH_1):PAGE110_I16@PURE_QUANTA.Q_RES(CHIPS)':
 'B': CDS_PINID='B';
NODE_NAME     R3278 2
 '@T6G_MB_LIB.T6G(SCH_1):PAGE110_I18@PURE_QUANTA.Q_RES(CHIPS)':
 'B': CDS_PINID='B';
NODE_NAME     R3279 2
 '@T6G_MB_LIB.T6G(SCH_1):PAGE110_I22@PURE_QUANTA.Q_RES(CHIPS)':
 'B': CDS_PINID='B';
NODE_NAME     R3281 2
 '@T6G_MB_LIB.T6G(SCH_1):PAGE110_I25@PURE_QUANTA.Q_RES(CHIPS)':
 'B': CDS_PINID='B';
NODE_NAME     R3276 2
 '@T6G_MB_LIB.T6G(SCH_1):PAGE110_I29@PURE_QUANTA.Q_RES(CHIPS)':
 'B': CDS_PINID='B';
NODE_NAME     R3282 2
 '@T6G_MB_LIB.T6G(SCH_1):PAGE110_I34@PURE_QUANTA.Q_RES(CHIPS)':
 'B': CDS_PINID='B';
NODE_NAME     R3284 2
 '@T6G_MB_LIB.T6G(SCH_1):PAGE110_I36@PURE_QUANTA.Q_RES(CHIPS)':
 'B': CDS_PINID='B';
NODE_NAME     R3285 2
 '@T6G_MB_LIB.T6G(SCH_1):PAGE110_I42@PURE_QUANTA.Q_RES(CHIPS)':
 'B': CDS_PINID='B';
NODE_NAME     R3287 2
 '@T6G_MB_LIB.T6G(SCH_1):PAGE110_I44@PURE_QUANTA.Q_RES(CHIPS)':
 'B': CDS_PINID='B';
NODE_NAME     C1867 2
 '@T6G_MB_LIB.T6G(SCH_1):PAGE110_I60@PURE_QUANTA.Q_CAP(CHIPS)':
 'B': CDS_PINID='B';
NODE_NAME     C1863 2
 '@T6G_MB_LIB.T6G(SCH_1):PAGE110_I61@PURE_QUANTA.Q_CAP(CHIPS)':
 'B': CDS_PINID='B';
NODE_NAME     C1864 2
 '@T6G_MB_LIB.T6G(SCH_1):PAGE110_I62@PURE_QUANTA.Q_CAP(CHIPS)':
 'B': CDS_PINID='B';
NODE_NAME     U237 4
 '@T6G_MB_LIB.T6G(SCH_1):PAGE110_I63@PURE_QUANTA.PI3EQX12902AZLEX(CHIPS)':
 'GND1': CDS_PINID='GND1';
NODE_NAME     U237 6
 '@T6G_MB_LIB.T6G(SCH_1):PAGE110_I63@PURE_QUANTA.PI3EQX12902AZLEX(CHIPS)':
 'GND2': CDS_PINID='GND2';
NODE_NAME     U237 7
 '@T6G_MB_LIB.T6G(SCH_1):PAGE110_I63@PURE_QUANTA.PI3EQX12902AZLEX(CHIPS)':
 'GND3': CDS_PINID='GND3';
NODE_NAME     U237 13
 '@T6G_MB_LIB.T6G(SCH_1):PAGE110_I63@PURE_QUANTA.PI3EQX12902AZLEX(CHIPS)':
 'GND4': CDS_PINID='GND4';
NODE_NAME     U237 19
 '@T6G_MB_LIB.T6G(SCH_1):PAGE110_I63@PURE_QUANTA.PI3EQX12902AZLEX(CHIPS)':
 'GND5': CDS_PINID='GND5';
NODE_NAME     U237 22
 '@T6G_MB_LIB.T6G(SCH_1):PAGE110_I63@PURE_QUANTA.PI3EQX12902AZLEX(CHIPS)':
 'GND6': CDS_PINID='GND6';
NODE_NAME     U237 28
 '@T6G_MB_LIB.T6G(SCH_1):PAGE110_I63@PURE_QUANTA.PI3EQX12902AZLEX(CHIPS)':
 'GND7': CDS_PINID='GND7';
NODE_NAME     U237 TH
 '@T6G_MB_LIB.T6G(SCH_1):PAGE110_I63@PURE_QUANTA.PI3EQX12902AZLEX(CHIPS)':
 'GND_TH': CDS_PINID='GND_TH';
NODE_NAME     C1865 2
 '@T6G_MB_LIB.T6G(SCH_1):PAGE110_I64@PURE_QUANTA.Q_CAP(CHIPS)':
 'B': CDS_PINID='B';
NODE_NAME     C1866 2
 '@T6G_MB_LIB.T6G(SCH_1):PAGE110_I65@PURE_QUANTA.Q_CAP(CHIPS)':
 'B': CDS_PINID='B';
NODE_NAME     R3288 2
 '@T6G_MB_LIB.T6G(SCH_1):PAGE110_I74@PURE_QUANTA.Q_RES(CHIPS)':
 'B': CDS_PINID='B';
NODE_NAME     R3290 2
 '@T6G_MB_LIB.T6G(SCH_1):PAGE110_I76@PURE_QUANTA.Q_RES(CHIPS)':
 'B': CDS_PINID='B';
NODE_NAME     R3265 2
 '@T6G_MB_LIB.T6G(SCH_1):PAGE110_I81@PURE_QUANTA.Q_RES(CHIPS)':
 'B': CDS_PINID='B';
NODE_NAME     R3291 2
 '@T6G_MB_LIB.T6G(SCH_1):PAGE110_I88@PURE_QUANTA.Q_RES(CHIPS)':
 'B': CDS_PINID='B';
NODE_NAME     R3293 2
 '@T6G_MB_LIB.T6G(SCH_1):PAGE110_I92@PURE_QUANTA.Q_RES(CHIPS)':
 'B': CDS_PINID='B';
NODE_NAME     R1930 1
 '@T6G_MB_LIB.T6G(SCH_1):PAGE335_I7@PURE_QUANTA.Q_RES(CHIPS)':
 'A': CDS_PINID='A';
NODE_NAME     R1929 1
 '@T6G_MB_LIB.T6G(SCH_1):PAGE335_I8@PURE_QUANTA.Q_RES(CHIPS)':
 'A': CDS_PINID='A';
NODE_NAME     R34 2
 '@T6G_MB_LIB.T6G(SCH_1):PAGE335_I12@PURE_QUANTA.Q_RES(CHIPS)':
 'B': CDS_PINID='B';
NODE_NAME     R8422 2
 '@T6G_MB_LIB.T6G(SCH_1):PAGE335_I19@PURE_QUANTA.Q_RES(CHIPS)':
 'B': CDS_PINID='B';
NODE_NAME     C1213 2
 '@T6G_MB_LIB.T6G(SCH_1):PAGE335_I87@PURE_QUANTA.Q_CAP(CHIPS)':
 'B': CDS_PINID='B';
NODE_NAME     C34 2
 '@T6G_MB_LIB.T6G(SCH_1):PAGE335_I88@PURE_QUANTA.Q_CAP(CHIPS)':
 'B': CDS_PINID='B';
NODE_NAME     C1239 2
 '@T6G_MB_LIB.T6G(SCH_1):PAGE335_I112@PURE_QUANTA.Q_CAP(CHIPS)':
 'B': CDS_PINID='B';
NODE_NAME     C27 2
 '@T6G_MB_LIB.T6G(SCH_1):PAGE335_I163@PURE_QUANTA.Q_CAP(CHIPS)':
 'B': CDS_PINID='B';
NODE_NAME     C1236 2
 '@T6G_MB_LIB.T6G(SCH_1):PAGE335_I164@PURE_QUANTA.Q_CAP(CHIPS)':
 'B': CDS_PINID='B';
NODE_NAME     Q144 1
 '@T6G_MB_LIB.T6G(SCH_1):PAGE368_I3@PURE_QUANTA.MOSFET_NCH_DUAL(CHIPS)':
 'S1': CDS_PINID='S1';
NODE_NAME     Q144 4
 '@T6G_MB_LIB.T6G(SCH_1):PAGE368_I10@PURE_QUANTA.MOSFET_NCH_DUAL(CHIPS)':
 'S2': CDS_PINID='S2';
NODE_NAME     D99 C
 '@T6G_MB_LIB.T6G(SCH_1):PAGE254_I3@PURE_QUANTA.Q_LED(CHIPS)':
 'C': CDS_PINID='C';
NODE_NAME     D98 C
 '@T6G_MB_LIB.T6G(SCH_1):PAGE254_I17@PURE_QUANTA.Q_LED(CHIPS)':
 'C': CDS_PINID='C';
NODE_NAME     Q78 4
 '@T6G_MB_LIB.T6G(SCH_1):PAGE254_I18@PURE_QUANTA.MOSFET_NCH_DUAL(CHIPS)':
 'S2': CDS_PINID='S2';
NODE_NAME     C1134 2
 '@T6G_MB_LIB.T6G(SCH_1):PAGE82_I79@PURE_QUANTA.Q_CAP(CHIPS)':
 'B': CDS_PINID='B';
NODE_NAME     C1132 2
 '@T6G_MB_LIB.T6G(SCH_1):PAGE82_I80@PURE_QUANTA.Q_CAP(CHIPS)':
 'B': CDS_PINID='B';
NODE_NAME     C1131 2
 '@T6G_MB_LIB.T6G(SCH_1):PAGE82_I82@PURE_QUANTA.Q_CAP(CHIPS)':
 'B': CDS_PINID='B';
NODE_NAME     C352 2
 '@T6G_MB_LIB.T6G(SCH_1):PAGE82_I83@PURE_QUANTA.Q_CAP(CHIPS)':
 'B': CDS_PINID='B';
NODE_NAME     C1128 2
 '@T6G_MB_LIB.T6G(SCH_1):PAGE82_I84@PURE_QUANTA.Q_CAP(CHIPS)':
 'B': CDS_PINID='B';
NODE_NAME     C1129 2
 '@T6G_MB_LIB.T6G(SCH_1):PAGE82_I85@PURE_QUANTA.Q_CAP(CHIPS)':
 'B': CDS_PINID='B';
NODE_NAME     C1126 2
 '@T6G_MB_LIB.T6G(SCH_1):PAGE82_I86@PURE_QUANTA.Q_CAP(CHIPS)':
 'B': CDS_PINID='B';
NODE_NAME     C1127 2
 '@T6G_MB_LIB.T6G(SCH_1):PAGE82_I87@PURE_QUANTA.Q_CAP(CHIPS)':
 'B': CDS_PINID='B';
NODE_NAME     R25 2
 '@T6G_MB_LIB.T6G(SCH_1):PAGE82_I97@PURE_QUANTA.Q_RES(CHIPS)':
 'B': CDS_PINID='B';
NODE_NAME     C358 2
 '@T6G_MB_LIB.T6G(SCH_1):PAGE82_I105@PURE_QUANTA.Q_CAP(CHIPS)':
 'B': CDS_PINID='B';
NODE_NAME     C357 2
 '@T6G_MB_LIB.T6G(SCH_1):PAGE82_I106@PURE_QUANTA.Q_CAP(CHIPS)':
 'B': CDS_PINID='B';
NODE_NAME     C356 2
 '@T6G_MB_LIB.T6G(SCH_1):PAGE82_I107@PURE_QUANTA.Q_CAP(CHIPS)':
 'B': CDS_PINID='B';
NODE_NAME     C355 2
 '@T6G_MB_LIB.T6G(SCH_1):PAGE82_I108@PURE_QUANTA.Q_CAP(CHIPS)':
 'B': CDS_PINID='B';
NODE_NAME     C1176 2
 '@T6G_MB_LIB.T6G(SCH_1):PAGE82_I109@PURE_QUANTA.Q_CAP(CHIPS)':
 'B': CDS_PINID='B';
NODE_NAME     C1175 2
 '@T6G_MB_LIB.T6G(SCH_1):PAGE82_I110@PURE_QUANTA.Q_CAP(CHIPS)':
 'B': CDS_PINID='B';
NODE_NAME     C1174 2
 '@T6G_MB_LIB.T6G(SCH_1):PAGE82_I111@PURE_QUANTA.Q_CAP(CHIPS)':
 'B': CDS_PINID='B';
NODE_NAME     C1172 2
 '@T6G_MB_LIB.T6G(SCH_1):PAGE82_I112@PURE_QUANTA.Q_CAP(CHIPS)':
 'B': CDS_PINID='B';
NODE_NAME     C1173 2
 '@T6G_MB_LIB.T6G(SCH_1):PAGE82_I113@PURE_QUANTA.Q_CAP(CHIPS)':
 'B': CDS_PINID='B';
NODE_NAME     C1171 2
 '@T6G_MB_LIB.T6G(SCH_1):PAGE82_I114@PURE_QUANTA.Q_CAP(CHIPS)':
 'B': CDS_PINID='B';
NODE_NAME     R804 2
 '@T6G_MB_LIB.T6G(SCH_1):PAGE82_I120@PURE_QUANTA.Q_RES(CHIPS)':
 'B': CDS_PINID='B';
NODE_NAME     R18 2
 '@T6G_MB_LIB.T6G(SCH_1):PAGE82_I126@PURE_QUANTA.Q_RES(CHIPS)':
 'B': CDS_PINID='B';
NODE_NAME     R19 2
 '@T6G_MB_LIB.T6G(SCH_1):PAGE82_I128@PURE_QUANTA.Q_RES(CHIPS)':
 'B': CDS_PINID='B';
NODE_NAME     Q123 1
 '@T6G_MB_LIB.T6G(SCH_1):PAGE338_I11@PURE_QUANTA.MOSFET_NCH_DUAL(CHIPS)':
 'S1': CDS_PINID='S1';
NODE_NAME     Q123 4
 '@T6G_MB_LIB.T6G(SCH_1):PAGE338_I19@PURE_QUANTA.MOSFET_NCH_DUAL(CHIPS)':
 'S2': CDS_PINID='S2';
NODE_NAME     Q124 1
 '@T6G_MB_LIB.T6G(SCH_1):PAGE338_I23@PURE_QUANTA.MOSFET_NCH_DUAL(CHIPS)':
 'S1': CDS_PINID='S1';
NODE_NAME     U8 2
 '@T6G_MB_LIB.T6G(SCH_1):PAGE338_I26@PURE_QUANTA.74LVC2G07DW7(CHIPS)':
 'GND': CDS_PINID='GND';
NODE_NAME     U211 2
 '@T6G_MB_LIB.T6G(SCH_1):PAGE338_I29@PURE_QUANTA.74LVC2G07DW7(CHIPS)':
 'GND': CDS_PINID='GND';
NODE_NAME     C593 2
 '@T6G_MB_LIB.T6G(SCH_1):PAGE338_I30@PURE_QUANTA.Q_CAP(CHIPS)':
 'B': CDS_PINID='B';
NODE_NAME     C592 2
 '@T6G_MB_LIB.T6G(SCH_1):PAGE338_I33@PURE_QUANTA.Q_CAP(CHIPS)':
 'B': CDS_PINID='B';
NODE_NAME     PR3788 2
 '@T6G_MB_LIB.T6G(SCH_1):PAGE338_I36@PURE_QUANTA.Q_RES(CHIPS)':
 'B': CDS_PINID='B';
NODE_NAME     PC2079 2
 '@T6G_MB_LIB.T6G(SCH_1):PAGE338_I45@PURE_QUANTA.Q_CAP(CHIPS)':
 'B': CDS_PINID='B';
NODE_NAME     PR5484 2
 '@T6G_MB_LIB.T6G(SCH_1):PAGE338_I48@PURE_QUANTA.Q_RES(CHIPS)':
 'B': CDS_PINID='B';
NODE_NAME     PU203 A7
 '@T6G_MB_LIB.T6G(SCH_1):PAGE338_I50@PURE_QUANTA.MAX15090BEWIT(CHIPS)':
 'CDLY': CDS_PINID='CDLY';
NODE_NAME     PU203 B7
 '@T6G_MB_LIB.T6G(SCH_1):PAGE338_I50@PURE_QUANTA.MAX15090BEWIT(CHIPS)':
 'EN#': CDS_PINID='\en#\';
NODE_NAME     PU203 B2
 '@T6G_MB_LIB.T6G(SCH_1):PAGE338_I50@PURE_QUANTA.MAX15090BEWIT(CHIPS)':
 'GND_B2': CDS_PINID='GND_B2';
NODE_NAME     PU203 C1
 '@T6G_MB_LIB.T6G(SCH_1):PAGE338_I50@PURE_QUANTA.MAX15090BEWIT(CHIPS)':
 'GND_C1': CDS_PINID='GND_C1';
NODE_NAME     PU203 C2
 '@T6G_MB_LIB.T6G(SCH_1):PAGE338_I50@PURE_QUANTA.MAX15090BEWIT(CHIPS)':
 'GND_C2': CDS_PINID='GND_C2';
NODE_NAME     PC2087 1
 '@T6G_MB_LIB.T6G(SCH_1):PAGE338_I54@PURE_QUANTA.Q_CAP(CHIPS)':
 'A': CDS_PINID='A';
NODE_NAME     PC2085 2
 '@T6G_MB_LIB.T6G(SCH_1):PAGE338_I55@PURE_QUANTA.Q_CAP(CHIPS)':
 'B': CDS_PINID='B';
NODE_NAME     PC5328 2
 '@T6G_MB_LIB.T6G(SCH_1):PAGE338_I62@PURE_QUANTA.Q_CAP(CHIPS)':
 'B': CDS_PINID='B';
NODE_NAME     PC2093 1
 '@T6G_MB_LIB.T6G(SCH_1):PAGE338_I67@PURE_QUANTA.Q_CAP(CHIPS)':
 'A': CDS_PINID='A';
NODE_NAME     PR3781 2
 '@T6G_MB_LIB.T6G(SCH_1):PAGE338_I73@PURE_QUANTA.Q_RES(CHIPS)':
 'B': CDS_PINID='B';
NODE_NAME     PC4056 2
 '@T6G_MB_LIB.T6G(SCH_1):PAGE338_I77@PURE_QUANTA.Q_CAP(CHIPS)':
 'B': CDS_PINID='B';
NODE_NAME     PD102 A
 '@T6G_MB_LIB.T6G(SCH_1):PAGE338_I79@PURE_QUANTA.SCHOTTKY_AC(CHIPS)':
 'A': CDS_PINID='A';
NODE_NAME     PC2092 2
 '@T6G_MB_LIB.T6G(SCH_1):PAGE338_I86@PURE_QUANTA.Q_CAP(CHIPS)':
 'B': CDS_PINID='B';
NODE_NAME     PC2080 2
 '@T6G_MB_LIB.T6G(SCH_1):PAGE338_I87@PURE_QUANTA.Q_CAP(CHIPS)':
 'B': CDS_PINID='B';
NODE_NAME     PC2082 2
 '@T6G_MB_LIB.T6G(SCH_1):PAGE338_I89@PURE_QUANTA.Q_CAP(CHIPS)':
 'B': CDS_PINID='B';
NODE_NAME     PR5481 2
 '@T6G_MB_LIB.T6G(SCH_1):PAGE338_I95@PURE_QUANTA.Q_RES(CHIPS)':
 'B': CDS_PINID='B';
NODE_NAME     PD103 A
 '@T6G_MB_LIB.T6G(SCH_1):PAGE338_I97@PURE_QUANTA.SCHOTTKY_AC(CHIPS)':
 'A': CDS_PINID='A';
NODE_NAME     PC2089 2
 '@T6G_MB_LIB.T6G(SCH_1):PAGE338_I100@PURE_QUANTA.Q_CAP(CHIPS)':
 'B': CDS_PINID='B';
NODE_NAME     PC2091 2
 '@T6G_MB_LIB.T6G(SCH_1):PAGE338_I104@PURE_QUANTA.Q_CAP(CHIPS)':
 'B': CDS_PINID='B';
NODE_NAME     PC2081 2
 '@T6G_MB_LIB.T6G(SCH_1):PAGE338_I106@PURE_QUANTA.Q_CAP(CHIPS)':
 'B': CDS_PINID='B';
NODE_NAME     PC2086 2
 '@T6G_MB_LIB.T6G(SCH_1):PAGE338_I110@PURE_QUANTA.Q_CAP(CHIPS)':
 'B': CDS_PINID='B';
NODE_NAME     PR3780 2
 '@T6G_MB_LIB.T6G(SCH_1):PAGE338_I111@PURE_QUANTA.Q_RES(CHIPS)':
 'B': CDS_PINID='B';
NODE_NAME     Q124 4
 '@T6G_MB_LIB.T6G(SCH_1):PAGE338_I112@PURE_QUANTA.MOSFET_NCH_DUAL(CHIPS)':
 'S2': CDS_PINID='S2';
NODE_NAME     PU202 A7
 '@T6G_MB_LIB.T6G(SCH_1):PAGE338_I113@PURE_QUANTA.MAX15090BEWIT(CHIPS)':
 'CDLY': CDS_PINID='CDLY';
NODE_NAME     PU202 B7
 '@T6G_MB_LIB.T6G(SCH_1):PAGE338_I113@PURE_QUANTA.MAX15090BEWIT(CHIPS)':
 'EN#': CDS_PINID='\en#\';
NODE_NAME     PU202 B2
 '@T6G_MB_LIB.T6G(SCH_1):PAGE338_I113@PURE_QUANTA.MAX15090BEWIT(CHIPS)':
 'GND_B2': CDS_PINID='GND_B2';
NODE_NAME     PU202 C1
 '@T6G_MB_LIB.T6G(SCH_1):PAGE338_I113@PURE_QUANTA.MAX15090BEWIT(CHIPS)':
 'GND_C1': CDS_PINID='GND_C1';
NODE_NAME     PU202 C2
 '@T6G_MB_LIB.T6G(SCH_1):PAGE338_I113@PURE_QUANTA.MAX15090BEWIT(CHIPS)':
 'GND_C2': CDS_PINID='GND_C2';
NODE_NAME     PR3791 2
 '@T6G_MB_LIB.T6G(SCH_1):PAGE338_I114@PURE_QUANTA.Q_RES(CHIPS)':
 'B': CDS_PINID='B';
NODE_NAME     PD101 A
 '@T6G_MB_LIB.T6G(SCH_1):PAGE338_I115@PURE_QUANTA.DIODE_TVS(CHIPS)':
 'A': CDS_PINID='A';
NODE_NAME     R999 2
 '@T6G_MB_LIB.T6G(SCH_1):PAGE297_I95@PURE_QUANTA.Q_RES(CHIPS)':
 'B': CDS_PINID='B';
NODE_NAME     U44 3
 '@T6G_MB_LIB.T6G(SCH_1):PAGE297_I97@PURE_QUANTA.74LVC1G17GW(CHIPS)':
 'GND': CDS_PINID='GND';
NODE_NAME     C508 2
 '@T6G_MB_LIB.T6G(SCH_1):PAGE297_I99@PURE_QUANTA.Q_CAP(CHIPS)':
 'B': CDS_PINID='B';
NODE_NAME     R1000 2
 '@T6G_MB_LIB.T6G(SCH_1):PAGE297_I102@PURE_QUANTA.Q_RES(CHIPS)':
 'B': CDS_PINID='B';
NODE_NAME     C552 2
 '@T6G_MB_LIB.T6G(SCH_1):PAGE83_I24@PURE_QUANTA.Q_CAP(CHIPS)':
 'B': CDS_PINID='B';
NODE_NAME     U92 3
 '@T6G_MB_LIB.T6G(SCH_1):PAGE83_I26@PURE_QUANTA.SN74LVC1G07DBVR(CHIPS)':
 'GND': CDS_PINID='GND';
NODE_NAME     R6145 2
 '@T6G_MB_LIB.T6G(SCH_1):PAGE83_I54@PURE_QUANTA.Q_RES(CHIPS)':
 'B': CDS_PINID='B';
NODE_NAME     R1508 1
 '@T6G_MB_LIB.T6G(SCH_1):PAGE144_I6@PURE_QUANTA.Q_RES(CHIPS)':
 'A': CDS_PINID='A';
NODE_NAME     R6044 2
 '@T6G_MB_LIB.T6G(SCH_1):PAGE144_I33@PURE_QUANTA.Q_RES(CHIPS)':
 'B': CDS_PINID='B';
NODE_NAME     R8 1
 '@T6G_MB_LIB.T6G(SCH_1):PAGE144_I47@PURE_QUANTA.Q_RES(CHIPS)':
 'A': CDS_PINID='A';
NODE_NAME     R1265 2
 '@T6G_MB_LIB.T6G(SCH_1):PAGE144_I52@PURE_QUANTA.Q_RES(CHIPS)':
 'B': CDS_PINID='B';
NODE_NAME     R6043 1
 '@T6G_MB_LIB.T6G(SCH_1):PAGE144_I61@PURE_QUANTA.Q_RES(CHIPS)':
 'A': CDS_PINID='A';
NODE_NAME     R6041 1
 '@T6G_MB_LIB.T6G(SCH_1):PAGE144_I69@PURE_QUANTA.Q_RES(CHIPS)':
 'A': CDS_PINID='A';
NODE_NAME     Q126 4
 '@T6G_MB_LIB.T6G(SCH_1):PAGE324_I7@PURE_QUANTA.MOSFET_NCH_DUAL(CHIPS)':
 'S2': CDS_PINID='S2';
NODE_NAME     Q127 1
 '@T6G_MB_LIB.T6G(SCH_1):PAGE324_I12@PURE_QUANTA.MOSFET_NCH_DUAL(CHIPS)':
 'S1': CDS_PINID='S1';
NODE_NAME     PC2212 1
 '@T6G_MB_LIB.T6G(SCH_1):PAGE324_I42@PURE_QUANTA.Q_CAP(CHIPS)':
 'A': CDS_PINID='A';
NODE_NAME     PC2216 2
 '@T6G_MB_LIB.T6G(SCH_1):PAGE324_I49@PURE_QUANTA.Q_CAP(CHIPS)':
 'B': CDS_PINID='B';
NODE_NAME     PC2218 2
 '@T6G_MB_LIB.T6G(SCH_1):PAGE324_I57@PURE_QUANTA.Q_CAP(CHIPS)':
 'B': CDS_PINID='B';
NODE_NAME     PC2209 2
 '@T6G_MB_LIB.T6G(SCH_1):PAGE324_I64@PURE_QUANTA.Q_CAP(CHIPS)':
 'B': CDS_PINID='B';
NODE_NAME     PC2219 2
 '@T6G_MB_LIB.T6G(SCH_1):PAGE324_I79@PURE_QUANTA.Q_CAP(CHIPS)':
 'B': CDS_PINID='B';
NODE_NAME     PU295 A7
 '@T6G_MB_LIB.T6G(SCH_1):PAGE324_I88@PURE_QUANTA.MAX15090BEWIT(CHIPS)':
 'CDLY': CDS_PINID='CDLY';
NODE_NAME     PU295 B7
 '@T6G_MB_LIB.T6G(SCH_1):PAGE324_I88@PURE_QUANTA.MAX15090BEWIT(CHIPS)':
 'EN#': CDS_PINID='\en#\';
NODE_NAME     PU295 B2
 '@T6G_MB_LIB.T6G(SCH_1):PAGE324_I88@PURE_QUANTA.MAX15090BEWIT(CHIPS)':
 'GND_B2': CDS_PINID='GND_B2';
NODE_NAME     PU295 C1
 '@T6G_MB_LIB.T6G(SCH_1):PAGE324_I88@PURE_QUANTA.MAX15090BEWIT(CHIPS)':
 'GND_C1': CDS_PINID='GND_C1';
NODE_NAME     PU295 C2
 '@T6G_MB_LIB.T6G(SCH_1):PAGE324_I88@PURE_QUANTA.MAX15090BEWIT(CHIPS)':
 'GND_C2': CDS_PINID='GND_C2';
NODE_NAME     PC2153 2
 '@T6G_MB_LIB.T6G(SCH_1):PAGE339_I60@PURE_QUANTA.Q_CAP(CHIPS)':
 'B': CDS_PINID='B';
NODE_NAME     PR3835 2
 '@T6G_MB_LIB.T6G(SCH_1):PAGE339_I63@PURE_QUANTA.Q_RES(CHIPS)':
 'B': CDS_PINID='B';
NODE_NAME     PC2155 2
 '@T6G_MB_LIB.T6G(SCH_1):PAGE339_I64@PURE_QUANTA.Q_CAP(CHIPS)':
 'B': CDS_PINID='B';
NODE_NAME     PC2154 2
 '@T6G_MB_LIB.T6G(SCH_1):PAGE339_I68@PURE_QUANTA.Q_CAP(CHIPS)':
 'B': CDS_PINID='B';
NODE_NAME     PR3837 2
 '@T6G_MB_LIB.T6G(SCH_1):PAGE339_I71@PURE_QUANTA.Q_RES(CHIPS)':
 'B': CDS_PINID='B';
NODE_NAME     PC2156 2
 '@T6G_MB_LIB.T6G(SCH_1):PAGE339_I73@PURE_QUANTA.Q_CAP(CHIPS)':
 'B': CDS_PINID='B';
NODE_NAME     PR3842 2
 '@T6G_MB_LIB.T6G(SCH_1):PAGE339_I80@PURE_QUANTA.Q_RES(CHIPS)':
 'B': CDS_PINID='B';
NODE_NAME     PC2158 2
 '@T6G_MB_LIB.T6G(SCH_1):PAGE339_I86@PURE_QUANTA.Q_CAP(CHIPS)':
 'B': CDS_PINID='B';
NODE_NAME     PC2160 2
 '@T6G_MB_LIB.T6G(SCH_1):PAGE339_I91@PURE_QUANTA.Q_CAP(CHIPS)':
 'B': CDS_PINID='B';
NODE_NAME     PC2157 2
 '@T6G_MB_LIB.T6G(SCH_1):PAGE339_I98@PURE_QUANTA.Q_CAP(CHIPS)':
 'B': CDS_PINID='B';
NODE_NAME     PR3844 2
 '@T6G_MB_LIB.T6G(SCH_1):PAGE339_I100@PURE_QUANTA.Q_RES(CHIPS)':
 'B': CDS_PINID='B';
NODE_NAME     PR3846 1
 '@T6G_MB_LIB.T6G(SCH_1):PAGE339_I102@PURE_QUANTA.Q_RES(CHIPS)':
 'A': CDS_PINID='A';
NODE_NAME     PC2161 2
 '@T6G_MB_LIB.T6G(SCH_1):PAGE339_I104@PURE_QUANTA.Q_CAP(CHIPS)':
 'B': CDS_PINID='B';
NODE_NAME     PC2162 2
 '@T6G_MB_LIB.T6G(SCH_1):PAGE339_I106@PURE_QUANTA.Q_CAP(CHIPS)':
 'B': CDS_PINID='B';
NODE_NAME     PC2163 2
 '@T6G_MB_LIB.T6G(SCH_1):PAGE339_I108@PURE_QUANTA.Q_CAP(CHIPS)':
 'B': CDS_PINID='B';
NODE_NAME     PC2159 2
 '@T6G_MB_LIB.T6G(SCH_1):PAGE339_I111@PURE_QUANTA.Q_CAP(CHIPS)':
 'B': CDS_PINID='B';
NODE_NAME     PU205 3
 '@T6G_MB_LIB.T6G(SCH_1):PAGE339_I113@PURE_QUANTA.MP5016GQHLZ(CHIPS)':
 'GND': CDS_PINID='GND';
NODE_NAME     R334 2
 '@T6G_MB_LIB.T6G(SCH_1):PAGE273_I7@PURE_QUANTA.Q_RES(CHIPS)':
 'B': CDS_PINID='B';
NODE_NAME     C1042 2
 '@T6G_MB_LIB.T6G(SCH_1):PAGE273_I18@PURE_QUANTA.Q_CAP(CHIPS)':
 'B': CDS_PINID='B';
NODE_NAME     C1170 2
 '@T6G_MB_LIB.T6G(SCH_1):PAGE273_I19@PURE_QUANTA.Q_CAP(CHIPS)':
 'B': CDS_PINID='B';
NODE_NAME     C57 2
 '@T6G_MB_LIB.T6G(SCH_1):PAGE273_I20@PURE_QUANTA.Q_CAP(CHIPS)':
 'B': CDS_PINID='B';
NODE_NAME     C9226 2
 '@T6G_MB_LIB.T6G(SCH_1):PAGE273_I38@PURE_QUANTA.Q_CAP(CHIPS)':
 'B': CDS_PINID='B';
NODE_NAME     C1331 2
 '@T6G_MB_LIB.T6G(SCH_1):PAGE273_I43@PURE_QUANTA.Q_CAP(CHIPS)':
 'B': CDS_PINID='B';
NODE_NAME     C61 2
 '@T6G_MB_LIB.T6G(SCH_1):PAGE273_I59@PURE_QUANTA.Q_CAP(CHIPS)':
 'B': CDS_PINID='B';
NODE_NAME     U324 S
 '@T6G_MB_LIB.T6G(SCH_1):PAGE273_I62@PURE_QUANTA.MOSFET_NCH_GDS_ESD_PROTECTED(CHIPS)':
 'S': CDS_PINID='S';
NODE_NAME     J57 7
 '@T6G_MB_LIB.T6G(SCH_1):PAGE84_I41@PURE_QUANTA.CONN8_HBB1081L200D8H(CHIPS)':
 '7': CDS_PINID='\7\';
NODE_NAME     C20 2
 '@T6G_MB_LIB.T6G(SCH_1):PAGE84_I42@PURE_QUANTA.Q_CAP(CHIPS)':
 'B': CDS_PINID='B';
NODE_NAME     R5032 1
 '@T6G_MB_LIB.T6G(SCH_1):PAGE55_I330@PURE_QUANTA.Q_RES(CHIPS)':
 'A': CDS_PINID='A';
NODE_NAME     R5031 1
 '@T6G_MB_LIB.T6G(SCH_1):PAGE55_I331@PURE_QUANTA.Q_RES(CHIPS)':
 'A': CDS_PINID='A';
NODE_NAME     R5030 1
 '@T6G_MB_LIB.T6G(SCH_1):PAGE55_I334@PURE_QUANTA.Q_RES(CHIPS)':
 'A': CDS_PINID='A';
NODE_NAME     R491 1
 '@T6G_MB_LIB.T6G(SCH_1):PAGE55_I335@PURE_QUANTA.Q_RES(CHIPS)':
 'A': CDS_PINID='A';
NODE_NAME     R584 1
 '@T6G_MB_LIB.T6G(SCH_1):PAGE55_I341@PURE_QUANTA.Q_RES(CHIPS)':
 'A': CDS_PINID='A';
NODE_NAME     PC1648 2
 '@T6G_MB_LIB.T6G(SCH_1):PAGE244_I2@PURE_QUANTA.Q_CAP(CHIPS)':
 'B': CDS_PINID='B';
NODE_NAME     PC1849 2
 '@T6G_MB_LIB.T6G(SCH_1):PAGE244_I7@PURE_QUANTA.Q_CAP(CHIPS)':
 'B': CDS_PINID='B';
NODE_NAME     PC1848 2
 '@T6G_MB_LIB.T6G(SCH_1):PAGE244_I8@PURE_QUANTA.Q_CAP(CHIPS)':
 'B': CDS_PINID='B';
NODE_NAME     PC1850 2
 '@T6G_MB_LIB.T6G(SCH_1):PAGE244_I10@PURE_QUANTA.Q_CAP(CHIPS)':
 'B': CDS_PINID='B';
NODE_NAME     PC1898 2
 '@T6G_MB_LIB.T6G(SCH_1):PAGE244_I11@PURE_QUANTA.Q_CAP(CHIPS)':
 'B': CDS_PINID='B';
NODE_NAME     PC1846 2
 '@T6G_MB_LIB.T6G(SCH_1):PAGE244_I13@PURE_QUANTA.Q_CAP(CHIPS)':
 'B': CDS_PINID='B';
NODE_NAME     PR8089 2
 '@T6G_MB_LIB.T6G(SCH_1):PAGE244_I15@PURE_QUANTA.Q_RES(CHIPS)':
 'B': CDS_PINID='B';
NODE_NAME     PC1853 2
 '@T6G_MB_LIB.T6G(SCH_1):PAGE244_I19@PURE_QUANTA.Q_CAP(CHIPS)':
 'B': CDS_PINID='B';
NODE_NAME     PR8091 2
 '@T6G_MB_LIB.T6G(SCH_1):PAGE244_I23@PURE_QUANTA.Q_RES(CHIPS)':
 'B': CDS_PINID='B';
NODE_NAME     PC1845 2
 '@T6G_MB_LIB.T6G(SCH_1):PAGE244_I30@PURE_QUANTA.Q_CAPP(CHIPS)':
 'B': CDS_PINID='B';
NODE_NAME     PC1855 2
 '@T6G_MB_LIB.T6G(SCH_1):PAGE244_I31@PURE_QUANTA.Q_CAP(CHIPS)':
 'B': CDS_PINID='B';
NODE_NAME     PC1856 2
 '@T6G_MB_LIB.T6G(SCH_1):PAGE244_I32@PURE_QUANTA.Q_CAP(CHIPS)':
 'B': CDS_PINID='B';
NODE_NAME     PC1852 2
 '@T6G_MB_LIB.T6G(SCH_1):PAGE244_I34@PURE_QUANTA.Q_CAP(CHIPS)':
 'B': CDS_PINID='B';
NODE_NAME     PR3337 2
 '@T6G_MB_LIB.T6G(SCH_1):PAGE244_I37@PURE_QUANTA.Q_RES(CHIPS)':
 'B': CDS_PINID='B';
NODE_NAME     U326 2
 '@T6G_MB_LIB.T6G(SCH_1):PAGE244_I38@PURE_QUANTA.MPQ8633AGLEC807Z(CHIPS)':
 'AGND': CDS_PINID='AGND';
NODE_NAME     U326 11_18
 '@T6G_MB_LIB.T6G(SCH_1):PAGE244_I38@PURE_QUANTA.MPQ8633AGLEC807Z(CHIPS)':
 'PGND': CDS_PINID='PGND';
NODE_NAME     U326 6
 '@T6G_MB_LIB.T6G(SCH_1):PAGE244_I38@PURE_QUANTA.MPQ8633AGLEC807Z(CHIPS)':
 'RGND': CDS_PINID='RGND';
NODE_NAME     PR832 2
 '@T6G_MB_LIB.T6G(SCH_1):PAGE245_I10@PURE_QUANTA.Q_RES(CHIPS)':
 'B': CDS_PINID='B';
NODE_NAME     PC581 2
 '@T6G_MB_LIB.T6G(SCH_1):PAGE245_I12@PURE_QUANTA.Q_CAP(CHIPS)':
 'B': CDS_PINID='B';
NODE_NAME     PC591 2
 '@T6G_MB_LIB.T6G(SCH_1):PAGE245_I19@PURE_QUANTA.Q_CAP(CHIPS)':
 'B': CDS_PINID='B';
NODE_NAME     PC2261 2
 '@T6G_MB_LIB.T6G(SCH_1):PAGE245_I27@PURE_QUANTA.Q_CAP(CHIPS)':
 'B': CDS_PINID='B';
NODE_NAME     PC8008 2
 '@T6G_MB_LIB.T6G(SCH_1):PAGE245_I44@PURE_QUANTA.Q_CAP(CHIPS)':
 'B': CDS_PINID='B';
NODE_NAME     PC1599 2
 '@T6G_MB_LIB.T6G(SCH_1):PAGE245_I60@PURE_QUANTA.Q_CAP(CHIPS)':
 'B': CDS_PINID='B';
NODE_NAME     PC118 2
 '@T6G_MB_LIB.T6G(SCH_1):PAGE167_I2@PURE_QUANTA.Q_CAP(CHIPS)':
 'B': CDS_PINID='B';
NODE_NAME     C348 2
 '@T6G_MB_LIB.T6G(SCH_1):PAGE167_I5@PURE_QUANTA.Q_CAP(CHIPS)':
 'B': CDS_PINID='B';
NODE_NAME     PC6000 2
 '@T6G_MB_LIB.T6G(SCH_1):PAGE167_I8@PURE_QUANTA.Q_CAP(CHIPS)':
 'B': CDS_PINID='B';
NODE_NAME     PC119 2
 '@T6G_MB_LIB.T6G(SCH_1):PAGE167_I12@PURE_QUANTA.Q_CAP(CHIPS)':
 'B': CDS_PINID='B';
NODE_NAME     PC120 2
 '@T6G_MB_LIB.T6G(SCH_1):PAGE167_I13@PURE_QUANTA.Q_CAP(CHIPS)':
 'B': CDS_PINID='B';
NODE_NAME     PR452 2
 '@T6G_MB_LIB.T6G(SCH_1):PAGE167_I15@PURE_QUANTA.Q_RES(CHIPS)':
 'B': CDS_PINID='B';
NODE_NAME     PR6000 1
 '@T6G_MB_LIB.T6G(SCH_1):PAGE167_I17@PURE_QUANTA.Q_RES(CHIPS)':
 'A': CDS_PINID='A';
NODE_NAME     PC127 2
 '@T6G_MB_LIB.T6G(SCH_1):PAGE167_I19@PURE_QUANTA.Q_CAP(CHIPS)':
 'B': CDS_PINID='B';
NODE_NAME     PR454 2
 '@T6G_MB_LIB.T6G(SCH_1):PAGE167_I23@PURE_QUANTA.Q_RES(CHIPS)':
 'B': CDS_PINID='B';
NODE_NAME     PC129 2
 '@T6G_MB_LIB.T6G(SCH_1):PAGE167_I27@PURE_QUANTA.Q_CAP(CHIPS)':
 'B': CDS_PINID='B';
NODE_NAME     PC130 2
 '@T6G_MB_LIB.T6G(SCH_1):PAGE167_I28@PURE_QUANTA.Q_CAP(CHIPS)':
 'B': CDS_PINID='B';
NODE_NAME     PC123 2
 '@T6G_MB_LIB.T6G(SCH_1):PAGE167_I29@PURE_QUANTA.Q_CAP(CHIPS)':
 'B': CDS_PINID='B';
NODE_NAME     PC126 2
 '@T6G_MB_LIB.T6G(SCH_1):PAGE167_I30@PURE_QUANTA.Q_CAP(CHIPS)':
 'B': CDS_PINID='B';
NODE_NAME     PC134 2
 '@T6G_MB_LIB.T6G(SCH_1):PAGE167_I35@PURE_QUANTA.Q_CAP(CHIPS)':
 'B': CDS_PINID='B';
NODE_NAME     PC135 2
 '@T6G_MB_LIB.T6G(SCH_1):PAGE167_I36@PURE_QUANTA.Q_CAP(CHIPS)':
 'B': CDS_PINID='B';
NODE_NAME     PC136 2
 '@T6G_MB_LIB.T6G(SCH_1):PAGE167_I37@PURE_QUANTA.Q_CAP(CHIPS)':
 'B': CDS_PINID='B';
NODE_NAME     PU55 2
 '@T6G_MB_LIB.T6G(SCH_1):PAGE167_I41@PURE_QUANTA.MPQ8633AGLEC807Z(CHIPS)':
 'AGND': CDS_PINID='AGND';
NODE_NAME     PU55 11_18
 '@T6G_MB_LIB.T6G(SCH_1):PAGE167_I41@PURE_QUANTA.MPQ8633AGLEC807Z(CHIPS)':
 'PGND': CDS_PINID='PGND';
NODE_NAME     PU55 6
 '@T6G_MB_LIB.T6G(SCH_1):PAGE167_I41@PURE_QUANTA.MPQ8633AGLEC807Z(CHIPS)':
 'RGND': CDS_PINID='RGND';
NODE_NAME     R8286 2
 '@T6G_MB_LIB.T6G(SCH_1):PAGE168_I6@PURE_QUANTA.Q_RES(CHIPS)':
 'B': CDS_PINID='B';
NODE_NAME     PQ17 S
 '@T6G_MB_LIB.T6G(SCH_1):PAGE168_I17@PURE_QUANTA.MOSFET_N(CHIPS)':
 'SOURCE': CDS_PINID='SOURCE';
NODE_NAME     PR5 2
 '@T6G_MB_LIB.T6G(SCH_1):PAGE168_I21@PURE_QUANTA.Q_RES(CHIPS)':
 'B': CDS_PINID='B';
NODE_NAME     PC462 2
 '@T6G_MB_LIB.T6G(SCH_1):PAGE168_I23@PURE_QUANTA.Q_CAP(CHIPS)':
 'B': CDS_PINID='B';
NODE_NAME     PR292 2
 '@T6G_MB_LIB.T6G(SCH_1):PAGE168_I27@PURE_QUANTA.Q_RES(CHIPS)':
 'B': CDS_PINID='B';
NODE_NAME     PR295 2
 '@T6G_MB_LIB.T6G(SCH_1):PAGE168_I44@PURE_QUANTA.Q_RES(CHIPS)':
 'B': CDS_PINID='B';
NODE_NAME     PC7 2
 '@T6G_MB_LIB.T6G(SCH_1):PAGE168_I50@PURE_QUANTA.Q_CAP(CHIPS)':
 'B': CDS_PINID='B';
NODE_NAME     C465 2
 '@T6G_MB_LIB.T6G(SCH_1):PAGE168_I51@PURE_QUANTA.Q_CAP(CHIPS)':
 'B': CDS_PINID='B';
NODE_NAME     PC466 2
 '@T6G_MB_LIB.T6G(SCH_1):PAGE168_I52@PURE_QUANTA.Q_CAP(CHIPS)':
 'B': CDS_PINID='B';
NODE_NAME     C298 2
 '@T6G_MB_LIB.T6G(SCH_1):PAGE168_I64@PURE_QUANTA.Q_CAP(CHIPS)':
 'B': CDS_PINID='B';
NODE_NAME     C467 2
 '@T6G_MB_LIB.T6G(SCH_1):PAGE168_I92@PURE_QUANTA.Q_CAP(CHIPS)':
 'B': CDS_PINID='B';
NODE_NAME     PC469 2
 '@T6G_MB_LIB.T6G(SCH_1):PAGE168_I95@PURE_QUANTA.Q_CAP(CHIPS)':
 'B': CDS_PINID='B';
NODE_NAME     PC472 2
 '@T6G_MB_LIB.T6G(SCH_1):PAGE168_I98@PURE_QUANTA.Q_CAP(CHIPS)':
 'B': CDS_PINID='B';
NODE_NAME     PR441 2
 '@T6G_MB_LIB.T6G(SCH_1):PAGE168_I107@PURE_QUANTA.Q_RES(CHIPS)':
 'B': CDS_PINID='B';
NODE_NAME     PR440 2
 '@T6G_MB_LIB.T6G(SCH_1):PAGE168_I108@PURE_QUANTA.Q_RES(CHIPS)':
 'B': CDS_PINID='B';
NODE_NAME     PR531 2
 '@T6G_MB_LIB.T6G(SCH_1):PAGE168_I111@PURE_QUANTA.Q_RES(CHIPS)':
 'B': CDS_PINID='B';
NODE_NAME     PC12 2
 '@T6G_MB_LIB.T6G(SCH_1):PAGE168_I120@PURE_QUANTA.Q_CAP(CHIPS)':
 'B': CDS_PINID='B';
NODE_NAME     PC470 2
 '@T6G_MB_LIB.T6G(SCH_1):PAGE168_I129@PURE_QUANTA.Q_CAP(CHIPS)':
 'B': CDS_PINID='B';
NODE_NAME     PC471 2
 '@T6G_MB_LIB.T6G(SCH_1):PAGE168_I131@PURE_QUANTA.Q_CAP(CHIPS)':
 'B': CDS_PINID='B';
NODE_NAME     PU42 TH
 '@T6G_MB_LIB.T6G(SCH_1):PAGE168_I135@PURE_QUANTA.RAA229620GNPHA0(CHIPS)':
 'TH_GND': CDS_PINID='TH_GND';
NODE_NAME     PC474_2 2
 '@T6G_MB_LIB.T6G(SCH_1):PAGE169_I8@PURE_QUANTA.Q_CAP(CHIPS)':
 'B': CDS_PINID='B';
NODE_NAME     PR321 1
 '@T6G_MB_LIB.T6G(SCH_1):PAGE169_I10@PURE_QUANTA.Q_RES(CHIPS)':
 'A': CDS_PINID='A';
NODE_NAME     PC476 2
 '@T6G_MB_LIB.T6G(SCH_1):PAGE169_I14@PURE_QUANTA.Q_CAP(CHIPS)':
 'B': CDS_PINID='B';
NODE_NAME     PC473_1 2
 '@T6G_MB_LIB.T6G(SCH_1):PAGE169_I22@PURE_QUANTA.Q_CAP(CHIPS)':
 'B': CDS_PINID='B';
NODE_NAME     PR496 2
 '@T6G_MB_LIB.T6G(SCH_1):PAGE169_I28@PURE_QUANTA.Q_RES(CHIPS)':
 'B': CDS_PINID='B';
NODE_NAME     PC480_2 2
 '@T6G_MB_LIB.T6G(SCH_1):PAGE169_I34@PURE_QUANTA.Q_CAP(CHIPS)':
 'B': CDS_PINID='B';
NODE_NAME     PC484_2 2
 '@T6G_MB_LIB.T6G(SCH_1):PAGE169_I36@PURE_QUANTA.Q_CAP(CHIPS)':
 'B': CDS_PINID='B';
NODE_NAME     PC486_2 2
 '@T6G_MB_LIB.T6G(SCH_1):PAGE169_I37@PURE_QUANTA.Q_CAP(CHIPS)':
 'B': CDS_PINID='B';
NODE_NAME     PC488_2 2
 '@T6G_MB_LIB.T6G(SCH_1):PAGE169_I39@PURE_QUANTA.Q_CAP(CHIPS)':
 'B': CDS_PINID='B';
NODE_NAME     PR495 2
 '@T6G_MB_LIB.T6G(SCH_1):PAGE169_I42@PURE_QUANTA.Q_RES(CHIPS)':
 'B': CDS_PINID='B';
NODE_NAME     PC475 2
 '@T6G_MB_LIB.T6G(SCH_1):PAGE169_I45@PURE_QUANTA.Q_CAP(CHIPS)':
 'B': CDS_PINID='B';
NODE_NAME     PR320 1
 '@T6G_MB_LIB.T6G(SCH_1):PAGE169_I46@PURE_QUANTA.Q_RES(CHIPS)':
 'A': CDS_PINID='A';
NODE_NAME     PC477_C0P0_1 2
 '@T6G_MB_LIB.T6G(SCH_1):PAGE169_I51@PURE_QUANTA.Q_CAP(CHIPS)':
 'B': CDS_PINID='B';
NODE_NAME     PC479_1 2
 '@T6G_MB_LIB.T6G(SCH_1):PAGE169_I52@PURE_QUANTA.Q_CAP(CHIPS)':
 'B': CDS_PINID='B';
NODE_NAME     PC481_1 2
 '@T6G_MB_LIB.T6G(SCH_1):PAGE169_I53@PURE_QUANTA.Q_CAP(CHIPS)':
 'B': CDS_PINID='B';
NODE_NAME     PC483_1 2
 '@T6G_MB_LIB.T6G(SCH_1):PAGE169_I57@PURE_QUANTA.Q_CAP(CHIPS)':
 'B': CDS_PINID='B';
NODE_NAME     PC485_1 2
 '@T6G_MB_LIB.T6G(SCH_1):PAGE169_I58@PURE_QUANTA.Q_CAP(CHIPS)':
 'B': CDS_PINID='B';
NODE_NAME     PC487_1 2
 '@T6G_MB_LIB.T6G(SCH_1):PAGE169_I59@PURE_QUANTA.Q_CAP(CHIPS)':
 'B': CDS_PINID='B';
NODE_NAME     PC501_2 2
 '@T6G_MB_LIB.T6G(SCH_1):PAGE169_I70@PURE_QUANTA.Q_CAP(CHIPS)':
 'B': CDS_PINID='B';
NODE_NAME     PC498 2
 '@T6G_MB_LIB.T6G(SCH_1):PAGE169_I73@PURE_QUANTA.Q_CAPP(CHIPS)':
 'B': CDS_PINID='B';
NODE_NAME     PC491 2
 '@T6G_MB_LIB.T6G(SCH_1):PAGE169_I79@PURE_QUANTA.Q_CAPP(CHIPS)':
 'B': CDS_PINID='B';
NODE_NAME     PC492 2
 '@T6G_MB_LIB.T6G(SCH_1):PAGE169_I81@PURE_QUANTA.Q_CAPP(CHIPS)':
 'B': CDS_PINID='B';
NODE_NAME     PC479 2
 '@T6G_MB_LIB.T6G(SCH_1):PAGE169_I85@PURE_QUANTA.Q_CAP(CHIPS)':
 'B': CDS_PINID='B';
NODE_NAME     PC497 2
 '@T6G_MB_LIB.T6G(SCH_1):PAGE169_I87@PURE_QUANTA.Q_CAP(CHIPS)':
 'B': CDS_PINID='B';
NODE_NAME     PC500_1 2
 '@T6G_MB_LIB.T6G(SCH_1):PAGE169_I88@PURE_QUANTA.Q_CAP(CHIPS)':
 'B': CDS_PINID='B';
NODE_NAME     PC502_1 2
 '@T6G_MB_LIB.T6G(SCH_1):PAGE169_I89@PURE_QUANTA.Q_CAP(CHIPS)':
 'B': CDS_PINID='B';
NODE_NAME     PR447 2
 '@T6G_MB_LIB.T6G(SCH_1):PAGE169_I90@PURE_QUANTA.Q_RES(CHIPS)':
 'B': CDS_PINID='B';
NODE_NAME     PC545_4 2
 '@T6G_MB_LIB.T6G(SCH_1):PAGE170_I2@PURE_QUANTA.Q_CAP(CHIPS)':
 'B': CDS_PINID='B';
NODE_NAME     PC547 2
 '@T6G_MB_LIB.T6G(SCH_1):PAGE170_I6@PURE_QUANTA.Q_CAP(CHIPS)':
 'B': CDS_PINID='B';
NODE_NAME     PU47 2
 '@T6G_MB_LIB.T6G(SCH_1):PAGE170_I9@PURE_QUANTA.ISL99390FRZTR5935(CHIPS)':
 'AGND': CDS_PINID='AGND';
NODE_NAME     PU47 5
 '@T6G_MB_LIB.T6G(SCH_1):PAGE170_I9@PURE_QUANTA.ISL99390FRZTR5935(CHIPS)':
 'PGND1': CDS_PINID='PGND1';
NODE_NAME     PU47 7_9-20_24
 '@T6G_MB_LIB.T6G(SCH_1):PAGE170_I9@PURE_QUANTA.ISL99390FRZTR5935(CHIPS)':
 'PGND2': CDS_PINID='PGND2';
NODE_NAME     PU47 40
 '@T6G_MB_LIB.T6G(SCH_1):PAGE170_I9@PURE_QUANTA.ISL99390FRZTR5935(CHIPS)':
 'PGND3': CDS_PINID='PGND3';
NODE_NAME     PR347 1
 '@T6G_MB_LIB.T6G(SCH_1):PAGE170_I11@PURE_QUANTA.Q_RES(CHIPS)':
 'A': CDS_PINID='A';
NODE_NAME     PC549_C0P0_4 2
 '@T6G_MB_LIB.T6G(SCH_1):PAGE170_I15@PURE_QUANTA.Q_CAP(CHIPS)':
 'B': CDS_PINID='B';
NODE_NAME     PC553_4 2
 '@T6G_MB_LIB.T6G(SCH_1):PAGE170_I22@PURE_QUANTA.Q_CAP(CHIPS)':
 'B': CDS_PINID='B';
NODE_NAME     PC557_4 2
 '@T6G_MB_LIB.T6G(SCH_1):PAGE170_I24@PURE_QUANTA.Q_CAP(CHIPS)':
 'B': CDS_PINID='B';
NODE_NAME     PC544_3 2
 '@T6G_MB_LIB.T6G(SCH_1):PAGE170_I27@PURE_QUANTA.Q_CAP(CHIPS)':
 'B': CDS_PINID='B';
NODE_NAME     PC546 2
 '@T6G_MB_LIB.T6G(SCH_1):PAGE170_I36@PURE_QUANTA.Q_CAP(CHIPS)':
 'B': CDS_PINID='B';
NODE_NAME     PU46 2
 '@T6G_MB_LIB.T6G(SCH_1):PAGE170_I38@PURE_QUANTA.ISL99390FRZTR5935(CHIPS)':
 'AGND': CDS_PINID='AGND';
NODE_NAME     PU46 5
 '@T6G_MB_LIB.T6G(SCH_1):PAGE170_I38@PURE_QUANTA.ISL99390FRZTR5935(CHIPS)':
 'PGND1': CDS_PINID='PGND1';
NODE_NAME     PU46 7_9-20_24
 '@T6G_MB_LIB.T6G(SCH_1):PAGE170_I38@PURE_QUANTA.ISL99390FRZTR5935(CHIPS)':
 'PGND2': CDS_PINID='PGND2';
NODE_NAME     PU46 40
 '@T6G_MB_LIB.T6G(SCH_1):PAGE170_I38@PURE_QUANTA.ISL99390FRZTR5935(CHIPS)':
 'PGND3': CDS_PINID='PGND3';
NODE_NAME     PC548_C0P0_3 2
 '@T6G_MB_LIB.T6G(SCH_1):PAGE170_I40@PURE_QUANTA.Q_CAP(CHIPS)':
 'B': CDS_PINID='B';
NODE_NAME     PC552_3 2
 '@T6G_MB_LIB.T6G(SCH_1):PAGE170_I43@PURE_QUANTA.Q_CAP(CHIPS)':
 'B': CDS_PINID='B';
NODE_NAME     PR498 2
 '@T6G_MB_LIB.T6G(SCH_1):PAGE170_I44@PURE_QUANTA.Q_RES(CHIPS)':
 'B': CDS_PINID='B';
NODE_NAME     PC550_3 2
 '@T6G_MB_LIB.T6G(SCH_1):PAGE170_I47@PURE_QUANTA.Q_CAP(CHIPS)':
 'B': CDS_PINID='B';
NODE_NAME     PC554_3 2
 '@T6G_MB_LIB.T6G(SCH_1):PAGE170_I48@PURE_QUANTA.Q_CAP(CHIPS)':
 'B': CDS_PINID='B';
NODE_NAME     PC556_3 2
 '@T6G_MB_LIB.T6G(SCH_1):PAGE170_I49@PURE_QUANTA.Q_CAP(CHIPS)':
 'B': CDS_PINID='B';
NODE_NAME     PL60 3
 '@T6G_MB_LIB.T6G(SCH_1):PAGE170_I52@PURE_QUANTA.Q_INDUCTOR4P_14(CHIPS)':
 '3': CDS_PINID='\3\';
NODE_NAME     PC559_4 2
 '@T6G_MB_LIB.T6G(SCH_1):PAGE170_I55@PURE_QUANTA.Q_CAP(CHIPS)':
 'B': CDS_PINID='B';
NODE_NAME     PC563_4 2
 '@T6G_MB_LIB.T6G(SCH_1):PAGE170_I58@PURE_QUANTA.Q_CAP(CHIPS)':
 'B': CDS_PINID='B';
NODE_NAME     PC565_4 2
 '@T6G_MB_LIB.T6G(SCH_1):PAGE170_I60@PURE_QUANTA.Q_CAP(CHIPS)':
 'B': CDS_PINID='B';
NODE_NAME     PC558_3 2
 '@T6G_MB_LIB.T6G(SCH_1):PAGE170_I66@PURE_QUANTA.Q_CAP(CHIPS)':
 'B': CDS_PINID='B';
NODE_NAME     PC562_3 2
 '@T6G_MB_LIB.T6G(SCH_1):PAGE170_I70@PURE_QUANTA.Q_CAP(CHIPS)':
 'B': CDS_PINID='B';
NODE_NAME     PC564_3 2
 '@T6G_MB_LIB.T6G(SCH_1):PAGE170_I71@PURE_QUANTA.Q_CAP(CHIPS)':
 'B': CDS_PINID='B';
NODE_NAME     PC150_6 2
 '@T6G_MB_LIB.T6G(SCH_1):PAGE171_I4@PURE_QUANTA.Q_CAP(CHIPS)':
 'B': CDS_PINID='B';
NODE_NAME     PR431 1
 '@T6G_MB_LIB.T6G(SCH_1):PAGE171_I8@PURE_QUANTA.Q_RES(CHIPS)':
 'A': CDS_PINID='A';
NODE_NAME     PC151 2
 '@T6G_MB_LIB.T6G(SCH_1):PAGE171_I11@PURE_QUANTA.Q_CAP(CHIPS)':
 'B': CDS_PINID='B';
NODE_NAME     PC152_C0P0_6 2
 '@T6G_MB_LIB.T6G(SCH_1):PAGE171_I14@PURE_QUANTA.Q_CAP(CHIPS)':
 'B': CDS_PINID='B';
NODE_NAME     PU48 2
 '@T6G_MB_LIB.T6G(SCH_1):PAGE171_I18@PURE_QUANTA.ISL99390FRZTR5935(CHIPS)':
 'AGND': CDS_PINID='AGND';
NODE_NAME     PU48 5
 '@T6G_MB_LIB.T6G(SCH_1):PAGE171_I18@PURE_QUANTA.ISL99390FRZTR5935(CHIPS)':
 'PGND1': CDS_PINID='PGND1';
NODE_NAME     PU48 7_9-20_24
 '@T6G_MB_LIB.T6G(SCH_1):PAGE171_I18@PURE_QUANTA.ISL99390FRZTR5935(CHIPS)':
 'PGND2': CDS_PINID='PGND2';
NODE_NAME     PU48 40
 '@T6G_MB_LIB.T6G(SCH_1):PAGE171_I18@PURE_QUANTA.ISL99390FRZTR5935(CHIPS)':
 'PGND3': CDS_PINID='PGND3';
NODE_NAME     PR500 2
 '@T6G_MB_LIB.T6G(SCH_1):PAGE171_I22@PURE_QUANTA.Q_RES(CHIPS)':
 'B': CDS_PINID='B';
NODE_NAME     PC153_6 2
 '@T6G_MB_LIB.T6G(SCH_1):PAGE171_I24@PURE_QUANTA.Q_CAP(CHIPS)':
 'B': CDS_PINID='B';
NODE_NAME     PC154_6 2
 '@T6G_MB_LIB.T6G(SCH_1):PAGE171_I27@PURE_QUANTA.Q_CAP(CHIPS)':
 'B': CDS_PINID='B';
NODE_NAME     PC157_6 2
 '@T6G_MB_LIB.T6G(SCH_1):PAGE171_I28@PURE_QUANTA.Q_CAP(CHIPS)':
 'B': CDS_PINID='B';
NODE_NAME     PC158_6 2
 '@T6G_MB_LIB.T6G(SCH_1):PAGE171_I29@PURE_QUANTA.Q_CAP(CHIPS)':
 'B': CDS_PINID='B';
NODE_NAME     PR501 2
 '@T6G_MB_LIB.T6G(SCH_1):PAGE171_I31@PURE_QUANTA.Q_RES(CHIPS)':
 'B': CDS_PINID='B';
NODE_NAME     PC566_5 2
 '@T6G_MB_LIB.T6G(SCH_1):PAGE171_I33@PURE_QUANTA.Q_CAP(CHIPS)':
 'B': CDS_PINID='B';
NODE_NAME     PR353 1
 '@T6G_MB_LIB.T6G(SCH_1):PAGE171_I36@PURE_QUANTA.Q_RES(CHIPS)':
 'A': CDS_PINID='A';
NODE_NAME     PC567 2
 '@T6G_MB_LIB.T6G(SCH_1):PAGE171_I38@PURE_QUANTA.Q_CAP(CHIPS)':
 'B': CDS_PINID='B';
NODE_NAME     PC568_C0P0_5 2
 '@T6G_MB_LIB.T6G(SCH_1):PAGE171_I42@PURE_QUANTA.Q_CAP(CHIPS)':
 'B': CDS_PINID='B';
NODE_NAME     PC570_5 2
 '@T6G_MB_LIB.T6G(SCH_1):PAGE171_I44@PURE_QUANTA.Q_CAP(CHIPS)':
 'B': CDS_PINID='B';
NODE_NAME     PC569_5 2
 '@T6G_MB_LIB.T6G(SCH_1):PAGE171_I47@PURE_QUANTA.Q_CAP(CHIPS)':
 'B': CDS_PINID='B';
NODE_NAME     PC571_5 2
 '@T6G_MB_LIB.T6G(SCH_1):PAGE171_I48@PURE_QUANTA.Q_CAP(CHIPS)':
 'B': CDS_PINID='B';
NODE_NAME     PC572_5 2
 '@T6G_MB_LIB.T6G(SCH_1):PAGE171_I49@PURE_QUANTA.Q_CAP(CHIPS)':
 'B': CDS_PINID='B';
NODE_NAME     PL50 1
 '@T6G_MB_LIB.T6G(SCH_1):PAGE171_I51@PURE_QUANTA.Q_INDUCTOR(CHIPS)':
 '1': CDS_PINID='\1\';
NODE_NAME     PC159_6 2
 '@T6G_MB_LIB.T6G(SCH_1):PAGE171_I55@PURE_QUANTA.Q_CAP(CHIPS)':
 'B': CDS_PINID='B';
NODE_NAME     PC163_6 2
 '@T6G_MB_LIB.T6G(SCH_1):PAGE171_I59@PURE_QUANTA.Q_CAP(CHIPS)':
 'B': CDS_PINID='B';
NODE_NAME     PC166_6 2
 '@T6G_MB_LIB.T6G(SCH_1):PAGE171_I60@PURE_QUANTA.Q_CAP(CHIPS)':
 'B': CDS_PINID='B';
NODE_NAME     PC573_5 2
 '@T6G_MB_LIB.T6G(SCH_1):PAGE171_I66@PURE_QUANTA.Q_CAP(CHIPS)':
 'B': CDS_PINID='B';
NODE_NAME     PC575_5 2
 '@T6G_MB_LIB.T6G(SCH_1):PAGE171_I69@PURE_QUANTA.Q_CAP(CHIPS)':
 'B': CDS_PINID='B';
NODE_NAME     PC576_5 2
 '@T6G_MB_LIB.T6G(SCH_1):PAGE171_I71@PURE_QUANTA.Q_CAP(CHIPS)':
 'B': CDS_PINID='B';
NODE_NAME     PU10 2
 '@T6G_MB_LIB.T6G(SCH_1):PAGE171_I73@PURE_QUANTA.ISL99390FRZTR5935(CHIPS)':
 'AGND': CDS_PINID='AGND';
NODE_NAME     PU10 5
 '@T6G_MB_LIB.T6G(SCH_1):PAGE171_I73@PURE_QUANTA.ISL99390FRZTR5935(CHIPS)':
 'PGND1': CDS_PINID='PGND1';
NODE_NAME     PU10 7_9-20_24
 '@T6G_MB_LIB.T6G(SCH_1):PAGE171_I73@PURE_QUANTA.ISL99390FRZTR5935(CHIPS)':
 'PGND2': CDS_PINID='PGND2';
NODE_NAME     PU10 40
 '@T6G_MB_LIB.T6G(SCH_1):PAGE171_I73@PURE_QUANTA.ISL99390FRZTR5935(CHIPS)':
 'PGND3': CDS_PINID='PGND3';
NODE_NAME     PR359 1
 '@T6G_MB_LIB.T6G(SCH_1):PAGE173_I8@PURE_QUANTA.Q_RES(CHIPS)':
 'A': CDS_PINID='A';
NODE_NAME     PC580 2
 '@T6G_MB_LIB.T6G(SCH_1):PAGE173_I11@PURE_QUANTA.Q_CAP(CHIPS)':
 'B': CDS_PINID='B';
NODE_NAME     PC582_SOP0_2 2
 '@T6G_MB_LIB.T6G(SCH_1):PAGE173_I14@PURE_QUANTA.Q_CAP(CHIPS)':
 'B': CDS_PINID='B';
NODE_NAME     PC586_2 2
 '@T6G_MB_LIB.T6G(SCH_1):PAGE173_I21@PURE_QUANTA.Q_CAP(CHIPS)':
 'B': CDS_PINID='B';
NODE_NAME     PR358 1
 '@T6G_MB_LIB.T6G(SCH_1):PAGE173_I32@PURE_QUANTA.Q_RES(CHIPS)':
 'A': CDS_PINID='A';
NODE_NAME     PC579 2
 '@T6G_MB_LIB.T6G(SCH_1):PAGE173_I36@PURE_QUANTA.Q_CAP(CHIPS)':
 'B': CDS_PINID='B';
NODE_NAME     PC581_SOP0_1 2
 '@T6G_MB_LIB.T6G(SCH_1):PAGE173_I40@PURE_QUANTA.Q_CAP(CHIPS)':
 'B': CDS_PINID='B';
NODE_NAME     PU49 2
 '@T6G_MB_LIB.T6G(SCH_1):PAGE173_I41@PURE_QUANTA.ISL99390FRZTR5935(CHIPS)':
 'AGND': CDS_PINID='AGND';
NODE_NAME     PU49 5
 '@T6G_MB_LIB.T6G(SCH_1):PAGE173_I41@PURE_QUANTA.ISL99390FRZTR5935(CHIPS)':
 'PGND1': CDS_PINID='PGND1';
NODE_NAME     PU49 7_9-20_24
 '@T6G_MB_LIB.T6G(SCH_1):PAGE173_I41@PURE_QUANTA.ISL99390FRZTR5935(CHIPS)':
 'PGND2': CDS_PINID='PGND2';
NODE_NAME     PU49 40
 '@T6G_MB_LIB.T6G(SCH_1):PAGE173_I41@PURE_QUANTA.ISL99390FRZTR5935(CHIPS)':
 'PGND3': CDS_PINID='PGND3';
NODE_NAME     PC585_1 2
 '@T6G_MB_LIB.T6G(SCH_1):PAGE173_I44@PURE_QUANTA.Q_CAP(CHIPS)':
 'B': CDS_PINID='B';
NODE_NAME     PR502 2
 '@T6G_MB_LIB.T6G(SCH_1):PAGE173_I45@PURE_QUANTA.Q_RES(CHIPS)':
 'B': CDS_PINID='B';
NODE_NAME     PC587_1 2
 '@T6G_MB_LIB.T6G(SCH_1):PAGE173_I49@PURE_QUANTA.Q_CAP(CHIPS)':
 'B': CDS_PINID='B';
NODE_NAME     PC589_1 2
 '@T6G_MB_LIB.T6G(SCH_1):PAGE173_I50@PURE_QUANTA.Q_CAP(CHIPS)':
 'B': CDS_PINID='B';
NODE_NAME     PC591_1 2
 '@T6G_MB_LIB.T6G(SCH_1):PAGE173_I51@PURE_QUANTA.Q_CAP(CHIPS)':
 'B': CDS_PINID='B';
NODE_NAME     PC592_2 2
 '@T6G_MB_LIB.T6G(SCH_1):PAGE173_I56@PURE_QUANTA.Q_CAP(CHIPS)':
 'B': CDS_PINID='B';
NODE_NAME     PC595_2 2
 '@T6G_MB_LIB.T6G(SCH_1):PAGE173_I57@PURE_QUANTA.Q_CAP(CHIPS)':
 'B': CDS_PINID='B';
NODE_NAME     PC600_2 2
 '@T6G_MB_LIB.T6G(SCH_1):PAGE173_I59@PURE_QUANTA.Q_CAP(CHIPS)':
 'B': CDS_PINID='B';
NODE_NAME     PC603_2 2
 '@T6G_MB_LIB.T6G(SCH_1):PAGE173_I61@PURE_QUANTA.Q_CAP(CHIPS)':
 'B': CDS_PINID='B';
NODE_NAME     PC598 2
 '@T6G_MB_LIB.T6G(SCH_1):PAGE173_I64@PURE_QUANTA.Q_CAPP(CHIPS)':
 'B': CDS_PINID='B';
NODE_NAME     PC593_1 2
 '@T6G_MB_LIB.T6G(SCH_1):PAGE173_I72@PURE_QUANTA.Q_CAP(CHIPS)':
 'B': CDS_PINID='B';
NODE_NAME     PC596 2
 '@T6G_MB_LIB.T6G(SCH_1):PAGE173_I73@PURE_QUANTA.Q_CAPP(CHIPS)':
 'B': CDS_PINID='B';
NODE_NAME     PC583 2
 '@T6G_MB_LIB.T6G(SCH_1):PAGE173_I77@PURE_QUANTA.Q_CAP(CHIPS)':
 'B': CDS_PINID='B';
NODE_NAME     PC602_1 2
 '@T6G_MB_LIB.T6G(SCH_1):PAGE173_I80@PURE_QUANTA.Q_CAP(CHIPS)':
 'B': CDS_PINID='B';
NODE_NAME     PR334 2
 '@T6G_MB_LIB.T6G(SCH_1):PAGE173_I82@PURE_QUANTA.Q_RES(CHIPS)':
 'B': CDS_PINID='B';
NODE_NAME     PU50 2
 '@T6G_MB_LIB.T6G(SCH_1):PAGE173_I86@PURE_QUANTA.ISL99390FRZTR5935(CHIPS)':
 'AGND': CDS_PINID='AGND';
NODE_NAME     PU50 5
 '@T6G_MB_LIB.T6G(SCH_1):PAGE173_I86@PURE_QUANTA.ISL99390FRZTR5935(CHIPS)':
 'PGND1': CDS_PINID='PGND1';
NODE_NAME     PU50 7_9-20_24
 '@T6G_MB_LIB.T6G(SCH_1):PAGE173_I86@PURE_QUANTA.ISL99390FRZTR5935(CHIPS)':
 'PGND2': CDS_PINID='PGND2';
NODE_NAME     PU50 40
 '@T6G_MB_LIB.T6G(SCH_1):PAGE173_I86@PURE_QUANTA.ISL99390FRZTR5935(CHIPS)':
 'PGND3': CDS_PINID='PGND3';
NODE_NAME     PC605_9 2
 '@T6G_MB_LIB.T6G(SCH_1):PAGE174_I2@PURE_QUANTA.Q_CAP(CHIPS)':
 'B': CDS_PINID='B';
NODE_NAME     PR505 2
 '@T6G_MB_LIB.T6G(SCH_1):PAGE174_I10@PURE_QUANTA.Q_RES(CHIPS)':
 'B': CDS_PINID='B';
NODE_NAME     PC606 2
 '@T6G_MB_LIB.T6G(SCH_1):PAGE174_I14@PURE_QUANTA.Q_CAP(CHIPS)':
 'B': CDS_PINID='B';
NODE_NAME     PC607_SOP0_3 2
 '@T6G_MB_LIB.T6G(SCH_1):PAGE174_I19@PURE_QUANTA.Q_CAP(CHIPS)':
 'B': CDS_PINID='B';
NODE_NAME     PL62 1
 '@T6G_MB_LIB.T6G(SCH_1):PAGE174_I24@PURE_QUANTA.Q_INDUCTOR(CHIPS)':
 '1': CDS_PINID='\1\';
NODE_NAME     PC614_3 2
 '@T6G_MB_LIB.T6G(SCH_1):PAGE174_I27@PURE_QUANTA.Q_CAP(CHIPS)':
 'B': CDS_PINID='B';
NODE_NAME     PC612_3 2
 '@T6G_MB_LIB.T6G(SCH_1):PAGE174_I34@PURE_QUANTA.Q_CAP(CHIPS)':
 'B': CDS_PINID='B';
NODE_NAME     C8066 2
 '@T6G_MB_LIB.T6G(SCH_1):PAGE175_I3@PURE_QUANTA.Q_CAP(CHIPS)':
 'B': CDS_PINID='B';
NODE_NAME     PQ14 S
 '@T6G_MB_LIB.T6G(SCH_1):PAGE175_I6@PURE_QUANTA.MOSFET_N(CHIPS)':
 'SOURCE': CDS_PINID='SOURCE';
NODE_NAME     PR54 2
 '@T6G_MB_LIB.T6G(SCH_1):PAGE175_I8@PURE_QUANTA.Q_RES(CHIPS)':
 'B': CDS_PINID='B';
NODE_NAME     PR67 2
 '@T6G_MB_LIB.T6G(SCH_1):PAGE175_I12@PURE_QUANTA.Q_RES(CHIPS)':
 'B': CDS_PINID='B';
NODE_NAME     PR50 2
 '@T6G_MB_LIB.T6G(SCH_1):PAGE175_I19@PURE_QUANTA.Q_RES(CHIPS)':
 'B': CDS_PINID='B';
NODE_NAME     PR49 2
 '@T6G_MB_LIB.T6G(SCH_1):PAGE175_I23@PURE_QUANTA.Q_RES(CHIPS)':
 'B': CDS_PINID='B';
NODE_NAME     PR40 2
 '@T6G_MB_LIB.T6G(SCH_1):PAGE175_I28@PURE_QUANTA.Q_RES(CHIPS)':
 'B': CDS_PINID='B';
NODE_NAME     R8042 2
 '@T6G_MB_LIB.T6G(SCH_1):PAGE175_I32@PURE_QUANTA.Q_RES(CHIPS)':
 'B': CDS_PINID='B';
NODE_NAME     C303 2
 '@T6G_MB_LIB.T6G(SCH_1):PAGE175_I33@PURE_QUANTA.Q_CAP(CHIPS)':
 'B': CDS_PINID='B';
NODE_NAME     C304 2
 '@T6G_MB_LIB.T6G(SCH_1):PAGE175_I34@PURE_QUANTA.Q_CAP(CHIPS)':
 'B': CDS_PINID='B';
NODE_NAME     C305 2
 '@T6G_MB_LIB.T6G(SCH_1):PAGE175_I35@PURE_QUANTA.Q_CAP(CHIPS)':
 'B': CDS_PINID='B';
NODE_NAME     PC67 2
 '@T6G_MB_LIB.T6G(SCH_1):PAGE175_I50@PURE_QUANTA.Q_CAP(CHIPS)':
 'B': CDS_PINID='B';
NODE_NAME     C8072 2
 '@T6G_MB_LIB.T6G(SCH_1):PAGE175_I55@PURE_QUANTA.Q_CAP(CHIPS)':
 'B': CDS_PINID='B';
NODE_NAME     PR600 2
 '@T6G_MB_LIB.T6G(SCH_1):PAGE175_I59@PURE_QUANTA.Q_RES(CHIPS)':
 'B': CDS_PINID='B';
NODE_NAME     PC74 2
 '@T6G_MB_LIB.T6G(SCH_1):PAGE175_I60@PURE_QUANTA.Q_CAP(CHIPS)':
 'B': CDS_PINID='B';
NODE_NAME     PC73 2
 '@T6G_MB_LIB.T6G(SCH_1):PAGE175_I63@PURE_QUANTA.Q_CAP(CHIPS)':
 'B': CDS_PINID='B';
NODE_NAME     PC78 2
 '@T6G_MB_LIB.T6G(SCH_1):PAGE175_I73@PURE_QUANTA.Q_CAP(CHIPS)':
 'B': CDS_PINID='B';
NODE_NAME     PC77 2
 '@T6G_MB_LIB.T6G(SCH_1):PAGE175_I75@PURE_QUANTA.Q_CAP(CHIPS)':
 'B': CDS_PINID='B';
NODE_NAME     PR532 2
 '@T6G_MB_LIB.T6G(SCH_1):PAGE175_I76@PURE_QUANTA.Q_RES(CHIPS)':
 'B': CDS_PINID='B';
NODE_NAME     PR32 2
 '@T6G_MB_LIB.T6G(SCH_1):PAGE175_I77@PURE_QUANTA.Q_RES(CHIPS)':
 'B': CDS_PINID='B';
NODE_NAME     C8069 2
 '@T6G_MB_LIB.T6G(SCH_1):PAGE175_I86@PURE_QUANTA.Q_CAP(CHIPS)':
 'B': CDS_PINID='B';
NODE_NAME     C8070 2
 '@T6G_MB_LIB.T6G(SCH_1):PAGE175_I91@PURE_QUANTA.Q_CAP(CHIPS)':
 'B': CDS_PINID='B';
NODE_NAME     PC15 2
 '@T6G_MB_LIB.T6G(SCH_1):PAGE175_I94@PURE_QUANTA.Q_CAP(CHIPS)':
 'B': CDS_PINID='B';
NODE_NAME     PC14 2
 '@T6G_MB_LIB.T6G(SCH_1):PAGE175_I96@PURE_QUANTA.Q_CAP(CHIPS)':
 'B': CDS_PINID='B';
NODE_NAME     PC76 2
 '@T6G_MB_LIB.T6G(SCH_1):PAGE175_I98@PURE_QUANTA.Q_CAP(CHIPS)':
 'B': CDS_PINID='B';
NODE_NAME     PC75 2
 '@T6G_MB_LIB.T6G(SCH_1):PAGE175_I100@PURE_QUANTA.Q_CAP(CHIPS)':
 'B': CDS_PINID='B';
NODE_NAME     PU12 TH
 '@T6G_MB_LIB.T6G(SCH_1):PAGE175_I128@PURE_QUANTA.RAA229620GNPHA0(CHIPS)':
 'TH_GND': CDS_PINID='TH_GND';
NODE_NAME     PR77 2
 '@T6G_MB_LIB.T6G(SCH_1):PAGE176_I4@PURE_QUANTA.Q_RES(CHIPS)':
 'B': CDS_PINID='B';
NODE_NAME     PC80 2
 '@T6G_MB_LIB.T6G(SCH_1):PAGE176_I10@PURE_QUANTA.Q_CAP(CHIPS)':
 'B': CDS_PINID='B';
NODE_NAME     PC84_1 2
 '@T6G_MB_LIB.T6G(SCH_1):PAGE176_I12@PURE_QUANTA.Q_CAP(CHIPS)':
 'B': CDS_PINID='B';
NODE_NAME     PC82_C1P0_2 2
 '@T6G_MB_LIB.T6G(SCH_1):PAGE176_I15@PURE_QUANTA.Q_CAP(CHIPS)':
 'B': CDS_PINID='B';
NODE_NAME     PR78 2
 '@T6G_MB_LIB.T6G(SCH_1):PAGE176_I18@PURE_QUANTA.Q_RES(CHIPS)':
 'B': CDS_PINID='B';
NODE_NAME     PC81_C1P0_1 2
 '@T6G_MB_LIB.T6G(SCH_1):PAGE176_I30@PURE_QUANTA.Q_CAP(CHIPS)':
 'B': CDS_PINID='B';
NODE_NAME     PU2 2
 '@T6G_MB_LIB.T6G(SCH_1):PAGE176_I33@PURE_QUANTA.ISL99390FRZTR5935(CHIPS)':
 'AGND': CDS_PINID='AGND';
NODE_NAME     PU2 5
 '@T6G_MB_LIB.T6G(SCH_1):PAGE176_I33@PURE_QUANTA.ISL99390FRZTR5935(CHIPS)':
 'PGND1': CDS_PINID='PGND1';
NODE_NAME     PU2 7_9-20_24
 '@T6G_MB_LIB.T6G(SCH_1):PAGE176_I33@PURE_QUANTA.ISL99390FRZTR5935(CHIPS)':
 'PGND2': CDS_PINID='PGND2';
NODE_NAME     PU2 40
 '@T6G_MB_LIB.T6G(SCH_1):PAGE176_I33@PURE_QUANTA.ISL99390FRZTR5935(CHIPS)':
 'PGND3': CDS_PINID='PGND3';
NODE_NAME     PU13 2
 '@T6G_MB_LIB.T6G(SCH_1):PAGE176_I35@PURE_QUANTA.ISL99390FRZTR5935(CHIPS)':
 'AGND': CDS_PINID='AGND';
NODE_NAME     PU13 5
 '@T6G_MB_LIB.T6G(SCH_1):PAGE176_I35@PURE_QUANTA.ISL99390FRZTR5935(CHIPS)':
 'PGND1': CDS_PINID='PGND1';
NODE_NAME     PU13 7_9-20_24
 '@T6G_MB_LIB.T6G(SCH_1):PAGE176_I35@PURE_QUANTA.ISL99390FRZTR5935(CHIPS)':
 'PGND2': CDS_PINID='PGND2';
NODE_NAME     PU13 40
 '@T6G_MB_LIB.T6G(SCH_1):PAGE176_I35@PURE_QUANTA.ISL99390FRZTR5935(CHIPS)':
 'PGND3': CDS_PINID='PGND3';
NODE_NAME     PC86_2 2
 '@T6G_MB_LIB.T6G(SCH_1):PAGE176_I37@PURE_QUANTA.Q_CAP(CHIPS)':
 'B': CDS_PINID='B';
NODE_NAME     PR507 2
 '@T6G_MB_LIB.T6G(SCH_1):PAGE176_I39@PURE_QUANTA.Q_RES(CHIPS)':
 'B': CDS_PINID='B';
NODE_NAME     PC90_2 2
 '@T6G_MB_LIB.T6G(SCH_1):PAGE176_I48@PURE_QUANTA.Q_CAP(CHIPS)':
 'B': CDS_PINID='B';
NODE_NAME     PR506 2
 '@T6G_MB_LIB.T6G(SCH_1):PAGE176_I50@PURE_QUANTA.Q_RES(CHIPS)':
 'B': CDS_PINID='B';
NODE_NAME     PC93_2 2
 '@T6G_MB_LIB.T6G(SCH_1):PAGE176_I51@PURE_QUANTA.Q_CAP(CHIPS)':
 'B': CDS_PINID='B';
NODE_NAME     PC96_2 2
 '@T6G_MB_LIB.T6G(SCH_1):PAGE176_I52@PURE_QUANTA.Q_CAP(CHIPS)':
 'B': CDS_PINID='B';
NODE_NAME     PC85_1 2
 '@T6G_MB_LIB.T6G(SCH_1):PAGE176_I55@PURE_QUANTA.Q_CAP(CHIPS)':
 'B': CDS_PINID='B';
NODE_NAME     PC87_1 2
 '@T6G_MB_LIB.T6G(SCH_1):PAGE176_I59@PURE_QUANTA.Q_CAP(CHIPS)':
 'B': CDS_PINID='B';
NODE_NAME     PC89_1 2
 '@T6G_MB_LIB.T6G(SCH_1):PAGE176_I60@PURE_QUANTA.Q_CAP(CHIPS)':
 'B': CDS_PINID='B';
NODE_NAME     PC91_1 2
 '@T6G_MB_LIB.T6G(SCH_1):PAGE176_I64@PURE_QUANTA.Q_CAP(CHIPS)':
 'B': CDS_PINID='B';
NODE_NAME     PC106_2 2
 '@T6G_MB_LIB.T6G(SCH_1):PAGE176_I69@PURE_QUANTA.Q_CAP(CHIPS)':
 'B': CDS_PINID='B';
NODE_NAME     PC102 2
 '@T6G_MB_LIB.T6G(SCH_1):PAGE176_I70@PURE_QUANTA.Q_CAPP(CHIPS)':
 'B': CDS_PINID='B';
NODE_NAME     PC97 2
 '@T6G_MB_LIB.T6G(SCH_1):PAGE176_I71@PURE_QUANTA.Q_CAPP(CHIPS)':
 'B': CDS_PINID='B';
NODE_NAME     PC98 2
 '@T6G_MB_LIB.T6G(SCH_1):PAGE176_I72@PURE_QUANTA.Q_CAPP(CHIPS)':
 'B': CDS_PINID='B';
NODE_NAME     PC100 2
 '@T6G_MB_LIB.T6G(SCH_1):PAGE176_I73@PURE_QUANTA.Q_CAPP(CHIPS)':
 'B': CDS_PINID='B';
NODE_NAME     PC108_2 2
 '@T6G_MB_LIB.T6G(SCH_1):PAGE176_I77@PURE_QUANTA.Q_CAP(CHIPS)':
 'B': CDS_PINID='B';
NODE_NAME     PC104 2
 '@T6G_MB_LIB.T6G(SCH_1):PAGE176_I82@PURE_QUANTA.Q_CAPP(CHIPS)':
 'B': CDS_PINID='B';
NODE_NAME     PC99 2
 '@T6G_MB_LIB.T6G(SCH_1):PAGE176_I84@PURE_QUANTA.Q_CAP(CHIPS)':
 'B': CDS_PINID='B';
NODE_NAME     PC102_1 2
 '@T6G_MB_LIB.T6G(SCH_1):PAGE176_I86@PURE_QUANTA.Q_CAP(CHIPS)':
 'B': CDS_PINID='B';
NODE_NAME     PC105_1 2
 '@T6G_MB_LIB.T6G(SCH_1):PAGE176_I89@PURE_QUANTA.Q_CAP(CHIPS)':
 'B': CDS_PINID='B';
NODE_NAME     PR444 2
 '@T6G_MB_LIB.T6G(SCH_1):PAGE176_I90@PURE_QUANTA.Q_RES(CHIPS)':
 'B': CDS_PINID='B';
NODE_NAME     PR85 2
 '@T6G_MB_LIB.T6G(SCH_1):PAGE177_I4@PURE_QUANTA.Q_RES(CHIPS)':
 'B': CDS_PINID='B';
NODE_NAME     PC109 2
 '@T6G_MB_LIB.T6G(SCH_1):PAGE177_I7@PURE_QUANTA.Q_CAP(CHIPS)':
 'B': CDS_PINID='B';
NODE_NAME     PC114_3 2
 '@T6G_MB_LIB.T6G(SCH_1):PAGE177_I12@PURE_QUANTA.Q_CAP(CHIPS)':
 'B': CDS_PINID='B';
NODE_NAME     PC111_C1P0_4 2
 '@T6G_MB_LIB.T6G(SCH_1):PAGE177_I16@PURE_QUANTA.Q_CAP(CHIPS)':
 'B': CDS_PINID='B';
NODE_NAME     PR86 2
 '@T6G_MB_LIB.T6G(SCH_1):PAGE177_I18@PURE_QUANTA.Q_RES(CHIPS)':
 'B': CDS_PINID='B';
NODE_NAME     PU14 2
 '@T6G_MB_LIB.T6G(SCH_1):PAGE177_I21@PURE_QUANTA.ISL99390FRZTR5935(CHIPS)':
 'AGND': CDS_PINID='AGND';
NODE_NAME     PU14 5
 '@T6G_MB_LIB.T6G(SCH_1):PAGE177_I21@PURE_QUANTA.ISL99390FRZTR5935(CHIPS)':
 'PGND1': CDS_PINID='PGND1';
NODE_NAME     PU14 7_9-20_24
 '@T6G_MB_LIB.T6G(SCH_1):PAGE177_I21@PURE_QUANTA.ISL99390FRZTR5935(CHIPS)':
 'PGND2': CDS_PINID='PGND2';
NODE_NAME     PU14 40
 '@T6G_MB_LIB.T6G(SCH_1):PAGE177_I21@PURE_QUANTA.ISL99390FRZTR5935(CHIPS)':
 'PGND3': CDS_PINID='PGND3';
NODE_NAME     PU15 2
 '@T6G_MB_LIB.T6G(SCH_1):PAGE177_I23@PURE_QUANTA.ISL99390FRZTR5935(CHIPS)':
 'AGND': CDS_PINID='AGND';
NODE_NAME     PU15 5
 '@T6G_MB_LIB.T6G(SCH_1):PAGE177_I23@PURE_QUANTA.ISL99390FRZTR5935(CHIPS)':
 'PGND1': CDS_PINID='PGND1';
NODE_NAME     PU15 7_9-20_24
 '@T6G_MB_LIB.T6G(SCH_1):PAGE177_I23@PURE_QUANTA.ISL99390FRZTR5935(CHIPS)':
 'PGND2': CDS_PINID='PGND2';
NODE_NAME     PU15 40
 '@T6G_MB_LIB.T6G(SCH_1):PAGE177_I23@PURE_QUANTA.ISL99390FRZTR5935(CHIPS)':
 'PGND3': CDS_PINID='PGND3';
NODE_NAME     PC115_4 2
 '@T6G_MB_LIB.T6G(SCH_1):PAGE177_I24@PURE_QUANTA.Q_CAP(CHIPS)':
 'B': CDS_PINID='B';
NODE_NAME     PC110 2
 '@T6G_MB_LIB.T6G(SCH_1):PAGE177_I28@PURE_QUANTA.Q_CAP(CHIPS)':
 'B': CDS_PINID='B';
NODE_NAME     PC112_C1P0_3 2
 '@T6G_MB_LIB.T6G(SCH_1):PAGE177_I32@PURE_QUANTA.Q_CAP(CHIPS)':
 'B': CDS_PINID='B';
NODE_NAME     PC116_3 2
 '@T6G_MB_LIB.T6G(SCH_1):PAGE177_I34@PURE_QUANTA.Q_CAP(CHIPS)':
 'B': CDS_PINID='B';
NODE_NAME     PR509 2
 '@T6G_MB_LIB.T6G(SCH_1):PAGE177_I36@PURE_QUANTA.Q_RES(CHIPS)':
 'B': CDS_PINID='B';
NODE_NAME     PC117_4 2
 '@T6G_MB_LIB.T6G(SCH_1):PAGE177_I43@PURE_QUANTA.Q_CAP(CHIPS)':
 'B': CDS_PINID='B';
NODE_NAME     PC119_4 2
 '@T6G_MB_LIB.T6G(SCH_1):PAGE177_I44@PURE_QUANTA.Q_CAP(CHIPS)':
 'B': CDS_PINID='B';
NODE_NAME     PR510 2
 '@T6G_MB_LIB.T6G(SCH_1):PAGE177_I46@PURE_QUANTA.Q_RES(CHIPS)':
 'B': CDS_PINID='B';
NODE_NAME     PC123_4 2
 '@T6G_MB_LIB.T6G(SCH_1):PAGE177_I47@PURE_QUANTA.Q_CAP(CHIPS)':
 'B': CDS_PINID='B';
NODE_NAME     PC125_4 2
 '@T6G_MB_LIB.T6G(SCH_1):PAGE177_I49@PURE_QUANTA.Q_CAP(CHIPS)':
 'B': CDS_PINID='B';
NODE_NAME     PC127_4 2
 '@T6G_MB_LIB.T6G(SCH_1):PAGE177_I54@PURE_QUANTA.Q_CAP(CHIPS)':
 'B': CDS_PINID='B';
NODE_NAME     PC118_3 2
 '@T6G_MB_LIB.T6G(SCH_1):PAGE177_I60@PURE_QUANTA.Q_CAP(CHIPS)':
 'B': CDS_PINID='B';
NODE_NAME     PC120_3 2
 '@T6G_MB_LIB.T6G(SCH_1):PAGE177_I61@PURE_QUANTA.Q_CAP(CHIPS)':
 'B': CDS_PINID='B';
NODE_NAME     PC124_3 2
 '@T6G_MB_LIB.T6G(SCH_1):PAGE177_I65@PURE_QUANTA.Q_CAP(CHIPS)':
 'B': CDS_PINID='B';
NODE_NAME     PC126_3 2
 '@T6G_MB_LIB.T6G(SCH_1):PAGE177_I66@PURE_QUANTA.Q_CAP(CHIPS)':
 'B': CDS_PINID='B';
NODE_NAME     PC129_3 2
 '@T6G_MB_LIB.T6G(SCH_1):PAGE177_I69@PURE_QUANTA.Q_CAP(CHIPS)':
 'B': CDS_PINID='B';
NODE_NAME     PC130_3 2
 '@T6G_MB_LIB.T6G(SCH_1):PAGE177_I71@PURE_QUANTA.Q_CAP(CHIPS)':
 'B': CDS_PINID='B';
NODE_NAME     PC111_6 2
 '@T6G_MB_LIB.T6G(SCH_1):PAGE178_I2@PURE_QUANTA.Q_CAP(CHIPS)':
 'B': CDS_PINID='B';
NODE_NAME     PR7 2
 '@T6G_MB_LIB.T6G(SCH_1):PAGE178_I4@PURE_QUANTA.Q_RES(CHIPS)':
 'B': CDS_PINID='B';
NODE_NAME     PC132_5 2
 '@T6G_MB_LIB.T6G(SCH_1):PAGE178_I10@PURE_QUANTA.Q_CAP(CHIPS)':
 'B': CDS_PINID='B';
NODE_NAME     PC112 2
 '@T6G_MB_LIB.T6G(SCH_1):PAGE178_I11@PURE_QUANTA.Q_CAP(CHIPS)':
 'B': CDS_PINID='B';
NODE_NAME     PR93 2
 '@T6G_MB_LIB.T6G(SCH_1):PAGE178_I15@PURE_QUANTA.Q_RES(CHIPS)':
 'B': CDS_PINID='B';
NODE_NAME     PC113_C1P0_6 2
 '@T6G_MB_LIB.T6G(SCH_1):PAGE178_I20@PURE_QUANTA.Q_CAP(CHIPS)':
 'B': CDS_PINID='B';
NODE_NAME     PU16 2
 '@T6G_MB_LIB.T6G(SCH_1):PAGE178_I22@PURE_QUANTA.ISL99390FRZTR5935(CHIPS)':
 'AGND': CDS_PINID='AGND';
NODE_NAME     PU16 5
 '@T6G_MB_LIB.T6G(SCH_1):PAGE178_I22@PURE_QUANTA.ISL99390FRZTR5935(CHIPS)':
 'PGND1': CDS_PINID='PGND1';
NODE_NAME     PU16 7_9-20_24
 '@T6G_MB_LIB.T6G(SCH_1):PAGE178_I22@PURE_QUANTA.ISL99390FRZTR5935(CHIPS)':
 'PGND2': CDS_PINID='PGND2';
NODE_NAME     PU16 40
 '@T6G_MB_LIB.T6G(SCH_1):PAGE178_I22@PURE_QUANTA.ISL99390FRZTR5935(CHIPS)':
 'PGND3': CDS_PINID='PGND3';
NODE_NAME     PC131 2
 '@T6G_MB_LIB.T6G(SCH_1):PAGE178_I27@PURE_QUANTA.Q_CAP(CHIPS)':
 'B': CDS_PINID='B';
NODE_NAME     PR155 2
 '@T6G_MB_LIB.T6G(SCH_1):PAGE178_I33@PURE_QUANTA.Q_RES(CHIPS)':
 'B': CDS_PINID='B';
NODE_NAME     PL9 2
 '@T6G_MB_LIB.T6G(SCH_1):PAGE178_I36@PURE_QUANTA.Q_INDUCTOR(CHIPS)':
 '2': CDS_PINID='\2\';
NODE_NAME     PC115_6 2
 '@T6G_MB_LIB.T6G(SCH_1):PAGE178_I41@PURE_QUANTA.Q_CAP(CHIPS)':
 'B': CDS_PINID='B';
NODE_NAME     PC116_6 2
 '@T6G_MB_LIB.T6G(SCH_1):PAGE178_I42@PURE_QUANTA.Q_CAP(CHIPS)':
 'B': CDS_PINID='B';
NODE_NAME     PR158 2
 '@T6G_MB_LIB.T6G(SCH_1):PAGE178_I44@PURE_QUANTA.Q_RES(CHIPS)':
 'B': CDS_PINID='B';
NODE_NAME     PC118_6 2
 '@T6G_MB_LIB.T6G(SCH_1):PAGE178_I45@PURE_QUANTA.Q_CAP(CHIPS)':
 'B': CDS_PINID='B';
NODE_NAME     PC119_6 2
 '@T6G_MB_LIB.T6G(SCH_1):PAGE178_I47@PURE_QUANTA.Q_CAP(CHIPS)':
 'B': CDS_PINID='B';
NODE_NAME     PC120_6 2
 '@T6G_MB_LIB.T6G(SCH_1):PAGE178_I51@PURE_QUANTA.Q_CAP(CHIPS)':
 'B': CDS_PINID='B';
NODE_NAME     PC123_6 2
 '@T6G_MB_LIB.T6G(SCH_1):PAGE178_I53@PURE_QUANTA.Q_CAP(CHIPS)':
 'B': CDS_PINID='B';
NODE_NAME     PC134_5 2
 '@T6G_MB_LIB.T6G(SCH_1):PAGE178_I58@PURE_QUANTA.Q_CAP(CHIPS)':
 'B': CDS_PINID='B';
NODE_NAME     PC138_5 2
 '@T6G_MB_LIB.T6G(SCH_1):PAGE178_I65@PURE_QUANTA.Q_CAP(CHIPS)':
 'B': CDS_PINID='B';
NODE_NAME     PC139_5 2
 '@T6G_MB_LIB.T6G(SCH_1):PAGE178_I66@PURE_QUANTA.Q_CAP(CHIPS)':
 'B': CDS_PINID='B';
NODE_NAME     PC140_5 2
 '@T6G_MB_LIB.T6G(SCH_1):PAGE178_I69@PURE_QUANTA.Q_CAP(CHIPS)':
 'B': CDS_PINID='B';
NODE_NAME     PC141_5 2
 '@T6G_MB_LIB.T6G(SCH_1):PAGE178_I70@PURE_QUANTA.Q_CAP(CHIPS)':
 'B': CDS_PINID='B';
NODE_NAME     PU11 2
 '@T6G_MB_LIB.T6G(SCH_1):PAGE178_I73@PURE_QUANTA.ISL99390FRZTR5935(CHIPS)':
 'AGND': CDS_PINID='AGND';
NODE_NAME     PU11 5
 '@T6G_MB_LIB.T6G(SCH_1):PAGE178_I73@PURE_QUANTA.ISL99390FRZTR5935(CHIPS)':
 'PGND1': CDS_PINID='PGND1';
NODE_NAME     PU11 7_9-20_24
 '@T6G_MB_LIB.T6G(SCH_1):PAGE178_I73@PURE_QUANTA.ISL99390FRZTR5935(CHIPS)':
 'PGND2': CDS_PINID='PGND2';
NODE_NAME     PU11 40
 '@T6G_MB_LIB.T6G(SCH_1):PAGE178_I73@PURE_QUANTA.ISL99390FRZTR5935(CHIPS)':
 'PGND3': CDS_PINID='PGND3';
NODE_NAME     PC146_8 2
 '@T6G_MB_LIB.T6G(SCH_1):PAGE180_I2@PURE_QUANTA.Q_CAP(CHIPS)':
 'B': CDS_PINID='B';
NODE_NAME     PR97 2
 '@T6G_MB_LIB.T6G(SCH_1):PAGE180_I4@PURE_QUANTA.Q_RES(CHIPS)':
 'B': CDS_PINID='B';
NODE_NAME     PC142 2
 '@T6G_MB_LIB.T6G(SCH_1):PAGE180_I10@PURE_QUANTA.Q_CAP(CHIPS)':
 'B': CDS_PINID='B';
NODE_NAME     PC144_IOP0_2 2
 '@T6G_MB_LIB.T6G(SCH_1):PAGE180_I13@PURE_QUANTA.Q_CAP(CHIPS)':
 'B': CDS_PINID='B';
NODE_NAME     PU18 2
 '@T6G_MB_LIB.T6G(SCH_1):PAGE180_I15@PURE_QUANTA.ISL99390FRZTR5935(CHIPS)':
 'AGND': CDS_PINID='AGND';
NODE_NAME     PU18 5
 '@T6G_MB_LIB.T6G(SCH_1):PAGE180_I15@PURE_QUANTA.ISL99390FRZTR5935(CHIPS)':
 'PGND1': CDS_PINID='PGND1';
NODE_NAME     PU18 7_9-20_24
 '@T6G_MB_LIB.T6G(SCH_1):PAGE180_I15@PURE_QUANTA.ISL99390FRZTR5935(CHIPS)':
 'PGND2': CDS_PINID='PGND2';
NODE_NAME     PU18 40
 '@T6G_MB_LIB.T6G(SCH_1):PAGE180_I15@PURE_QUANTA.ISL99390FRZTR5935(CHIPS)':
 'PGND3': CDS_PINID='PGND3';
NODE_NAME     PC149_2 2
 '@T6G_MB_LIB.T6G(SCH_1):PAGE180_I18@PURE_QUANTA.Q_CAP(CHIPS)':
 'B': CDS_PINID='B';
NODE_NAME     PC145_7 2
 '@T6G_MB_LIB.T6G(SCH_1):PAGE180_I20@PURE_QUANTA.Q_CAP(CHIPS)':
 'B': CDS_PINID='B';
NODE_NAME     PR98 2
 '@T6G_MB_LIB.T6G(SCH_1):PAGE180_I22@PURE_QUANTA.Q_RES(CHIPS)':
 'B': CDS_PINID='B';
NODE_NAME     PC143 2
 '@T6G_MB_LIB.T6G(SCH_1):PAGE180_I28@PURE_QUANTA.Q_CAP(CHIPS)':
 'B': CDS_PINID='B';
NODE_NAME     PC147_IOP0_1 2
 '@T6G_MB_LIB.T6G(SCH_1):PAGE180_I31@PURE_QUANTA.Q_CAP(CHIPS)':
 'B': CDS_PINID='B';
NODE_NAME     PR223 2
 '@T6G_MB_LIB.T6G(SCH_1):PAGE180_I36@PURE_QUANTA.Q_RES(CHIPS)':
 'B': CDS_PINID='B';
NODE_NAME     PC151_2 2
 '@T6G_MB_LIB.T6G(SCH_1):PAGE180_I42@PURE_QUANTA.Q_CAP(CHIPS)':
 'B': CDS_PINID='B';
NODE_NAME     PC153_2 2
 '@T6G_MB_LIB.T6G(SCH_1):PAGE180_I43@PURE_QUANTA.Q_CAP(CHIPS)':
 'B': CDS_PINID='B';
NODE_NAME     PC157_2 2
 '@T6G_MB_LIB.T6G(SCH_1):PAGE180_I45@PURE_QUANTA.Q_CAP(CHIPS)':
 'B': CDS_PINID='B';
NODE_NAME     PC159_2 2
 '@T6G_MB_LIB.T6G(SCH_1):PAGE180_I47@PURE_QUANTA.Q_CAP(CHIPS)':
 'B': CDS_PINID='B';
NODE_NAME     PC168_2 2
 '@T6G_MB_LIB.T6G(SCH_1):PAGE180_I51@PURE_QUANTA.Q_CAP(CHIPS)':
 'B': CDS_PINID='B';
NODE_NAME     PC170_2 2
 '@T6G_MB_LIB.T6G(SCH_1):PAGE180_I53@PURE_QUANTA.Q_CAP(CHIPS)':
 'B': CDS_PINID='B';
NODE_NAME     PC160 2
 '@T6G_MB_LIB.T6G(SCH_1):PAGE180_I54@PURE_QUANTA.Q_CAPP(CHIPS)':
 'B': CDS_PINID='B';
NODE_NAME     PC162 2
 '@T6G_MB_LIB.T6G(SCH_1):PAGE180_I57@PURE_QUANTA.Q_CAPP(CHIPS)':
 'B': CDS_PINID='B';
NODE_NAME     PC165 2
 '@T6G_MB_LIB.T6G(SCH_1):PAGE180_I58@PURE_QUANTA.Q_CAPP(CHIPS)':
 'B': CDS_PINID='B';
NODE_NAME     PR221 2
 '@T6G_MB_LIB.T6G(SCH_1):PAGE180_I60@PURE_QUANTA.Q_RES(CHIPS)':
 'B': CDS_PINID='B';
NODE_NAME     PL17 3
 '@T6G_MB_LIB.T6G(SCH_1):PAGE180_I64@PURE_QUANTA.Q_INDUCTOR4P_14(CHIPS)':
 '3': CDS_PINID='\3\';
NODE_NAME     PC158_1 2
 '@T6G_MB_LIB.T6G(SCH_1):PAGE180_I66@PURE_QUANTA.Q_CAP(CHIPS)':
 'B': CDS_PINID='B';
NODE_NAME     PC164 2
 '@T6G_MB_LIB.T6G(SCH_1):PAGE180_I67@PURE_QUANTA.Q_CAPP(CHIPS)':
 'B': CDS_PINID='B';
NODE_NAME     PC148 2
 '@T6G_MB_LIB.T6G(SCH_1):PAGE180_I72@PURE_QUANTA.Q_CAP(CHIPS)':
 'B': CDS_PINID='B';
NODE_NAME     PC107 2
 '@T6G_MB_LIB.T6G(SCH_1):PAGE180_I73@PURE_QUANTA.Q_CAP(CHIPS)':
 'B': CDS_PINID='B';
NODE_NAME     PC166_1 2
 '@T6G_MB_LIB.T6G(SCH_1):PAGE180_I74@PURE_QUANTA.Q_CAP(CHIPS)':
 'B': CDS_PINID='B';
NODE_NAME     PC169_1 2
 '@T6G_MB_LIB.T6G(SCH_1):PAGE180_I75@PURE_QUANTA.Q_CAP(CHIPS)':
 'B': CDS_PINID='B';
NODE_NAME     PR410 2
 '@T6G_MB_LIB.T6G(SCH_1):PAGE180_I78@PURE_QUANTA.Q_RES(CHIPS)':
 'B': CDS_PINID='B';
NODE_NAME     PC154_1 2
 '@T6G_MB_LIB.T6G(SCH_1):PAGE180_I80@PURE_QUANTA.Q_CAP(CHIPS)':
 'B': CDS_PINID='B';
NODE_NAME     PC152_1 2
 '@T6G_MB_LIB.T6G(SCH_1):PAGE180_I81@PURE_QUANTA.Q_CAP(CHIPS)':
 'B': CDS_PINID='B';
NODE_NAME     PC150_1 2
 '@T6G_MB_LIB.T6G(SCH_1):PAGE180_I82@PURE_QUANTA.Q_CAP(CHIPS)':
 'B': CDS_PINID='B';
NODE_NAME     PC148_1 2
 '@T6G_MB_LIB.T6G(SCH_1):PAGE180_I83@PURE_QUANTA.Q_CAP(CHIPS)':
 'B': CDS_PINID='B';
NODE_NAME     PU17 2
 '@T6G_MB_LIB.T6G(SCH_1):PAGE180_I84@PURE_QUANTA.ISL99390FRZTR5935(CHIPS)':
 'AGND': CDS_PINID='AGND';
NODE_NAME     PU17 5
 '@T6G_MB_LIB.T6G(SCH_1):PAGE180_I84@PURE_QUANTA.ISL99390FRZTR5935(CHIPS)':
 'PGND1': CDS_PINID='PGND1';
NODE_NAME     PU17 7_9-20_24
 '@T6G_MB_LIB.T6G(SCH_1):PAGE180_I84@PURE_QUANTA.ISL99390FRZTR5935(CHIPS)':
 'PGND2': CDS_PINID='PGND2';
NODE_NAME     PU17 40
 '@T6G_MB_LIB.T6G(SCH_1):PAGE180_I84@PURE_QUANTA.ISL99390FRZTR5935(CHIPS)':
 'PGND3': CDS_PINID='PGND3';
NODE_NAME     PC176_10 2
 '@T6G_MB_LIB.T6G(SCH_1):PAGE181_I1@PURE_QUANTA.Q_CAP(CHIPS)':
 'B': CDS_PINID='B';
NODE_NAME     PR105 2
 '@T6G_MB_LIB.T6G(SCH_1):PAGE181_I4@PURE_QUANTA.Q_RES(CHIPS)':
 'B': CDS_PINID='B';
NODE_NAME     PC171 2
 '@T6G_MB_LIB.T6G(SCH_1):PAGE181_I10@PURE_QUANTA.Q_CAP(CHIPS)':
 'B': CDS_PINID='B';
NODE_NAME     PC173_IOP0_4 2
 '@T6G_MB_LIB.T6G(SCH_1):PAGE181_I13@PURE_QUANTA.Q_CAP(CHIPS)':
 'B': CDS_PINID='B';
NODE_NAME     PC178_4 2
 '@T6G_MB_LIB.T6G(SCH_1):PAGE181_I17@PURE_QUANTA.Q_CAP(CHIPS)':
 'B': CDS_PINID='B';
NODE_NAME     PC175_9 2
 '@T6G_MB_LIB.T6G(SCH_1):PAGE181_I19@PURE_QUANTA.Q_CAP(CHIPS)':
 'B': CDS_PINID='B';
NODE_NAME     PR106 2
 '@T6G_MB_LIB.T6G(SCH_1):PAGE181_I21@PURE_QUANTA.Q_RES(CHIPS)':
 'B': CDS_PINID='B';
NODE_NAME     PC172 2
 '@T6G_MB_LIB.T6G(SCH_1):PAGE181_I27@PURE_QUANTA.Q_CAP(CHIPS)':
 'B': CDS_PINID='B';
NODE_NAME     PC174_IOP0_3 2
 '@T6G_MB_LIB.T6G(SCH_1):PAGE181_I30@PURE_QUANTA.Q_CAP(CHIPS)':
 'B': CDS_PINID='B';
NODE_NAME     PU19 2
 '@T6G_MB_LIB.T6G(SCH_1):PAGE181_I32@PURE_QUANTA.ISL99390FRZTR5935(CHIPS)':
 'AGND': CDS_PINID='AGND';
NODE_NAME     PU19 5
 '@T6G_MB_LIB.T6G(SCH_1):PAGE181_I32@PURE_QUANTA.ISL99390FRZTR5935(CHIPS)':
 'PGND1': CDS_PINID='PGND1';
NODE_NAME     PU19 7_9-20_24
 '@T6G_MB_LIB.T6G(SCH_1):PAGE181_I32@PURE_QUANTA.ISL99390FRZTR5935(CHIPS)':
 'PGND2': CDS_PINID='PGND2';
NODE_NAME     PU19 40
 '@T6G_MB_LIB.T6G(SCH_1):PAGE181_I32@PURE_QUANTA.ISL99390FRZTR5935(CHIPS)':
 'PGND3': CDS_PINID='PGND3';
NODE_NAME     PC177_3 2
 '@T6G_MB_LIB.T6G(SCH_1):PAGE181_I35@PURE_QUANTA.Q_CAP(CHIPS)':
 'B': CDS_PINID='B';
NODE_NAME     PC179_3 2
 '@T6G_MB_LIB.T6G(SCH_1):PAGE181_I36@PURE_QUANTA.Q_CAP(CHIPS)':
 'B': CDS_PINID='B';
NODE_NAME     PR291 2
 '@T6G_MB_LIB.T6G(SCH_1):PAGE181_I38@PURE_QUANTA.Q_RES(CHIPS)':
 'B': CDS_PINID='B';
NODE_NAME     PL16 2
 '@T6G_MB_LIB.T6G(SCH_1):PAGE181_I43@PURE_QUANTA.Q_INDUCTOR(CHIPS)':
 '2': CDS_PINID='\2\';
NODE_NAME     PC180_4 2
 '@T6G_MB_LIB.T6G(SCH_1):PAGE181_I45@PURE_QUANTA.Q_CAP(CHIPS)':
 'B': CDS_PINID='B';
NODE_NAME     PC185_4 2
 '@T6G_MB_LIB.T6G(SCH_1):PAGE181_I47@PURE_QUANTA.Q_CAP(CHIPS)':
 'B': CDS_PINID='B';
NODE_NAME     PC188_4 2
 '@T6G_MB_LIB.T6G(SCH_1):PAGE181_I49@PURE_QUANTA.Q_CAP(CHIPS)':
 'B': CDS_PINID='B';
NODE_NAME     PC189_4 2
 '@T6G_MB_LIB.T6G(SCH_1):PAGE181_I53@PURE_QUANTA.Q_CAP(CHIPS)':
 'B': CDS_PINID='B';
NODE_NAME     PC181_3 2
 '@T6G_MB_LIB.T6G(SCH_1):PAGE181_I58@PURE_QUANTA.Q_CAP(CHIPS)':
 'B': CDS_PINID='B';
NODE_NAME     PC184_3 2
 '@T6G_MB_LIB.T6G(SCH_1):PAGE181_I60@PURE_QUANTA.Q_CAP(CHIPS)':
 'B': CDS_PINID='B';
NODE_NAME     PC187_3 2
 '@T6G_MB_LIB.T6G(SCH_1):PAGE181_I63@PURE_QUANTA.Q_CAP(CHIPS)':
 'B': CDS_PINID='B';
NODE_NAME     PC190_3 2
 '@T6G_MB_LIB.T6G(SCH_1):PAGE181_I66@PURE_QUANTA.Q_CAP(CHIPS)':
 'B': CDS_PINID='B';
NODE_NAME     PU20 2
 '@T6G_MB_LIB.T6G(SCH_1):PAGE181_I73@PURE_QUANTA.ISL99390FRZTR5935(CHIPS)':
 'AGND': CDS_PINID='AGND';
NODE_NAME     PU20 5
 '@T6G_MB_LIB.T6G(SCH_1):PAGE181_I73@PURE_QUANTA.ISL99390FRZTR5935(CHIPS)':
 'PGND1': CDS_PINID='PGND1';
NODE_NAME     PU20 7_9-20_24
 '@T6G_MB_LIB.T6G(SCH_1):PAGE181_I73@PURE_QUANTA.ISL99390FRZTR5935(CHIPS)':
 'PGND2': CDS_PINID='PGND2';
NODE_NAME     PU20 40
 '@T6G_MB_LIB.T6G(SCH_1):PAGE181_I73@PURE_QUANTA.ISL99390FRZTR5935(CHIPS)':
 'PGND3': CDS_PINID='PGND3';
NODE_NAME     PC193 2
 '@T6G_MB_LIB.T6G(SCH_1):PAGE182_I4@PURE_QUANTA.Q_CAP(CHIPS)':
 'B': CDS_PINID='B';
NODE_NAME     PR3 2
 '@T6G_MB_LIB.T6G(SCH_1):PAGE182_I6@PURE_QUANTA.Q_RES(CHIPS)':
 'B': CDS_PINID='B';
NODE_NAME     PR115 2
 '@T6G_MB_LIB.T6G(SCH_1):PAGE182_I15@PURE_QUANTA.Q_RES(CHIPS)':
 'B': CDS_PINID='B';
NODE_NAME     PR601 2
 '@T6G_MB_LIB.T6G(SCH_1):PAGE182_I18@PURE_QUANTA.Q_RES(CHIPS)':
 'B': CDS_PINID='B';
NODE_NAME     PC5 2
 '@T6G_MB_LIB.T6G(SCH_1):PAGE182_I20@PURE_QUANTA.Q_CAP(CHIPS)':
 'B': CDS_PINID='B';
NODE_NAME     PR126 2
 '@T6G_MB_LIB.T6G(SCH_1):PAGE182_I22@PURE_QUANTA.Q_RES(CHIPS)':
 'B': CDS_PINID='B';
NODE_NAME     PU21 31
 '@T6G_MB_LIB.T6G(SCH_1):PAGE182_I24@PURE_QUANTA.RAA229621GNPHA0(CHIPS)':
 'RGND1': CDS_PINID='RGND1';
NODE_NAME     PU21 18
 '@T6G_MB_LIB.T6G(SCH_1):PAGE182_I24@PURE_QUANTA.RAA229621GNPHA0(CHIPS)':
 'SVC': CDS_PINID='SVC';
NODE_NAME     PU21 17
 '@T6G_MB_LIB.T6G(SCH_1):PAGE182_I24@PURE_QUANTA.RAA229621GNPHA0(CHIPS)':
 'SVD': CDS_PINID='SVD';
NODE_NAME     PU21 20
 '@T6G_MB_LIB.T6G(SCH_1):PAGE182_I24@PURE_QUANTA.RAA229621GNPHA0(CHIPS)':
 'SVTI': CDS_PINID='SVTI';
NODE_NAME     PU21 TH
 '@T6G_MB_LIB.T6G(SCH_1):PAGE182_I24@PURE_QUANTA.RAA229621GNPHA0(CHIPS)':
 'TH_GND': CDS_PINID='TH_GND';
NODE_NAME     PU21 32
 '@T6G_MB_LIB.T6G(SCH_1):PAGE182_I24@PURE_QUANTA.RAA229621GNPHA0(CHIPS)':
 'VSEN1': CDS_PINID='VSEN1';
NODE_NAME     C197 2
 '@T6G_MB_LIB.T6G(SCH_1):PAGE182_I45@PURE_QUANTA.Q_CAP(CHIPS)':
 'B': CDS_PINID='B';
NODE_NAME     PC198 2
 '@T6G_MB_LIB.T6G(SCH_1):PAGE182_I50@PURE_QUANTA.Q_CAP(CHIPS)':
 'B': CDS_PINID='B';
NODE_NAME     PR412 2
 '@T6G_MB_LIB.T6G(SCH_1):PAGE182_I52@PURE_QUANTA.Q_RES(CHIPS)':
 'B': CDS_PINID='B';
NODE_NAME     PR36 2
 '@T6G_MB_LIB.T6G(SCH_1):PAGE182_I53@PURE_QUANTA.Q_RES(CHIPS)':
 'B': CDS_PINID='B';
NODE_NAME     PR127 2
 '@T6G_MB_LIB.T6G(SCH_1):PAGE182_I57@PURE_QUANTA.Q_RES(CHIPS)':
 'B': CDS_PINID='B';
NODE_NAME     PR419 2
 '@T6G_MB_LIB.T6G(SCH_1):PAGE182_I58@PURE_QUANTA.Q_RES(CHIPS)':
 'B': CDS_PINID='B';
NODE_NAME     PR35 2
 '@T6G_MB_LIB.T6G(SCH_1):PAGE182_I59@PURE_QUANTA.Q_RES(CHIPS)':
 'B': CDS_PINID='B';
NODE_NAME     PR34 2
 '@T6G_MB_LIB.T6G(SCH_1):PAGE182_I60@PURE_QUANTA.Q_RES(CHIPS)':
 'B': CDS_PINID='B';
NODE_NAME     PR33 2
 '@T6G_MB_LIB.T6G(SCH_1):PAGE182_I61@PURE_QUANTA.Q_RES(CHIPS)':
 'B': CDS_PINID='B';
NODE_NAME     PR37 2
 '@T6G_MB_LIB.T6G(SCH_1):PAGE182_I71@PURE_QUANTA.Q_RES(CHIPS)':
 'B': CDS_PINID='B';
NODE_NAME     PC4 2
 '@T6G_MB_LIB.T6G(SCH_1):PAGE182_I79@PURE_QUANTA.Q_CAP(CHIPS)':
 'B': CDS_PINID='B';
NODE_NAME     PC199 2
 '@T6G_MB_LIB.T6G(SCH_1):PAGE182_I80@PURE_QUANTA.Q_CAP(CHIPS)':
 'B': CDS_PINID='B';
NODE_NAME     PC202_2 2
 '@T6G_MB_LIB.T6G(SCH_1):PAGE183_I7@PURE_QUANTA.Q_CAP(CHIPS)':
 'B': CDS_PINID='B';
NODE_NAME     PC204 2
 '@T6G_MB_LIB.T6G(SCH_1):PAGE183_I9@PURE_QUANTA.Q_CAP(CHIPS)':
 'B': CDS_PINID='B';
NODE_NAME     PR134 1
 '@T6G_MB_LIB.T6G(SCH_1):PAGE183_I11@PURE_QUANTA.Q_RES(CHIPS)':
 'A': CDS_PINID='A';
NODE_NAME     PU23 2
 '@T6G_MB_LIB.T6G(SCH_1):PAGE183_I13@PURE_QUANTA.ISL99390FRZTR5935(CHIPS)':
 'AGND': CDS_PINID='AGND';
NODE_NAME     PU23 5
 '@T6G_MB_LIB.T6G(SCH_1):PAGE183_I13@PURE_QUANTA.ISL99390FRZTR5935(CHIPS)':
 'PGND1': CDS_PINID='PGND1';
NODE_NAME     PU23 7_9-20_24
 '@T6G_MB_LIB.T6G(SCH_1):PAGE183_I13@PURE_QUANTA.ISL99390FRZTR5935(CHIPS)':
 'PGND2': CDS_PINID='PGND2';
NODE_NAME     PU23 40
 '@T6G_MB_LIB.T6G(SCH_1):PAGE183_I13@PURE_QUANTA.ISL99390FRZTR5935(CHIPS)':
 'PGND3': CDS_PINID='PGND3';
NODE_NAME     PC206_11P0_2 2
 '@T6G_MB_LIB.T6G(SCH_1):PAGE183_I17@PURE_QUANTA.Q_CAP(CHIPS)':
 'B': CDS_PINID='B';
NODE_NAME     PC212_2 2
 '@T6G_MB_LIB.T6G(SCH_1):PAGE183_I30@PURE_QUANTA.Q_CAP(CHIPS)':
 'B': CDS_PINID='B';
NODE_NAME     PC214_2 2
 '@T6G_MB_LIB.T6G(SCH_1):PAGE183_I31@PURE_QUANTA.Q_CAP(CHIPS)':
 'B': CDS_PINID='B';
NODE_NAME     PR482 2
 '@T6G_MB_LIB.T6G(SCH_1):PAGE183_I33@PURE_QUANTA.Q_RES(CHIPS)':
 'B': CDS_PINID='B';
NODE_NAME     PC203 2
 '@T6G_MB_LIB.T6G(SCH_1):PAGE183_I36@PURE_QUANTA.Q_CAP(CHIPS)':
 'B': CDS_PINID='B';
NODE_NAME     PC205_11P0_1 2
 '@T6G_MB_LIB.T6G(SCH_1):PAGE183_I42@PURE_QUANTA.Q_CAP(CHIPS)':
 'B': CDS_PINID='B';
NODE_NAME     PC207_1 2
 '@T6G_MB_LIB.T6G(SCH_1):PAGE183_I47@PURE_QUANTA.Q_CAP(CHIPS)':
 'B': CDS_PINID='B';
NODE_NAME     PC213_1 2
 '@T6G_MB_LIB.T6G(SCH_1):PAGE183_I49@PURE_QUANTA.Q_CAP(CHIPS)':
 'B': CDS_PINID='B';
NODE_NAME     PC216_2 2
 '@T6G_MB_LIB.T6G(SCH_1):PAGE183_I50@PURE_QUANTA.Q_CAP(CHIPS)':
 'B': CDS_PINID='B';
NODE_NAME     PC218_2 2
 '@T6G_MB_LIB.T6G(SCH_1):PAGE183_I54@PURE_QUANTA.Q_CAP(CHIPS)':
 'B': CDS_PINID='B';
NODE_NAME     PC223 2
 '@T6G_MB_LIB.T6G(SCH_1):PAGE183_I58@PURE_QUANTA.Q_CAPP(CHIPS)':
 'B': CDS_PINID='B';
NODE_NAME     PC226 2
 '@T6G_MB_LIB.T6G(SCH_1):PAGE183_I59@PURE_QUANTA.Q_CAPP(CHIPS)':
 'B': CDS_PINID='B';
NODE_NAME     PC225_2 2
 '@T6G_MB_LIB.T6G(SCH_1):PAGE183_I62@PURE_QUANTA.Q_CAP(CHIPS)':
 'B': CDS_PINID='B';
NODE_NAME     PC228 2
 '@T6G_MB_LIB.T6G(SCH_1):PAGE183_I65@PURE_QUANTA.Q_CAPP(CHIPS)':
 'B': CDS_PINID='B';
NODE_NAME     PC220 2
 '@T6G_MB_LIB.T6G(SCH_1):PAGE183_I75@PURE_QUANTA.Q_CAPP(CHIPS)':
 'B': CDS_PINID='B';
NODE_NAME     PC222 2
 '@T6G_MB_LIB.T6G(SCH_1):PAGE183_I76@PURE_QUANTA.Q_CAP(CHIPS)':
 'B': CDS_PINID='B';
NODE_NAME     PC227_1 2
 '@T6G_MB_LIB.T6G(SCH_1):PAGE183_I82@PURE_QUANTA.Q_CAP(CHIPS)':
 'B': CDS_PINID='B';
NODE_NAME     PR414 2
 '@T6G_MB_LIB.T6G(SCH_1):PAGE183_I83@PURE_QUANTA.Q_RES(CHIPS)':
 'B': CDS_PINID='B';
NODE_NAME     PC215_1 2
 '@T6G_MB_LIB.T6G(SCH_1):PAGE183_I87@PURE_QUANTA.Q_CAP(CHIPS)':
 'B': CDS_PINID='B';
NODE_NAME     PC219_1 2
 '@T6G_MB_LIB.T6G(SCH_1):PAGE183_I88@PURE_QUANTA.Q_CAP(CHIPS)':
 'B': CDS_PINID='B';
NODE_NAME     PC800 2
 '@T6G_MB_LIB.T6G(SCH_1):PAGE183_I89@PURE_QUANTA.Q_CAPP(CHIPS)':
 'B': CDS_PINID='B';
NODE_NAME     PC221_2 2
 '@T6G_MB_LIB.T6G(SCH_1):PAGE183_I90@PURE_QUANTA.Q_CAP(CHIPS)':
 'B': CDS_PINID='B';
NODE_NAME     PU22 2
 '@T6G_MB_LIB.T6G(SCH_1):PAGE183_I92@PURE_QUANTA.ISL99390FRZTR5935(CHIPS)':
 'AGND': CDS_PINID='AGND';
NODE_NAME     PU22 5
 '@T6G_MB_LIB.T6G(SCH_1):PAGE183_I92@PURE_QUANTA.ISL99390FRZTR5935(CHIPS)':
 'PGND1': CDS_PINID='PGND1';
NODE_NAME     PU22 7_9-20_24
 '@T6G_MB_LIB.T6G(SCH_1):PAGE183_I92@PURE_QUANTA.ISL99390FRZTR5935(CHIPS)':
 'PGND2': CDS_PINID='PGND2';
NODE_NAME     PU22 40
 '@T6G_MB_LIB.T6G(SCH_1):PAGE183_I92@PURE_QUANTA.ISL99390FRZTR5935(CHIPS)':
 'PGND3': CDS_PINID='PGND3';
NODE_NAME     C674 2
 '@T6G_MB_LIB.T6G(SCH_1):PAGE184_I4@PURE_QUANTA.Q_CAP(CHIPS)':
 'B': CDS_PINID='B';
NODE_NAME     PC6001 2
 '@T6G_MB_LIB.T6G(SCH_1):PAGE184_I5@PURE_QUANTA.Q_CAP(CHIPS)':
 'B': CDS_PINID='B';
NODE_NAME     PC111 2
 '@T6G_MB_LIB.T6G(SCH_1):PAGE184_I8@PURE_QUANTA.Q_CAP(CHIPS)':
 'B': CDS_PINID='B';
NODE_NAME     PC212 2
 '@T6G_MB_LIB.T6G(SCH_1):PAGE184_I11@PURE_QUANTA.Q_CAP(CHIPS)':
 'B': CDS_PINID='B';
NODE_NAME     PR417 1
 '@T6G_MB_LIB.T6G(SCH_1):PAGE184_I15@PURE_QUANTA.Q_RES(CHIPS)':
 'A': CDS_PINID='A';
NODE_NAME     PR448 2
 '@T6G_MB_LIB.T6G(SCH_1):PAGE184_I17@PURE_QUANTA.Q_RES(CHIPS)':
 'B': CDS_PINID='B';
NODE_NAME     PU57 2
 '@T6G_MB_LIB.T6G(SCH_1):PAGE184_I18@PURE_QUANTA.MPQ8633BGLEC838Z(CHIPS)':
 'AGND': CDS_PINID='AGND';
NODE_NAME     PU57 11_18
 '@T6G_MB_LIB.T6G(SCH_1):PAGE184_I18@PURE_QUANTA.MPQ8633BGLEC838Z(CHIPS)':
 'PGND': CDS_PINID='PGND';
NODE_NAME     PC258 2
 '@T6G_MB_LIB.T6G(SCH_1):PAGE184_I21@PURE_QUANTA.Q_CAP(CHIPS)':
 'B': CDS_PINID='B';
NODE_NAME     PC227 2
 '@T6G_MB_LIB.T6G(SCH_1):PAGE184_I25@PURE_QUANTA.Q_CAP(CHIPS)':
 'B': CDS_PINID='B';
NODE_NAME     PC254 2
 '@T6G_MB_LIB.T6G(SCH_1):PAGE184_I26@PURE_QUANTA.Q_CAP(CHIPS)':
 'B': CDS_PINID='B';
NODE_NAME     PC81 2
 '@T6G_MB_LIB.T6G(SCH_1):PAGE184_I27@PURE_QUANTA.Q_CAP(CHIPS)':
 'B': CDS_PINID='B';
NODE_NAME     PC237 2
 '@T6G_MB_LIB.T6G(SCH_1):PAGE184_I28@PURE_QUANTA.Q_CAP(CHIPS)':
 'B': CDS_PINID='B';
NODE_NAME     PR418 1
 '@T6G_MB_LIB.T6G(SCH_1):PAGE184_I31@PURE_QUANTA.Q_RES(CHIPS)':
 'A': CDS_PINID='A';
NODE_NAME     PC114 2
 '@T6G_MB_LIB.T6G(SCH_1):PAGE184_I39@PURE_QUANTA.Q_CAP(CHIPS)':
 'B': CDS_PINID='B';
NODE_NAME     PC288 2
 '@T6G_MB_LIB.T6G(SCH_1):PAGE184_I40@PURE_QUANTA.Q_CAP(CHIPS)':
 'B': CDS_PINID='B';
NODE_NAME     PC260 2
 '@T6G_MB_LIB.T6G(SCH_1):PAGE184_I41@PURE_QUANTA.Q_CAP(CHIPS)':
 'B': CDS_PINID='B';
NODE_NAME     PC261 2
 '@T6G_MB_LIB.T6G(SCH_1):PAGE184_I46@PURE_QUANTA.Q_CAP(CHIPS)':
 'B': CDS_PINID='B';
NODE_NAME     PC115 2
 '@T6G_MB_LIB.T6G(SCH_1):PAGE184_I47@PURE_QUANTA.Q_CAPP(CHIPS)':
 'B': CDS_PINID='B';
NODE_NAME     PC215 2
 '@T6G_MB_LIB.T6G(SCH_1):PAGE184_I48@PURE_QUANTA.Q_CAP(CHIPS)':
 'B': CDS_PINID='B';
NODE_NAME     PR439 2
 '@T6G_MB_LIB.T6G(SCH_1):PAGE184_I51@PURE_QUANTA.Q_RES(CHIPS)':
 'B': CDS_PINID='B';
NODE_NAME     PC285 2
 '@T6G_MB_LIB.T6G(SCH_1):PAGE184_I54@PURE_QUANTA.Q_CAP(CHIPS)':
 'B': CDS_PINID='B';
NODE_NAME     R8153 2
 '@T6G_MB_LIB.T6G(SCH_1):PAGE185_I6@PURE_QUANTA.Q_RES(CHIPS)':
 'B': CDS_PINID='B';
NODE_NAME     PQ15 S
 '@T6G_MB_LIB.T6G(SCH_1):PAGE185_I16@PURE_QUANTA.MOSFET_N(CHIPS)':
 'SOURCE': CDS_PINID='SOURCE';
NODE_NAME     PR4 2
 '@T6G_MB_LIB.T6G(SCH_1):PAGE185_I20@PURE_QUANTA.Q_RES(CHIPS)':
 'B': CDS_PINID='B';
NODE_NAME     PC243 2
 '@T6G_MB_LIB.T6G(SCH_1):PAGE185_I22@PURE_QUANTA.Q_CAP(CHIPS)':
 'B': CDS_PINID='B';
NODE_NAME     PR162 2
 '@T6G_MB_LIB.T6G(SCH_1):PAGE185_I45@PURE_QUANTA.Q_RES(CHIPS)':
 'B': CDS_PINID='B';
NODE_NAME     PR602 2
 '@T6G_MB_LIB.T6G(SCH_1):PAGE185_I48@PURE_QUANTA.Q_RES(CHIPS)':
 'B': CDS_PINID='B';
NODE_NAME     PC6 2
 '@T6G_MB_LIB.T6G(SCH_1):PAGE185_I51@PURE_QUANTA.Q_CAP(CHIPS)':
 'B': CDS_PINID='B';
NODE_NAME     C8246 2
 '@T6G_MB_LIB.T6G(SCH_1):PAGE185_I52@PURE_QUANTA.Q_CAP(CHIPS)':
 'B': CDS_PINID='B';
NODE_NAME     C296 2
 '@T6G_MB_LIB.T6G(SCH_1):PAGE185_I64@PURE_QUANTA.Q_CAP(CHIPS)':
 'B': CDS_PINID='B';
NODE_NAME     C297 2
 '@T6G_MB_LIB.T6G(SCH_1):PAGE185_I66@PURE_QUANTA.Q_CAP(CHIPS)':
 'B': CDS_PINID='B';
NODE_NAME     PC250 2
 '@T6G_MB_LIB.T6G(SCH_1):PAGE185_I91@PURE_QUANTA.Q_CAP(CHIPS)':
 'B': CDS_PINID='B';
NODE_NAME     PC253 2
 '@T6G_MB_LIB.T6G(SCH_1):PAGE185_I94@PURE_QUANTA.Q_CAP(CHIPS)':
 'B': CDS_PINID='B';
NODE_NAME     PR437 2
 '@T6G_MB_LIB.T6G(SCH_1):PAGE185_I102@PURE_QUANTA.Q_RES(CHIPS)':
 'B': CDS_PINID='B';
NODE_NAME     PR436 2
 '@T6G_MB_LIB.T6G(SCH_1):PAGE185_I103@PURE_QUANTA.Q_RES(CHIPS)':
 'B': CDS_PINID='B';
NODE_NAME     PR530 2
 '@T6G_MB_LIB.T6G(SCH_1):PAGE185_I107@PURE_QUANTA.Q_RES(CHIPS)':
 'B': CDS_PINID='B';
NODE_NAME     PC10 2
 '@T6G_MB_LIB.T6G(SCH_1):PAGE185_I116@PURE_QUANTA.Q_CAP(CHIPS)':
 'B': CDS_PINID='B';
NODE_NAME     PC251 2
 '@T6G_MB_LIB.T6G(SCH_1):PAGE185_I125@PURE_QUANTA.Q_CAP(CHIPS)':
 'B': CDS_PINID='B';
NODE_NAME     PC252 2
 '@T6G_MB_LIB.T6G(SCH_1):PAGE185_I127@PURE_QUANTA.Q_CAP(CHIPS)':
 'B': CDS_PINID='B';
NODE_NAME     PC247 2
 '@T6G_MB_LIB.T6G(SCH_1):PAGE185_I132@PURE_QUANTA.Q_CAP(CHIPS)':
 'B': CDS_PINID='B';
NODE_NAME     PU25 TH
 '@T6G_MB_LIB.T6G(SCH_1):PAGE185_I133@PURE_QUANTA.RAA229620GNPHA0(CHIPS)':
 'TH_GND': CDS_PINID='TH_GND';
NODE_NAME     PC255_2 2
 '@T6G_MB_LIB.T6G(SCH_1):PAGE186_I5@PURE_QUANTA.Q_CAP(CHIPS)':
 'B': CDS_PINID='B';
NODE_NAME     PC257 2
 '@T6G_MB_LIB.T6G(SCH_1):PAGE186_I9@PURE_QUANTA.Q_CAP(CHIPS)':
 'B': CDS_PINID='B';
NODE_NAME     PR486 2
 '@T6G_MB_LIB.T6G(SCH_1):PAGE186_I22@PURE_QUANTA.Q_RES(CHIPS)':
 'B': CDS_PINID='B';
NODE_NAME     PC261_2 2
 '@T6G_MB_LIB.T6G(SCH_1):PAGE186_I25@PURE_QUANTA.Q_CAP(CHIPS)':
 'B': CDS_PINID='B';
NODE_NAME     PC265_2 2
 '@T6G_MB_LIB.T6G(SCH_1):PAGE186_I28@PURE_QUANTA.Q_CAP(CHIPS)':
 'B': CDS_PINID='B';
NODE_NAME     PC267_2 2
 '@T6G_MB_LIB.T6G(SCH_1):PAGE186_I29@PURE_QUANTA.Q_CAP(CHIPS)':
 'B': CDS_PINID='B';
NODE_NAME     PR485 2
 '@T6G_MB_LIB.T6G(SCH_1):PAGE186_I34@PURE_QUANTA.Q_RES(CHIPS)':
 'B': CDS_PINID='B';
NODE_NAME     PC256 2
 '@T6G_MB_LIB.T6G(SCH_1):PAGE186_I36@PURE_QUANTA.Q_CAP(CHIPS)':
 'B': CDS_PINID='B';
NODE_NAME     PR187 1
 '@T6G_MB_LIB.T6G(SCH_1):PAGE186_I37@PURE_QUANTA.Q_RES(CHIPS)':
 'A': CDS_PINID='A';
NODE_NAME     PC258_C0P1_1 2
 '@T6G_MB_LIB.T6G(SCH_1):PAGE186_I44@PURE_QUANTA.Q_CAP(CHIPS)':
 'B': CDS_PINID='B';
NODE_NAME     PC262_1 2
 '@T6G_MB_LIB.T6G(SCH_1):PAGE186_I47@PURE_QUANTA.Q_CAP(CHIPS)':
 'B': CDS_PINID='B';
NODE_NAME     PC264_1 2
 '@T6G_MB_LIB.T6G(SCH_1):PAGE186_I51@PURE_QUANTA.Q_CAP(CHIPS)':
 'B': CDS_PINID='B';
NODE_NAME     PC266_1 2
 '@T6G_MB_LIB.T6G(SCH_1):PAGE186_I52@PURE_QUANTA.Q_CAP(CHIPS)':
 'B': CDS_PINID='B';
NODE_NAME     PC268_1 2
 '@T6G_MB_LIB.T6G(SCH_1):PAGE186_I53@PURE_QUANTA.Q_CAP(CHIPS)':
 'B': CDS_PINID='B';
NODE_NAME     PC275 2
 '@T6G_MB_LIB.T6G(SCH_1):PAGE186_I58@PURE_QUANTA.Q_CAPP(CHIPS)':
 'B': CDS_PINID='B';
NODE_NAME     PC276 2
 '@T6G_MB_LIB.T6G(SCH_1):PAGE186_I59@PURE_QUANTA.Q_CAPP(CHIPS)':
 'B': CDS_PINID='B';
NODE_NAME     PC277 2
 '@T6G_MB_LIB.T6G(SCH_1):PAGE186_I60@PURE_QUANTA.Q_CAPP(CHIPS)':
 'B': CDS_PINID='B';
NODE_NAME     PC280_2 2
 '@T6G_MB_LIB.T6G(SCH_1):PAGE186_I61@PURE_QUANTA.Q_CAP(CHIPS)':
 'B': CDS_PINID='B';
NODE_NAME     PC272 2
 '@T6G_MB_LIB.T6G(SCH_1):PAGE186_I70@PURE_QUANTA.Q_CAPP(CHIPS)':
 'B': CDS_PINID='B';
NODE_NAME     PC6004 2
 '@T6G_MB_LIB.T6G(SCH_1):PAGE186_I74@PURE_QUANTA.Q_CAP(CHIPS)':
 'B': CDS_PINID='B';
NODE_NAME     PC281_1 2
 '@T6G_MB_LIB.T6G(SCH_1):PAGE186_I76@PURE_QUANTA.Q_CAP(CHIPS)':
 'B': CDS_PINID='B';
NODE_NAME     PC283_1 2
 '@T6G_MB_LIB.T6G(SCH_1):PAGE186_I77@PURE_QUANTA.Q_CAP(CHIPS)':
 'B': CDS_PINID='B';
NODE_NAME     PR337 2
 '@T6G_MB_LIB.T6G(SCH_1):PAGE186_I78@PURE_QUANTA.Q_RES(CHIPS)':
 'B': CDS_PINID='B';
NODE_NAME     PR188 1
 '@T6G_MB_LIB.T6G(SCH_1):PAGE186_I80@PURE_QUANTA.Q_RES(CHIPS)':
 'A': CDS_PINID='A';
NODE_NAME     PC105 2
 '@T6G_MB_LIB.T6G(SCH_1):PAGE186_I84@PURE_QUANTA.Q_CAPP(CHIPS)':
 'B': CDS_PINID='B';
NODE_NAME     PC278 2
 '@T6G_MB_LIB.T6G(SCH_1):PAGE186_I85@PURE_QUANTA.Q_CAP(CHIPS)':
 'B': CDS_PINID='B';
NODE_NAME     PU4 2
 '@T6G_MB_LIB.T6G(SCH_1):PAGE186_I88@PURE_QUANTA.ISL99390FRZTR5935(CHIPS)':
 'AGND': CDS_PINID='AGND';
NODE_NAME     PU4 5
 '@T6G_MB_LIB.T6G(SCH_1):PAGE186_I88@PURE_QUANTA.ISL99390FRZTR5935(CHIPS)':
 'PGND1': CDS_PINID='PGND1';
NODE_NAME     PU4 7_9-20_24
 '@T6G_MB_LIB.T6G(SCH_1):PAGE186_I88@PURE_QUANTA.ISL99390FRZTR5935(CHIPS)':
 'PGND2': CDS_PINID='PGND2';
NODE_NAME     PU4 40
 '@T6G_MB_LIB.T6G(SCH_1):PAGE186_I88@PURE_QUANTA.ISL99390FRZTR5935(CHIPS)':
 'PGND3': CDS_PINID='PGND3';
NODE_NAME     PU26 2
 '@T6G_MB_LIB.T6G(SCH_1):PAGE186_I91@PURE_QUANTA.ISL99390FRZTR5935(CHIPS)':
 'AGND': CDS_PINID='AGND';
NODE_NAME     PU26 5
 '@T6G_MB_LIB.T6G(SCH_1):PAGE186_I91@PURE_QUANTA.ISL99390FRZTR5935(CHIPS)':
 'PGND1': CDS_PINID='PGND1';
NODE_NAME     PU26 7_9-20_24
 '@T6G_MB_LIB.T6G(SCH_1):PAGE186_I91@PURE_QUANTA.ISL99390FRZTR5935(CHIPS)':
 'PGND2': CDS_PINID='PGND2';
NODE_NAME     PU26 40
 '@T6G_MB_LIB.T6G(SCH_1):PAGE186_I91@PURE_QUANTA.ISL99390FRZTR5935(CHIPS)':
 'PGND3': CDS_PINID='PGND3';
NODE_NAME     PC285_4 2
 '@T6G_MB_LIB.T6G(SCH_1):PAGE187_I2@PURE_QUANTA.Q_CAP(CHIPS)':
 'B': CDS_PINID='B';
NODE_NAME     PC287 2
 '@T6G_MB_LIB.T6G(SCH_1):PAGE187_I6@PURE_QUANTA.Q_CAP(CHIPS)':
 'B': CDS_PINID='B';
NODE_NAME     PU28 2
 '@T6G_MB_LIB.T6G(SCH_1):PAGE187_I9@PURE_QUANTA.ISL99390FRZTR5935(CHIPS)':
 'AGND': CDS_PINID='AGND';
NODE_NAME     PU28 5
 '@T6G_MB_LIB.T6G(SCH_1):PAGE187_I9@PURE_QUANTA.ISL99390FRZTR5935(CHIPS)':
 'PGND1': CDS_PINID='PGND1';
NODE_NAME     PU28 7_9-20_24
 '@T6G_MB_LIB.T6G(SCH_1):PAGE187_I9@PURE_QUANTA.ISL99390FRZTR5935(CHIPS)':
 'PGND2': CDS_PINID='PGND2';
NODE_NAME     PU28 40
 '@T6G_MB_LIB.T6G(SCH_1):PAGE187_I9@PURE_QUANTA.ISL99390FRZTR5935(CHIPS)':
 'PGND3': CDS_PINID='PGND3';
NODE_NAME     PR196 1
 '@T6G_MB_LIB.T6G(SCH_1):PAGE187_I11@PURE_QUANTA.Q_RES(CHIPS)':
 'A': CDS_PINID='A';
NODE_NAME     PC289_C0P1_4 2
 '@T6G_MB_LIB.T6G(SCH_1):PAGE187_I15@PURE_QUANTA.Q_CAP(CHIPS)':
 'B': CDS_PINID='B';
NODE_NAME     PR523 2
 '@T6G_MB_LIB.T6G(SCH_1):PAGE187_I19@PURE_QUANTA.Q_RES(CHIPS)':
 'B': CDS_PINID='B';
NODE_NAME     PC293_4 2
 '@T6G_MB_LIB.T6G(SCH_1):PAGE187_I22@PURE_QUANTA.Q_CAP(CHIPS)':
 'B': CDS_PINID='B';
NODE_NAME     PC291_4 2
 '@T6G_MB_LIB.T6G(SCH_1):PAGE187_I23@PURE_QUANTA.Q_CAP(CHIPS)':
 'B': CDS_PINID='B';
NODE_NAME     PC295_4 2
 '@T6G_MB_LIB.T6G(SCH_1):PAGE187_I24@PURE_QUANTA.Q_CAP(CHIPS)':
 'B': CDS_PINID='B';
NODE_NAME     PC297_4 2
 '@T6G_MB_LIB.T6G(SCH_1):PAGE187_I25@PURE_QUANTA.Q_CAP(CHIPS)':
 'B': CDS_PINID='B';
NODE_NAME     PC284_3 2
 '@T6G_MB_LIB.T6G(SCH_1):PAGE187_I28@PURE_QUANTA.Q_CAP(CHIPS)':
 'B': CDS_PINID='B';
NODE_NAME     PR195 1
 '@T6G_MB_LIB.T6G(SCH_1):PAGE187_I34@PURE_QUANTA.Q_RES(CHIPS)':
 'A': CDS_PINID='A';
NODE_NAME     PC286 2
 '@T6G_MB_LIB.T6G(SCH_1):PAGE187_I37@PURE_QUANTA.Q_CAP(CHIPS)':
 'B': CDS_PINID='B';
NODE_NAME     PU27 2
 '@T6G_MB_LIB.T6G(SCH_1):PAGE187_I39@PURE_QUANTA.ISL99390FRZTR5935(CHIPS)':
 'AGND': CDS_PINID='AGND';
NODE_NAME     PU27 5
 '@T6G_MB_LIB.T6G(SCH_1):PAGE187_I39@PURE_QUANTA.ISL99390FRZTR5935(CHIPS)':
 'PGND1': CDS_PINID='PGND1';
NODE_NAME     PU27 7_9-20_24
 '@T6G_MB_LIB.T6G(SCH_1):PAGE187_I39@PURE_QUANTA.ISL99390FRZTR5935(CHIPS)':
 'PGND2': CDS_PINID='PGND2';
NODE_NAME     PU27 40
 '@T6G_MB_LIB.T6G(SCH_1):PAGE187_I39@PURE_QUANTA.ISL99390FRZTR5935(CHIPS)':
 'PGND3': CDS_PINID='PGND3';
NODE_NAME     PC288_C0P1_3 2
 '@T6G_MB_LIB.T6G(SCH_1):PAGE187_I41@PURE_QUANTA.Q_CAP(CHIPS)':
 'B': CDS_PINID='B';
NODE_NAME     PC290_3 2
 '@T6G_MB_LIB.T6G(SCH_1):PAGE187_I44@PURE_QUANTA.Q_CAP(CHIPS)':
 'B': CDS_PINID='B';
NODE_NAME     PR522 2
 '@T6G_MB_LIB.T6G(SCH_1):PAGE187_I45@PURE_QUANTA.Q_RES(CHIPS)':
 'B': CDS_PINID='B';
NODE_NAME     PC292_3 2
 '@T6G_MB_LIB.T6G(SCH_1):PAGE187_I48@PURE_QUANTA.Q_CAP(CHIPS)':
 'B': CDS_PINID='B';
NODE_NAME     PC294_3 2
 '@T6G_MB_LIB.T6G(SCH_1):PAGE187_I49@PURE_QUANTA.Q_CAP(CHIPS)':
 'B': CDS_PINID='B';
NODE_NAME     PC296_3 2
 '@T6G_MB_LIB.T6G(SCH_1):PAGE187_I50@PURE_QUANTA.Q_CAP(CHIPS)':
 'B': CDS_PINID='B';
NODE_NAME     PL32 3
 '@T6G_MB_LIB.T6G(SCH_1):PAGE187_I53@PURE_QUANTA.Q_INDUCTOR4P_14(CHIPS)':
 '3': CDS_PINID='\3\';
NODE_NAME     PC299_4 2
 '@T6G_MB_LIB.T6G(SCH_1):PAGE187_I55@PURE_QUANTA.Q_CAP(CHIPS)':
 'B': CDS_PINID='B';
NODE_NAME     PC303_4 2
 '@T6G_MB_LIB.T6G(SCH_1):PAGE187_I58@PURE_QUANTA.Q_CAP(CHIPS)':
 'B': CDS_PINID='B';
NODE_NAME     PC305_4 2
 '@T6G_MB_LIB.T6G(SCH_1):PAGE187_I60@PURE_QUANTA.Q_CAP(CHIPS)':
 'B': CDS_PINID='B';
NODE_NAME     PC298_3 2
 '@T6G_MB_LIB.T6G(SCH_1):PAGE187_I65@PURE_QUANTA.Q_CAP(CHIPS)':
 'B': CDS_PINID='B';
NODE_NAME     PC302_3 2
 '@T6G_MB_LIB.T6G(SCH_1):PAGE187_I69@PURE_QUANTA.Q_CAP(CHIPS)':
 'B': CDS_PINID='B';
NODE_NAME     PC304_3 2
 '@T6G_MB_LIB.T6G(SCH_1):PAGE187_I71@PURE_QUANTA.Q_CAP(CHIPS)':
 'B': CDS_PINID='B';
NODE_NAME     PC124_6 2
 '@T6G_MB_LIB.T6G(SCH_1):PAGE188_I4@PURE_QUANTA.Q_CAP(CHIPS)':
 'B': CDS_PINID='B';
NODE_NAME     PR423 1
 '@T6G_MB_LIB.T6G(SCH_1):PAGE188_I8@PURE_QUANTA.Q_RES(CHIPS)':
 'A': CDS_PINID='A';
NODE_NAME     PC125 2
 '@T6G_MB_LIB.T6G(SCH_1):PAGE188_I10@PURE_QUANTA.Q_CAP(CHIPS)':
 'B': CDS_PINID='B';
NODE_NAME     PC126_C0P1_6 2
 '@T6G_MB_LIB.T6G(SCH_1):PAGE188_I15@PURE_QUANTA.Q_CAP(CHIPS)':
 'B': CDS_PINID='B';
NODE_NAME     PU29 2
 '@T6G_MB_LIB.T6G(SCH_1):PAGE188_I18@PURE_QUANTA.ISL99390FRZTR5935(CHIPS)':
 'AGND': CDS_PINID='AGND';
NODE_NAME     PU29 5
 '@T6G_MB_LIB.T6G(SCH_1):PAGE188_I18@PURE_QUANTA.ISL99390FRZTR5935(CHIPS)':
 'PGND1': CDS_PINID='PGND1';
NODE_NAME     PU29 7_9-20_24
 '@T6G_MB_LIB.T6G(SCH_1):PAGE188_I18@PURE_QUANTA.ISL99390FRZTR5935(CHIPS)':
 'PGND2': CDS_PINID='PGND2';
NODE_NAME     PU29 40
 '@T6G_MB_LIB.T6G(SCH_1):PAGE188_I18@PURE_QUANTA.ISL99390FRZTR5935(CHIPS)':
 'PGND3': CDS_PINID='PGND3';
NODE_NAME     PR524 2
 '@T6G_MB_LIB.T6G(SCH_1):PAGE188_I21@PURE_QUANTA.Q_RES(CHIPS)':
 'B': CDS_PINID='B';
NODE_NAME     PC127_6 2
 '@T6G_MB_LIB.T6G(SCH_1):PAGE188_I25@PURE_QUANTA.Q_CAP(CHIPS)':
 'B': CDS_PINID='B';
NODE_NAME     PC128_6 2
 '@T6G_MB_LIB.T6G(SCH_1):PAGE188_I27@PURE_QUANTA.Q_CAP(CHIPS)':
 'B': CDS_PINID='B';
NODE_NAME     PC129_6 2
 '@T6G_MB_LIB.T6G(SCH_1):PAGE188_I29@PURE_QUANTA.Q_CAP(CHIPS)':
 'B': CDS_PINID='B';
NODE_NAME     PC130_6 2
 '@T6G_MB_LIB.T6G(SCH_1):PAGE188_I30@PURE_QUANTA.Q_CAP(CHIPS)':
 'B': CDS_PINID='B';
NODE_NAME     PR46 2
 '@T6G_MB_LIB.T6G(SCH_1):PAGE188_I32@PURE_QUANTA.Q_RES(CHIPS)':
 'B': CDS_PINID='B';
NODE_NAME     PC306_5 2
 '@T6G_MB_LIB.T6G(SCH_1):PAGE188_I34@PURE_QUANTA.Q_CAP(CHIPS)':
 'B': CDS_PINID='B';
NODE_NAME     PR202 1
 '@T6G_MB_LIB.T6G(SCH_1):PAGE188_I37@PURE_QUANTA.Q_RES(CHIPS)':
 'A': CDS_PINID='A';
NODE_NAME     PC307 2
 '@T6G_MB_LIB.T6G(SCH_1):PAGE188_I39@PURE_QUANTA.Q_CAP(CHIPS)':
 'B': CDS_PINID='B';
NODE_NAME     PC308_C0P1_5 2
 '@T6G_MB_LIB.T6G(SCH_1):PAGE188_I43@PURE_QUANTA.Q_CAP(CHIPS)':
 'B': CDS_PINID='B';
NODE_NAME     PC309_5 2
 '@T6G_MB_LIB.T6G(SCH_1):PAGE188_I45@PURE_QUANTA.Q_CAP(CHIPS)':
 'B': CDS_PINID='B';
NODE_NAME     PC310_5 2
 '@T6G_MB_LIB.T6G(SCH_1):PAGE188_I48@PURE_QUANTA.Q_CAP(CHIPS)':
 'B': CDS_PINID='B';
NODE_NAME     PC311_5 2
 '@T6G_MB_LIB.T6G(SCH_1):PAGE188_I49@PURE_QUANTA.Q_CAP(CHIPS)':
 'B': CDS_PINID='B';
NODE_NAME     PC312_5 2
 '@T6G_MB_LIB.T6G(SCH_1):PAGE188_I50@PURE_QUANTA.Q_CAP(CHIPS)':
 'B': CDS_PINID='B';
NODE_NAME     PL27 1
 '@T6G_MB_LIB.T6G(SCH_1):PAGE188_I51@PURE_QUANTA.Q_INDUCTOR(CHIPS)':
 '1': CDS_PINID='\1\';
NODE_NAME     PC132_6 2
 '@T6G_MB_LIB.T6G(SCH_1):PAGE188_I55@PURE_QUANTA.Q_CAP(CHIPS)':
 'B': CDS_PINID='B';
NODE_NAME     PC134_6 2
 '@T6G_MB_LIB.T6G(SCH_1):PAGE188_I58@PURE_QUANTA.Q_CAP(CHIPS)':
 'B': CDS_PINID='B';
NODE_NAME     PC135_6 2
 '@T6G_MB_LIB.T6G(SCH_1):PAGE188_I60@PURE_QUANTA.Q_CAP(CHIPS)':
 'B': CDS_PINID='B';
NODE_NAME     PC313_5 2
 '@T6G_MB_LIB.T6G(SCH_1):PAGE188_I66@PURE_QUANTA.Q_CAP(CHIPS)':
 'B': CDS_PINID='B';
NODE_NAME     PC315_5 2
 '@T6G_MB_LIB.T6G(SCH_1):PAGE188_I69@PURE_QUANTA.Q_CAP(CHIPS)':
 'B': CDS_PINID='B';
NODE_NAME     PC316_5 2
 '@T6G_MB_LIB.T6G(SCH_1):PAGE188_I71@PURE_QUANTA.Q_CAP(CHIPS)':
 'B': CDS_PINID='B';
NODE_NAME     PU24 2
 '@T6G_MB_LIB.T6G(SCH_1):PAGE188_I73@PURE_QUANTA.ISL99390FRZTR5935(CHIPS)':
 'AGND': CDS_PINID='AGND';
NODE_NAME     PU24 5
 '@T6G_MB_LIB.T6G(SCH_1):PAGE188_I73@PURE_QUANTA.ISL99390FRZTR5935(CHIPS)':
 'PGND1': CDS_PINID='PGND1';
NODE_NAME     PU24 7_9-20_24
 '@T6G_MB_LIB.T6G(SCH_1):PAGE188_I73@PURE_QUANTA.ISL99390FRZTR5935(CHIPS)':
 'PGND2': CDS_PINID='PGND2';
NODE_NAME     PU24 40
 '@T6G_MB_LIB.T6G(SCH_1):PAGE188_I73@PURE_QUANTA.ISL99390FRZTR5935(CHIPS)':
 'PGND3': CDS_PINID='PGND3';
NODE_NAME     PC345_9 2
 '@T6G_MB_LIB.T6G(SCH_1):PAGE191_I2@PURE_QUANTA.Q_CAP(CHIPS)':
 'B': CDS_PINID='B';
NODE_NAME     PR511 2
 '@T6G_MB_LIB.T6G(SCH_1):PAGE191_I10@PURE_QUANTA.Q_RES(CHIPS)':
 'B': CDS_PINID='B';
NODE_NAME     PC346 2
 '@T6G_MB_LIB.T6G(SCH_1):PAGE191_I13@PURE_QUANTA.Q_CAP(CHIPS)':
 'B': CDS_PINID='B';
NODE_NAME     PC348_3 2
 '@T6G_MB_LIB.T6G(SCH_1):PAGE191_I19@PURE_QUANTA.Q_CAP(CHIPS)':
 'B': CDS_PINID='B';
NODE_NAME     PC354_3 2
 '@T6G_MB_LIB.T6G(SCH_1):PAGE191_I28@PURE_QUANTA.Q_CAP(CHIPS)':
 'B': CDS_PINID='B';
NODE_NAME     PC355_3 2
 '@T6G_MB_LIB.T6G(SCH_1):PAGE191_I30@PURE_QUANTA.Q_CAP(CHIPS)':
 'B': CDS_PINID='B';
NODE_NAME     PR208 1
 '@T6G_MB_LIB.T6G(SCH_1):PAGE190_I8@PURE_QUANTA.Q_RES(CHIPS)':
 'A': CDS_PINID='A';
NODE_NAME     PC320 2
 '@T6G_MB_LIB.T6G(SCH_1):PAGE190_I11@PURE_QUANTA.Q_CAP(CHIPS)':
 'B': CDS_PINID='B';
NODE_NAME     PC322_SOP1_2 2
 '@T6G_MB_LIB.T6G(SCH_1):PAGE190_I14@PURE_QUANTA.Q_CAP(CHIPS)':
 'B': CDS_PINID='B';
NODE_NAME     PU30 2
 '@T6G_MB_LIB.T6G(SCH_1):PAGE190_I17@PURE_QUANTA.ISL99390FRZTR5935(CHIPS)':
 'AGND': CDS_PINID='AGND';
NODE_NAME     PU30 5
 '@T6G_MB_LIB.T6G(SCH_1):PAGE190_I17@PURE_QUANTA.ISL99390FRZTR5935(CHIPS)':
 'PGND1': CDS_PINID='PGND1';
NODE_NAME     PU30 7_9-20_24
 '@T6G_MB_LIB.T6G(SCH_1):PAGE190_I17@PURE_QUANTA.ISL99390FRZTR5935(CHIPS)':
 'PGND2': CDS_PINID='PGND2';
NODE_NAME     PU30 40
 '@T6G_MB_LIB.T6G(SCH_1):PAGE190_I17@PURE_QUANTA.ISL99390FRZTR5935(CHIPS)':
 'PGND3': CDS_PINID='PGND3';
NODE_NAME     PR526 2
 '@T6G_MB_LIB.T6G(SCH_1):PAGE190_I21@PURE_QUANTA.Q_RES(CHIPS)':
 'B': CDS_PINID='B';
NODE_NAME     PC330_2 2
 '@T6G_MB_LIB.T6G(SCH_1):PAGE190_I27@PURE_QUANTA.Q_CAP(CHIPS)':
 'B': CDS_PINID='B';
NODE_NAME     PC317_7 2
 '@T6G_MB_LIB.T6G(SCH_1):PAGE190_I32@PURE_QUANTA.Q_CAP(CHIPS)':
 'B': CDS_PINID='B';
NODE_NAME     PR207 1
 '@T6G_MB_LIB.T6G(SCH_1):PAGE190_I35@PURE_QUANTA.Q_RES(CHIPS)':
 'A': CDS_PINID='A';
NODE_NAME     PC319 2
 '@T6G_MB_LIB.T6G(SCH_1):PAGE190_I36@PURE_QUANTA.Q_CAP(CHIPS)':
 'B': CDS_PINID='B';
NODE_NAME     PC321_SOP1_1 2
 '@T6G_MB_LIB.T6G(SCH_1):PAGE190_I41@PURE_QUANTA.Q_CAP(CHIPS)':
 'B': CDS_PINID='B';
NODE_NAME     PC329_1 2
 '@T6G_MB_LIB.T6G(SCH_1):PAGE190_I49@PURE_QUANTA.Q_CAP(CHIPS)':
 'B': CDS_PINID='B';
NODE_NAME     PC331_1 2
 '@T6G_MB_LIB.T6G(SCH_1):PAGE190_I50@PURE_QUANTA.Q_CAP(CHIPS)':
 'B': CDS_PINID='B';
NODE_NAME     PC332_2 2
 '@T6G_MB_LIB.T6G(SCH_1):PAGE190_I56@PURE_QUANTA.Q_CAP(CHIPS)':
 'B': CDS_PINID='B';
NODE_NAME     PC335_2 2
 '@T6G_MB_LIB.T6G(SCH_1):PAGE190_I57@PURE_QUANTA.Q_CAP(CHIPS)':
 'B': CDS_PINID='B';
NODE_NAME     PC337 2
 '@T6G_MB_LIB.T6G(SCH_1):PAGE190_I59@PURE_QUANTA.Q_CAPP(CHIPS)':
 'B': CDS_PINID='B';
NODE_NAME     PC339_2 2
 '@T6G_MB_LIB.T6G(SCH_1):PAGE190_I60@PURE_QUANTA.Q_CAP(CHIPS)':
 'B': CDS_PINID='B';
NODE_NAME     PC342_2 2
 '@T6G_MB_LIB.T6G(SCH_1):PAGE190_I62@PURE_QUANTA.Q_CAP(CHIPS)':
 'B': CDS_PINID='B';
NODE_NAME     PC334_1 2
 '@T6G_MB_LIB.T6G(SCH_1):PAGE190_I71@PURE_QUANTA.Q_CAP(CHIPS)':
 'B': CDS_PINID='B';
NODE_NAME     PC336 2
 '@T6G_MB_LIB.T6G(SCH_1):PAGE190_I73@PURE_QUANTA.Q_CAPP(CHIPS)':
 'B': CDS_PINID='B';
NODE_NAME     PC6007 2
 '@T6G_MB_LIB.T6G(SCH_1):PAGE190_I77@PURE_QUANTA.Q_CAP(CHIPS)':
 'B': CDS_PINID='B';
NODE_NAME     PC341_1 2
 '@T6G_MB_LIB.T6G(SCH_1):PAGE190_I80@PURE_QUANTA.Q_CAP(CHIPS)':
 'B': CDS_PINID='B';
NODE_NAME     PU31 2
 '@T6G_MB_LIB.T6G(SCH_1):PAGE190_I86@PURE_QUANTA.ISL99390FRZTR5935(CHIPS)':
 'AGND': CDS_PINID='AGND';
NODE_NAME     PU31 5
 '@T6G_MB_LIB.T6G(SCH_1):PAGE190_I86@PURE_QUANTA.ISL99390FRZTR5935(CHIPS)':
 'PGND1': CDS_PINID='PGND1';
NODE_NAME     PU31 7_9-20_24
 '@T6G_MB_LIB.T6G(SCH_1):PAGE190_I86@PURE_QUANTA.ISL99390FRZTR5935(CHIPS)':
 'PGND2': CDS_PINID='PGND2';
NODE_NAME     PU31 40
 '@T6G_MB_LIB.T6G(SCH_1):PAGE190_I86@PURE_QUANTA.ISL99390FRZTR5935(CHIPS)':
 'PGND3': CDS_PINID='PGND3';
NODE_NAME     C8356 2
 '@T6G_MB_LIB.T6G(SCH_1):PAGE192_I3@PURE_QUANTA.Q_CAP(CHIPS)':
 'B': CDS_PINID='B';
NODE_NAME     PQ16 S
 '@T6G_MB_LIB.T6G(SCH_1):PAGE192_I6@PURE_QUANTA.MOSFET_N(CHIPS)':
 'SOURCE': CDS_PINID='SOURCE';
NODE_NAME     PR231 2
 '@T6G_MB_LIB.T6G(SCH_1):PAGE192_I8@PURE_QUANTA.Q_RES(CHIPS)':
 'B': CDS_PINID='B';
NODE_NAME     PR244 2
 '@T6G_MB_LIB.T6G(SCH_1):PAGE192_I12@PURE_QUANTA.Q_RES(CHIPS)':
 'B': CDS_PINID='B';
NODE_NAME     PR460 2
 '@T6G_MB_LIB.T6G(SCH_1):PAGE192_I19@PURE_QUANTA.Q_RES(CHIPS)':
 'B': CDS_PINID='B';
NODE_NAME     PR226 2
 '@T6G_MB_LIB.T6G(SCH_1):PAGE192_I23@PURE_QUANTA.Q_RES(CHIPS)':
 'B': CDS_PINID='B';
NODE_NAME     PR217 2
 '@T6G_MB_LIB.T6G(SCH_1):PAGE192_I29@PURE_QUANTA.Q_RES(CHIPS)':
 'B': CDS_PINID='B';
NODE_NAME     R8219 2
 '@T6G_MB_LIB.T6G(SCH_1):PAGE192_I30@PURE_QUANTA.Q_RES(CHIPS)':
 'B': CDS_PINID='B';
NODE_NAME     C308 2
 '@T6G_MB_LIB.T6G(SCH_1):PAGE192_I31@PURE_QUANTA.Q_CAP(CHIPS)':
 'B': CDS_PINID='B';
NODE_NAME     C309 2
 '@T6G_MB_LIB.T6G(SCH_1):PAGE192_I32@PURE_QUANTA.Q_CAP(CHIPS)':
 'B': CDS_PINID='B';
NODE_NAME     C310 2
 '@T6G_MB_LIB.T6G(SCH_1):PAGE192_I33@PURE_QUANTA.Q_CAP(CHIPS)':
 'B': CDS_PINID='B';
NODE_NAME     PC357 2
 '@T6G_MB_LIB.T6G(SCH_1):PAGE192_I47@PURE_QUANTA.Q_CAP(CHIPS)':
 'B': CDS_PINID='B';
NODE_NAME     C8362 2
 '@T6G_MB_LIB.T6G(SCH_1):PAGE192_I52@PURE_QUANTA.Q_CAP(CHIPS)':
 'B': CDS_PINID='B';
NODE_NAME     PR603 2
 '@T6G_MB_LIB.T6G(SCH_1):PAGE192_I55@PURE_QUANTA.Q_RES(CHIPS)':
 'B': CDS_PINID='B';
NODE_NAME     PC364 2
 '@T6G_MB_LIB.T6G(SCH_1):PAGE192_I56@PURE_QUANTA.Q_CAP(CHIPS)':
 'B': CDS_PINID='B';
NODE_NAME     PC363 2
 '@T6G_MB_LIB.T6G(SCH_1):PAGE192_I60@PURE_QUANTA.Q_CAP(CHIPS)':
 'B': CDS_PINID='B';
NODE_NAME     PC368 2
 '@T6G_MB_LIB.T6G(SCH_1):PAGE192_I73@PURE_QUANTA.Q_CAP(CHIPS)':
 'B': CDS_PINID='B';
NODE_NAME     PC367 2
 '@T6G_MB_LIB.T6G(SCH_1):PAGE192_I75@PURE_QUANTA.Q_CAP(CHIPS)':
 'B': CDS_PINID='B';
NODE_NAME     PR533 2
 '@T6G_MB_LIB.T6G(SCH_1):PAGE192_I76@PURE_QUANTA.Q_RES(CHIPS)':
 'B': CDS_PINID='B';
NODE_NAME     C8359 2
 '@T6G_MB_LIB.T6G(SCH_1):PAGE192_I85@PURE_QUANTA.Q_CAP(CHIPS)':
 'B': CDS_PINID='B';
NODE_NAME     C8360 2
 '@T6G_MB_LIB.T6G(SCH_1):PAGE192_I90@PURE_QUANTA.Q_CAP(CHIPS)':
 'B': CDS_PINID='B';
NODE_NAME     PC93 2
 '@T6G_MB_LIB.T6G(SCH_1):PAGE192_I93@PURE_QUANTA.Q_CAP(CHIPS)':
 'B': CDS_PINID='B';
NODE_NAME     PC29 2
 '@T6G_MB_LIB.T6G(SCH_1):PAGE192_I95@PURE_QUANTA.Q_CAP(CHIPS)':
 'B': CDS_PINID='B';
NODE_NAME     PC366 2
 '@T6G_MB_LIB.T6G(SCH_1):PAGE192_I97@PURE_QUANTA.Q_CAP(CHIPS)':
 'B': CDS_PINID='B';
NODE_NAME     PC365 2
 '@T6G_MB_LIB.T6G(SCH_1):PAGE192_I99@PURE_QUANTA.Q_CAP(CHIPS)':
 'B': CDS_PINID='B';
NODE_NAME     PR12 2
 '@T6G_MB_LIB.T6G(SCH_1):PAGE192_I127@PURE_QUANTA.Q_RES(CHIPS)':
 'B': CDS_PINID='B';
NODE_NAME     PU34 TH
 '@T6G_MB_LIB.T6G(SCH_1):PAGE192_I128@PURE_QUANTA.RAA229620GNPHA0(CHIPS)':
 'TH_GND': CDS_PINID='TH_GND';
NODE_NAME     PR254 2
 '@T6G_MB_LIB.T6G(SCH_1):PAGE193_I4@PURE_QUANTA.Q_RES(CHIPS)':
 'B': CDS_PINID='B';
NODE_NAME     PC374_1 2
 '@T6G_MB_LIB.T6G(SCH_1):PAGE193_I11@PURE_QUANTA.Q_CAP(CHIPS)':
 'B': CDS_PINID='B';
NODE_NAME     PC370 2
 '@T6G_MB_LIB.T6G(SCH_1):PAGE193_I12@PURE_QUANTA.Q_CAP(CHIPS)':
 'B': CDS_PINID='B';
NODE_NAME     PC372_C1P1_2 2
 '@T6G_MB_LIB.T6G(SCH_1):PAGE193_I15@PURE_QUANTA.Q_CAP(CHIPS)':
 'B': CDS_PINID='B';
NODE_NAME     PR255 2
 '@T6G_MB_LIB.T6G(SCH_1):PAGE193_I17@PURE_QUANTA.Q_RES(CHIPS)':
 'B': CDS_PINID='B';
NODE_NAME     PC371_C1P1_1 2
 '@T6G_MB_LIB.T6G(SCH_1):PAGE193_I29@PURE_QUANTA.Q_CAP(CHIPS)':
 'B': CDS_PINID='B';
NODE_NAME     PU5 2
 '@T6G_MB_LIB.T6G(SCH_1):PAGE193_I31@PURE_QUANTA.ISL99390FRZTR5935(CHIPS)':
 'AGND': CDS_PINID='AGND';
NODE_NAME     PU5 5
 '@T6G_MB_LIB.T6G(SCH_1):PAGE193_I31@PURE_QUANTA.ISL99390FRZTR5935(CHIPS)':
 'PGND1': CDS_PINID='PGND1';
NODE_NAME     PU5 7_9-20_24
 '@T6G_MB_LIB.T6G(SCH_1):PAGE193_I31@PURE_QUANTA.ISL99390FRZTR5935(CHIPS)':
 'PGND2': CDS_PINID='PGND2';
NODE_NAME     PU5 40
 '@T6G_MB_LIB.T6G(SCH_1):PAGE193_I31@PURE_QUANTA.ISL99390FRZTR5935(CHIPS)':
 'PGND3': CDS_PINID='PGND3';
NODE_NAME     PC376_2 2
 '@T6G_MB_LIB.T6G(SCH_1):PAGE193_I34@PURE_QUANTA.Q_CAP(CHIPS)':
 'B': CDS_PINID='B';
NODE_NAME     PR513 2
 '@T6G_MB_LIB.T6G(SCH_1):PAGE193_I36@PURE_QUANTA.Q_RES(CHIPS)':
 'B': CDS_PINID='B';
NODE_NAME     PC378_2 2
 '@T6G_MB_LIB.T6G(SCH_1):PAGE193_I42@PURE_QUANTA.Q_CAP(CHIPS)':
 'B': CDS_PINID='B';
NODE_NAME     PC380_2 2
 '@T6G_MB_LIB.T6G(SCH_1):PAGE193_I43@PURE_QUANTA.Q_CAP(CHIPS)':
 'B': CDS_PINID='B';
NODE_NAME     PR512 2
 '@T6G_MB_LIB.T6G(SCH_1):PAGE193_I45@PURE_QUANTA.Q_RES(CHIPS)':
 'B': CDS_PINID='B';
NODE_NAME     PC385_2 2
 '@T6G_MB_LIB.T6G(SCH_1):PAGE193_I48@PURE_QUANTA.Q_CAP(CHIPS)':
 'B': CDS_PINID='B';
NODE_NAME     PC375_1 2
 '@T6G_MB_LIB.T6G(SCH_1):PAGE193_I50@PURE_QUANTA.Q_CAP(CHIPS)':
 'B': CDS_PINID='B';
NODE_NAME     PC377_1 2
 '@T6G_MB_LIB.T6G(SCH_1):PAGE193_I53@PURE_QUANTA.Q_CAP(CHIPS)':
 'B': CDS_PINID='B';
NODE_NAME     PC379_1 2
 '@T6G_MB_LIB.T6G(SCH_1):PAGE193_I54@PURE_QUANTA.Q_CAP(CHIPS)':
 'B': CDS_PINID='B';
NODE_NAME     PC381_1 2
 '@T6G_MB_LIB.T6G(SCH_1):PAGE193_I58@PURE_QUANTA.Q_CAP(CHIPS)':
 'B': CDS_PINID='B';
NODE_NAME     PC384_1 2
 '@T6G_MB_LIB.T6G(SCH_1):PAGE193_I60@PURE_QUANTA.Q_CAP(CHIPS)':
 'B': CDS_PINID='B';
NODE_NAME     PC394_2 2
 '@T6G_MB_LIB.T6G(SCH_1):PAGE193_I68@PURE_QUANTA.Q_CAP(CHIPS)':
 'B': CDS_PINID='B';
NODE_NAME     PC397_2 2
 '@T6G_MB_LIB.T6G(SCH_1):PAGE193_I70@PURE_QUANTA.Q_CAP(CHIPS)':
 'B': CDS_PINID='B';
NODE_NAME     PC389 2
 '@T6G_MB_LIB.T6G(SCH_1):PAGE193_I73@PURE_QUANTA.Q_CAPP(CHIPS)':
 'B': CDS_PINID='B';
NODE_NAME     PC392 2
 '@T6G_MB_LIB.T6G(SCH_1):PAGE193_I82@PURE_QUANTA.Q_CAP(CHIPS)':
 'B': CDS_PINID='B';
NODE_NAME     PC375 2
 '@T6G_MB_LIB.T6G(SCH_1):PAGE193_I83@PURE_QUANTA.Q_CAP(CHIPS)':
 'B': CDS_PINID='B';
NODE_NAME     PC395_1 2
 '@T6G_MB_LIB.T6G(SCH_1):PAGE193_I85@PURE_QUANTA.Q_CAP(CHIPS)':
 'B': CDS_PINID='B';
NODE_NAME     PC398_1 2
 '@T6G_MB_LIB.T6G(SCH_1):PAGE193_I86@PURE_QUANTA.Q_CAP(CHIPS)':
 'B': CDS_PINID='B';
NODE_NAME     PU35 2
 '@T6G_MB_LIB.T6G(SCH_1):PAGE193_I91@PURE_QUANTA.ISL99390FRZTR5935(CHIPS)':
 'AGND': CDS_PINID='AGND';
NODE_NAME     PU35 5
 '@T6G_MB_LIB.T6G(SCH_1):PAGE193_I91@PURE_QUANTA.ISL99390FRZTR5935(CHIPS)':
 'PGND1': CDS_PINID='PGND1';
NODE_NAME     PU35 7_9-20_24
 '@T6G_MB_LIB.T6G(SCH_1):PAGE193_I91@PURE_QUANTA.ISL99390FRZTR5935(CHIPS)':
 'PGND2': CDS_PINID='PGND2';
NODE_NAME     PU35 40
 '@T6G_MB_LIB.T6G(SCH_1):PAGE193_I91@PURE_QUANTA.ISL99390FRZTR5935(CHIPS)':
 'PGND3': CDS_PINID='PGND3';
NODE_NAME     PR262 2
 '@T6G_MB_LIB.T6G(SCH_1):PAGE194_I4@PURE_QUANTA.Q_RES(CHIPS)':
 'B': CDS_PINID='B';
NODE_NAME     PC399 2
 '@T6G_MB_LIB.T6G(SCH_1):PAGE194_I7@PURE_QUANTA.Q_CAP(CHIPS)':
 'B': CDS_PINID='B';
NODE_NAME     PC404_3 2
 '@T6G_MB_LIB.T6G(SCH_1):PAGE194_I12@PURE_QUANTA.Q_CAP(CHIPS)':
 'B': CDS_PINID='B';
NODE_NAME     PC401_C1P1_4 2
 '@T6G_MB_LIB.T6G(SCH_1):PAGE194_I16@PURE_QUANTA.Q_CAP(CHIPS)':
 'B': CDS_PINID='B';
NODE_NAME     PR263 2
 '@T6G_MB_LIB.T6G(SCH_1):PAGE194_I18@PURE_QUANTA.Q_RES(CHIPS)':
 'B': CDS_PINID='B';
NODE_NAME     PU36 2
 '@T6G_MB_LIB.T6G(SCH_1):PAGE194_I21@PURE_QUANTA.ISL99390FRZTR5935(CHIPS)':
 'AGND': CDS_PINID='AGND';
NODE_NAME     PU36 5
 '@T6G_MB_LIB.T6G(SCH_1):PAGE194_I21@PURE_QUANTA.ISL99390FRZTR5935(CHIPS)':
 'PGND1': CDS_PINID='PGND1';
NODE_NAME     PU36 7_9-20_24
 '@T6G_MB_LIB.T6G(SCH_1):PAGE194_I21@PURE_QUANTA.ISL99390FRZTR5935(CHIPS)':
 'PGND2': CDS_PINID='PGND2';
NODE_NAME     PU36 40
 '@T6G_MB_LIB.T6G(SCH_1):PAGE194_I21@PURE_QUANTA.ISL99390FRZTR5935(CHIPS)':
 'PGND3': CDS_PINID='PGND3';
NODE_NAME     PC405_4 2
 '@T6G_MB_LIB.T6G(SCH_1):PAGE194_I23@PURE_QUANTA.Q_CAP(CHIPS)':
 'B': CDS_PINID='B';
NODE_NAME     PC400 2
 '@T6G_MB_LIB.T6G(SCH_1):PAGE194_I27@PURE_QUANTA.Q_CAP(CHIPS)':
 'B': CDS_PINID='B';
NODE_NAME     PC402_C1P1_3 2
 '@T6G_MB_LIB.T6G(SCH_1):PAGE194_I31@PURE_QUANTA.Q_CAP(CHIPS)':
 'B': CDS_PINID='B';
NODE_NAME     PC408_3 2
 '@T6G_MB_LIB.T6G(SCH_1):PAGE194_I33@PURE_QUANTA.Q_CAP(CHIPS)':
 'B': CDS_PINID='B';
NODE_NAME     PR515 2
 '@T6G_MB_LIB.T6G(SCH_1):PAGE194_I35@PURE_QUANTA.Q_RES(CHIPS)':
 'B': CDS_PINID='B';
NODE_NAME     PC407_4 2
 '@T6G_MB_LIB.T6G(SCH_1):PAGE194_I41@PURE_QUANTA.Q_CAP(CHIPS)':
 'B': CDS_PINID='B';
NODE_NAME     PR516 2
 '@T6G_MB_LIB.T6G(SCH_1):PAGE194_I44@PURE_QUANTA.Q_RES(CHIPS)':
 'B': CDS_PINID='B';
NODE_NAME     PC411_4 2
 '@T6G_MB_LIB.T6G(SCH_1):PAGE194_I45@PURE_QUANTA.Q_CAP(CHIPS)':
 'B': CDS_PINID='B';
NODE_NAME     PC415_4 2
 '@T6G_MB_LIB.T6G(SCH_1):PAGE194_I47@PURE_QUANTA.Q_CAP(CHIPS)':
 'B': CDS_PINID='B';
NODE_NAME     PC406_3 2
 '@T6G_MB_LIB.T6G(SCH_1):PAGE194_I54@PURE_QUANTA.Q_CAP(CHIPS)':
 'B': CDS_PINID='B';
NODE_NAME     PC412_3 2
 '@T6G_MB_LIB.T6G(SCH_1):PAGE194_I59@PURE_QUANTA.Q_CAP(CHIPS)':
 'B': CDS_PINID='B';
NODE_NAME     PC416_3 2
 '@T6G_MB_LIB.T6G(SCH_1):PAGE194_I60@PURE_QUANTA.Q_CAP(CHIPS)':
 'B': CDS_PINID='B';
NODE_NAME     PC417_3 2
 '@T6G_MB_LIB.T6G(SCH_1):PAGE194_I64@PURE_QUANTA.Q_CAP(CHIPS)':
 'B': CDS_PINID='B';
NODE_NAME     PC418_4 2
 '@T6G_MB_LIB.T6G(SCH_1):PAGE194_I65@PURE_QUANTA.Q_CAP(CHIPS)':
 'B': CDS_PINID='B';
NODE_NAME     PC420_4 2
 '@T6G_MB_LIB.T6G(SCH_1):PAGE194_I67@PURE_QUANTA.Q_CAP(CHIPS)':
 'B': CDS_PINID='B';
NODE_NAME     PC419_3 2
 '@T6G_MB_LIB.T6G(SCH_1):PAGE194_I70@PURE_QUANTA.Q_CAP(CHIPS)':
 'B': CDS_PINID='B';
NODE_NAME     PU37 2
 '@T6G_MB_LIB.T6G(SCH_1):PAGE194_I72@PURE_QUANTA.ISL99390FRZTR5935(CHIPS)':
 'AGND': CDS_PINID='AGND';
NODE_NAME     PU37 5
 '@T6G_MB_LIB.T6G(SCH_1):PAGE194_I72@PURE_QUANTA.ISL99390FRZTR5935(CHIPS)':
 'PGND1': CDS_PINID='PGND1';
NODE_NAME     PU37 7_9-20_24
 '@T6G_MB_LIB.T6G(SCH_1):PAGE194_I72@PURE_QUANTA.ISL99390FRZTR5935(CHIPS)':
 'PGND2': CDS_PINID='PGND2';
NODE_NAME     PU37 40
 '@T6G_MB_LIB.T6G(SCH_1):PAGE194_I72@PURE_QUANTA.ISL99390FRZTR5935(CHIPS)':
 'PGND3': CDS_PINID='PGND3';
NODE_NAME     PC136_6 2
 '@T6G_MB_LIB.T6G(SCH_1):PAGE195_I1@PURE_QUANTA.Q_CAP(CHIPS)':
 'B': CDS_PINID='B';
NODE_NAME     PR426 2
 '@T6G_MB_LIB.T6G(SCH_1):PAGE195_I4@PURE_QUANTA.Q_RES(CHIPS)':
 'B': CDS_PINID='B';
NODE_NAME     PC422_5 2
 '@T6G_MB_LIB.T6G(SCH_1):PAGE195_I10@PURE_QUANTA.Q_CAP(CHIPS)':
 'B': CDS_PINID='B';
NODE_NAME     PC138 2
 '@T6G_MB_LIB.T6G(SCH_1):PAGE195_I12@PURE_QUANTA.Q_CAP(CHIPS)':
 'B': CDS_PINID='B';
NODE_NAME     PR270 2
 '@T6G_MB_LIB.T6G(SCH_1):PAGE195_I15@PURE_QUANTA.Q_RES(CHIPS)':
 'B': CDS_PINID='B';
NODE_NAME     PU33 2
 '@T6G_MB_LIB.T6G(SCH_1):PAGE195_I19@PURE_QUANTA.ISL99390FRZTR5935(CHIPS)':
 'AGND': CDS_PINID='AGND';
NODE_NAME     PU33 5
 '@T6G_MB_LIB.T6G(SCH_1):PAGE195_I19@PURE_QUANTA.ISL99390FRZTR5935(CHIPS)':
 'PGND1': CDS_PINID='PGND1';
NODE_NAME     PU33 7_9-20_24
 '@T6G_MB_LIB.T6G(SCH_1):PAGE195_I19@PURE_QUANTA.ISL99390FRZTR5935(CHIPS)':
 'PGND2': CDS_PINID='PGND2';
NODE_NAME     PU33 40
 '@T6G_MB_LIB.T6G(SCH_1):PAGE195_I19@PURE_QUANTA.ISL99390FRZTR5935(CHIPS)':
 'PGND3': CDS_PINID='PGND3';
NODE_NAME     PC139_C1P1_6 2
 '@T6G_MB_LIB.T6G(SCH_1):PAGE195_I22@PURE_QUANTA.Q_CAP(CHIPS)':
 'B': CDS_PINID='B';
NODE_NAME     PC421 2
 '@T6G_MB_LIB.T6G(SCH_1):PAGE195_I27@PURE_QUANTA.Q_CAP(CHIPS)':
 'B': CDS_PINID='B';
NODE_NAME     PR518 2
 '@T6G_MB_LIB.T6G(SCH_1):PAGE195_I33@PURE_QUANTA.Q_RES(CHIPS)':
 'B': CDS_PINID='B';
NODE_NAME     PL39 2
 '@T6G_MB_LIB.T6G(SCH_1):PAGE195_I37@PURE_QUANTA.Q_INDUCTOR(CHIPS)':
 '2': CDS_PINID='\2\';
NODE_NAME     PC141_6 2
 '@T6G_MB_LIB.T6G(SCH_1):PAGE195_I38@PURE_QUANTA.Q_CAP(CHIPS)':
 'B': CDS_PINID='B';
NODE_NAME     PC144_6 2
 '@T6G_MB_LIB.T6G(SCH_1):PAGE195_I41@PURE_QUANTA.Q_CAP(CHIPS)':
 'B': CDS_PINID='B';
NODE_NAME     PR517 2
 '@T6G_MB_LIB.T6G(SCH_1):PAGE195_I43@PURE_QUANTA.Q_RES(CHIPS)':
 'B': CDS_PINID='B';
NODE_NAME     PC145_6 2
 '@T6G_MB_LIB.T6G(SCH_1):PAGE195_I44@PURE_QUANTA.Q_CAP(CHIPS)':
 'B': CDS_PINID='B';
NODE_NAME     PC147_6 2
 '@T6G_MB_LIB.T6G(SCH_1):PAGE195_I47@PURE_QUANTA.Q_CAP(CHIPS)':
 'B': CDS_PINID='B';
NODE_NAME     PC425_5 2
 '@T6G_MB_LIB.T6G(SCH_1):PAGE195_I54@PURE_QUANTA.Q_CAP(CHIPS)':
 'B': CDS_PINID='B';
NODE_NAME     PC424_5 2
 '@T6G_MB_LIB.T6G(SCH_1):PAGE195_I55@PURE_QUANTA.Q_CAP(CHIPS)':
 'B': CDS_PINID='B';
NODE_NAME     PC426_5 2
 '@T6G_MB_LIB.T6G(SCH_1):PAGE195_I56@PURE_QUANTA.Q_CAP(CHIPS)':
 'B': CDS_PINID='B';
NODE_NAME     PC429_5 2
 '@T6G_MB_LIB.T6G(SCH_1):PAGE195_I61@PURE_QUANTA.Q_CAP(CHIPS)':
 'B': CDS_PINID='B';
NODE_NAME     PC148_6 2
 '@T6G_MB_LIB.T6G(SCH_1):PAGE195_I65@PURE_QUANTA.Q_CAP(CHIPS)':
 'B': CDS_PINID='B';
NODE_NAME     PC149_6 2
 '@T6G_MB_LIB.T6G(SCH_1):PAGE195_I67@PURE_QUANTA.Q_CAP(CHIPS)':
 'B': CDS_PINID='B';
NODE_NAME     PC430_5 2
 '@T6G_MB_LIB.T6G(SCH_1):PAGE195_I70@PURE_QUANTA.Q_CAP(CHIPS)':
 'B': CDS_PINID='B';
NODE_NAME     PC431_5 2
 '@T6G_MB_LIB.T6G(SCH_1):PAGE195_I71@PURE_QUANTA.Q_CAP(CHIPS)':
 'B': CDS_PINID='B';
NODE_NAME     PU38 2
 '@T6G_MB_LIB.T6G(SCH_1):PAGE195_I73@PURE_QUANTA.ISL99390FRZTR5935(CHIPS)':
 'AGND': CDS_PINID='AGND';
NODE_NAME     PU38 5
 '@T6G_MB_LIB.T6G(SCH_1):PAGE195_I73@PURE_QUANTA.ISL99390FRZTR5935(CHIPS)':
 'PGND1': CDS_PINID='PGND1';
NODE_NAME     PU38 7_9-20_24
 '@T6G_MB_LIB.T6G(SCH_1):PAGE195_I73@PURE_QUANTA.ISL99390FRZTR5935(CHIPS)':
 'PGND2': CDS_PINID='PGND2';
NODE_NAME     PU38 40
 '@T6G_MB_LIB.T6G(SCH_1):PAGE195_I73@PURE_QUANTA.ISL99390FRZTR5935(CHIPS)':
 'PGND3': CDS_PINID='PGND3';
NODE_NAME     PC436_8 2
 '@T6G_MB_LIB.T6G(SCH_1):PAGE197_I3@PURE_QUANTA.Q_CAP(CHIPS)':
 'B': CDS_PINID='B';
NODE_NAME     PC435_7 2
 '@T6G_MB_LIB.T6G(SCH_1):PAGE197_I4@PURE_QUANTA.Q_CAP(CHIPS)':
 'B': CDS_PINID='B';
NODE_NAME     PR274 2
 '@T6G_MB_LIB.T6G(SCH_1):PAGE197_I6@PURE_QUANTA.Q_RES(CHIPS)':
 'B': CDS_PINID='B';
NODE_NAME     PC432 2
 '@T6G_MB_LIB.T6G(SCH_1):PAGE197_I12@PURE_QUANTA.Q_CAP(CHIPS)':
 'B': CDS_PINID='B';
NODE_NAME     PC434_IOP1_2 2
 '@T6G_MB_LIB.T6G(SCH_1):PAGE197_I16@PURE_QUANTA.Q_CAP(CHIPS)':
 'B': CDS_PINID='B';
NODE_NAME     PR489 2
 '@T6G_MB_LIB.T6G(SCH_1):PAGE197_I19@PURE_QUANTA.Q_RES(CHIPS)':
 'B': CDS_PINID='B';
NODE_NAME     PC439_2 2
 '@T6G_MB_LIB.T6G(SCH_1):PAGE197_I21@PURE_QUANTA.Q_CAP(CHIPS)':
 'B': CDS_PINID='B';
NODE_NAME     PC441_2 2
 '@T6G_MB_LIB.T6G(SCH_1):PAGE197_I23@PURE_QUANTA.Q_CAP(CHIPS)':
 'B': CDS_PINID='B';
NODE_NAME     PR488 2
 '@T6G_MB_LIB.T6G(SCH_1):PAGE197_I26@PURE_QUANTA.Q_RES(CHIPS)':
 'B': CDS_PINID='B';
NODE_NAME     PR275 2
 '@T6G_MB_LIB.T6G(SCH_1):PAGE197_I28@PURE_QUANTA.Q_RES(CHIPS)':
 'B': CDS_PINID='B';
NODE_NAME     PC433 2
 '@T6G_MB_LIB.T6G(SCH_1):PAGE197_I34@PURE_QUANTA.Q_CAP(CHIPS)':
 'B': CDS_PINID='B';
NODE_NAME     PC437_IOP1_1 2
 '@T6G_MB_LIB.T6G(SCH_1):PAGE197_I38@PURE_QUANTA.Q_CAP(CHIPS)':
 'B': CDS_PINID='B';
NODE_NAME     PU39 2
 '@T6G_MB_LIB.T6G(SCH_1):PAGE197_I39@PURE_QUANTA.ISL99390FRZTR5935(CHIPS)':
 'AGND': CDS_PINID='AGND';
NODE_NAME     PU39 5
 '@T6G_MB_LIB.T6G(SCH_1):PAGE197_I39@PURE_QUANTA.ISL99390FRZTR5935(CHIPS)':
 'PGND1': CDS_PINID='PGND1';
NODE_NAME     PU39 7_9-20_24
 '@T6G_MB_LIB.T6G(SCH_1):PAGE197_I39@PURE_QUANTA.ISL99390FRZTR5935(CHIPS)':
 'PGND2': CDS_PINID='PGND2';
NODE_NAME     PU39 40
 '@T6G_MB_LIB.T6G(SCH_1):PAGE197_I39@PURE_QUANTA.ISL99390FRZTR5935(CHIPS)':
 'PGND3': CDS_PINID='PGND3';
NODE_NAME     PC438_1 2
 '@T6G_MB_LIB.T6G(SCH_1):PAGE197_I41@PURE_QUANTA.Q_CAP(CHIPS)':
 'B': CDS_PINID='B';
NODE_NAME     PC440_1 2
 '@T6G_MB_LIB.T6G(SCH_1):PAGE197_I42@PURE_QUANTA.Q_CAP(CHIPS)':
 'B': CDS_PINID='B';
NODE_NAME     PC442_1 2
 '@T6G_MB_LIB.T6G(SCH_1):PAGE197_I44@PURE_QUANTA.Q_CAP(CHIPS)':
 'B': CDS_PINID='B';
NODE_NAME     PC443_2 2
 '@T6G_MB_LIB.T6G(SCH_1):PAGE197_I48@PURE_QUANTA.Q_CAP(CHIPS)':
 'B': CDS_PINID='B';
NODE_NAME     PC446_2 2
 '@T6G_MB_LIB.T6G(SCH_1):PAGE197_I49@PURE_QUANTA.Q_CAP(CHIPS)':
 'B': CDS_PINID='B';
NODE_NAME     PC449_2 2
 '@T6G_MB_LIB.T6G(SCH_1):PAGE197_I52@PURE_QUANTA.Q_CAP(CHIPS)':
 'B': CDS_PINID='B';
NODE_NAME     PC458_2 2
 '@T6G_MB_LIB.T6G(SCH_1):PAGE197_I55@PURE_QUANTA.Q_CAP(CHIPS)':
 'B': CDS_PINID='B';
NODE_NAME     PC460_2 2
 '@T6G_MB_LIB.T6G(SCH_1):PAGE197_I57@PURE_QUANTA.Q_CAP(CHIPS)':
 'B': CDS_PINID='B';
NODE_NAME     PC450 2
 '@T6G_MB_LIB.T6G(SCH_1):PAGE197_I58@PURE_QUANTA.Q_CAPP(CHIPS)':
 'B': CDS_PINID='B';
NODE_NAME     PC452 2
 '@T6G_MB_LIB.T6G(SCH_1):PAGE197_I59@PURE_QUANTA.Q_CAPP(CHIPS)':
 'B': CDS_PINID='B';
NODE_NAME     PC455 2
 '@T6G_MB_LIB.T6G(SCH_1):PAGE197_I62@PURE_QUANTA.Q_CAPP(CHIPS)':
 'B': CDS_PINID='B';
NODE_NAME     PC444_1 2
 '@T6G_MB_LIB.T6G(SCH_1):PAGE197_I66@PURE_QUANTA.Q_CAP(CHIPS)':
 'B': CDS_PINID='B';
NODE_NAME     PC448_1 2
 '@T6G_MB_LIB.T6G(SCH_1):PAGE197_I69@PURE_QUANTA.Q_CAP(CHIPS)':
 'B': CDS_PINID='B';
NODE_NAME     PL47 3
 '@T6G_MB_LIB.T6G(SCH_1):PAGE197_I71@PURE_QUANTA.Q_INDUCTOR4P_14(CHIPS)':
 '3': CDS_PINID='\3\';
NODE_NAME     PC438 2
 '@T6G_MB_LIB.T6G(SCH_1):PAGE197_I74@PURE_QUANTA.Q_CAP(CHIPS)':
 'B': CDS_PINID='B';
NODE_NAME     PC451 2
 '@T6G_MB_LIB.T6G(SCH_1):PAGE197_I77@PURE_QUANTA.Q_CAP(CHIPS)':
 'B': CDS_PINID='B';
NODE_NAME     PC456_1 2
 '@T6G_MB_LIB.T6G(SCH_1):PAGE197_I78@PURE_QUANTA.Q_CAP(CHIPS)':
 'B': CDS_PINID='B';
NODE_NAME     PC459_1 2
 '@T6G_MB_LIB.T6G(SCH_1):PAGE197_I79@PURE_QUANTA.Q_CAP(CHIPS)':
 'B': CDS_PINID='B';
NODE_NAME     PR378 2
 '@T6G_MB_LIB.T6G(SCH_1):PAGE197_I81@PURE_QUANTA.Q_RES(CHIPS)':
 'B': CDS_PINID='B';
NODE_NAME     PU40 2
 '@T6G_MB_LIB.T6G(SCH_1):PAGE197_I84@PURE_QUANTA.ISL99390FRZTR5935(CHIPS)':
 'AGND': CDS_PINID='AGND';
NODE_NAME     PU40 5
 '@T6G_MB_LIB.T6G(SCH_1):PAGE197_I84@PURE_QUANTA.ISL99390FRZTR5935(CHIPS)':
 'PGND1': CDS_PINID='PGND1';
NODE_NAME     PU40 7_9-20_24
 '@T6G_MB_LIB.T6G(SCH_1):PAGE197_I84@PURE_QUANTA.ISL99390FRZTR5935(CHIPS)':
 'PGND2': CDS_PINID='PGND2';
NODE_NAME     PU40 40
 '@T6G_MB_LIB.T6G(SCH_1):PAGE197_I84@PURE_QUANTA.ISL99390FRZTR5935(CHIPS)':
 'PGND3': CDS_PINID='PGND3';
NODE_NAME     PR368 2
 '@T6G_MB_LIB.T6G(SCH_1):PAGE198_I4@PURE_QUANTA.Q_RES(CHIPS)':
 'B': CDS_PINID='B';
NODE_NAME     PC616 2
 '@T6G_MB_LIB.T6G(SCH_1):PAGE198_I10@PURE_QUANTA.Q_CAP(CHIPS)':
 'B': CDS_PINID='B';
NODE_NAME     PC618_IOP1_4 2
 '@T6G_MB_LIB.T6G(SCH_1):PAGE198_I13@PURE_QUANTA.Q_CAP(CHIPS)':
 'B': CDS_PINID='B';
NODE_NAME     PC623_4 2
 '@T6G_MB_LIB.T6G(SCH_1):PAGE198_I18@PURE_QUANTA.Q_CAP(CHIPS)':
 'B': CDS_PINID='B';
NODE_NAME     PC620_9 2
 '@T6G_MB_LIB.T6G(SCH_1):PAGE198_I20@PURE_QUANTA.Q_CAP(CHIPS)':
 'B': CDS_PINID='B';
NODE_NAME     PR369 2
 '@T6G_MB_LIB.T6G(SCH_1):PAGE198_I22@PURE_QUANTA.Q_RES(CHIPS)':
 'B': CDS_PINID='B';
NODE_NAME     PC619_IOP1_3 2
 '@T6G_MB_LIB.T6G(SCH_1):PAGE198_I31@PURE_QUANTA.Q_CAP(CHIPS)':
 'B': CDS_PINID='B';
NODE_NAME     PC622_3 2
 '@T6G_MB_LIB.T6G(SCH_1):PAGE198_I35@PURE_QUANTA.Q_CAP(CHIPS)':
 'B': CDS_PINID='B';
NODE_NAME     PC624_3 2
 '@T6G_MB_LIB.T6G(SCH_1):PAGE198_I36@PURE_QUANTA.Q_CAP(CHIPS)':
 'B': CDS_PINID='B';
NODE_NAME     PR491 2
 '@T6G_MB_LIB.T6G(SCH_1):PAGE198_I39@PURE_QUANTA.Q_RES(CHIPS)':
 'B': CDS_PINID='B';
NODE_NAME     PL46 2
 '@T6G_MB_LIB.T6G(SCH_1):PAGE198_I43@PURE_QUANTA.Q_INDUCTOR(CHIPS)':
 '2': CDS_PINID='\2\';
NODE_NAME     PC625_4 2
 '@T6G_MB_LIB.T6G(SCH_1):PAGE198_I45@PURE_QUANTA.Q_CAP(CHIPS)':
 'B': CDS_PINID='B';
NODE_NAME     PC633_4 2
 '@T6G_MB_LIB.T6G(SCH_1):PAGE198_I48@PURE_QUANTA.Q_CAP(CHIPS)':
 'B': CDS_PINID='B';
NODE_NAME     PC636_4 2
 '@T6G_MB_LIB.T6G(SCH_1):PAGE198_I53@PURE_QUANTA.Q_CAP(CHIPS)':
 'B': CDS_PINID='B';
NODE_NAME     PC626_3 2
 '@T6G_MB_LIB.T6G(SCH_1):PAGE198_I60@PURE_QUANTA.Q_CAP(CHIPS)':
 'B': CDS_PINID='B';
NODE_NAME     PC628_3 2
 '@T6G_MB_LIB.T6G(SCH_1):PAGE198_I61@PURE_QUANTA.Q_CAP(CHIPS)':
 'B': CDS_PINID='B';
NODE_NAME     PC637_3 2
 '@T6G_MB_LIB.T6G(SCH_1):PAGE198_I70@PURE_QUANTA.Q_CAP(CHIPS)':
 'B': CDS_PINID='B';
NODE_NAME     PC627_4 2
 '@T6G_MB_LIB.T6G(SCH_1):PAGE198_I72@PURE_QUANTA.Q_CAP(CHIPS)':
 'B': CDS_PINID='B';
NODE_NAME     PU52 2
 '@T6G_MB_LIB.T6G(SCH_1):PAGE198_I73@PURE_QUANTA.ISL99390FRZTR5935(CHIPS)':
 'AGND': CDS_PINID='AGND';
NODE_NAME     PU52 5
 '@T6G_MB_LIB.T6G(SCH_1):PAGE198_I73@PURE_QUANTA.ISL99390FRZTR5935(CHIPS)':
 'PGND1': CDS_PINID='PGND1';
NODE_NAME     PU52 7_9-20_24
 '@T6G_MB_LIB.T6G(SCH_1):PAGE198_I73@PURE_QUANTA.ISL99390FRZTR5935(CHIPS)':
 'PGND2': CDS_PINID='PGND2';
NODE_NAME     PU52 40
 '@T6G_MB_LIB.T6G(SCH_1):PAGE198_I73@PURE_QUANTA.ISL99390FRZTR5935(CHIPS)':
 'PGND3': CDS_PINID='PGND3';
NODE_NAME     PC638 2
 '@T6G_MB_LIB.T6G(SCH_1):PAGE199_I4@PURE_QUANTA.Q_CAP(CHIPS)':
 'B': CDS_PINID='B';
NODE_NAME     PR6 2
 '@T6G_MB_LIB.T6G(SCH_1):PAGE199_I6@PURE_QUANTA.Q_RES(CHIPS)':
 'B': CDS_PINID='B';
NODE_NAME     PR288 2
 '@T6G_MB_LIB.T6G(SCH_1):PAGE199_I15@PURE_QUANTA.Q_RES(CHIPS)':
 'B': CDS_PINID='B';
NODE_NAME     PR604 2
 '@T6G_MB_LIB.T6G(SCH_1):PAGE199_I17@PURE_QUANTA.Q_RES(CHIPS)':
 'B': CDS_PINID='B';
NODE_NAME     PC8 2
 '@T6G_MB_LIB.T6G(SCH_1):PAGE199_I20@PURE_QUANTA.Q_CAP(CHIPS)':
 'B': CDS_PINID='B';
NODE_NAME     C642 2
 '@T6G_MB_LIB.T6G(SCH_1):PAGE199_I44@PURE_QUANTA.Q_CAP(CHIPS)':
 'B': CDS_PINID='B';
NODE_NAME     C8641 2
 '@T6G_MB_LIB.T6G(SCH_1):PAGE199_I46@PURE_QUANTA.Q_CAP(CHIPS)':
 'B': CDS_PINID='B';
NODE_NAME     PC643 2
 '@T6G_MB_LIB.T6G(SCH_1):PAGE199_I49@PURE_QUANTA.Q_CAP(CHIPS)':
 'B': CDS_PINID='B';
NODE_NAME     PR415 2
 '@T6G_MB_LIB.T6G(SCH_1):PAGE199_I51@PURE_QUANTA.Q_RES(CHIPS)':
 'B': CDS_PINID='B';
NODE_NAME     PR409 2
 '@T6G_MB_LIB.T6G(SCH_1):PAGE199_I52@PURE_QUANTA.Q_RES(CHIPS)':
 'B': CDS_PINID='B';
NODE_NAME     PR390 2
 '@T6G_MB_LIB.T6G(SCH_1):PAGE199_I56@PURE_QUANTA.Q_RES(CHIPS)':
 'B': CDS_PINID='B';
NODE_NAME     PR408 2
 '@T6G_MB_LIB.T6G(SCH_1):PAGE199_I57@PURE_QUANTA.Q_RES(CHIPS)':
 'B': CDS_PINID='B';
NODE_NAME     PR14 2
 '@T6G_MB_LIB.T6G(SCH_1):PAGE199_I58@PURE_QUANTA.Q_RES(CHIPS)':
 'B': CDS_PINID='B';
NODE_NAME     PR13 2
 '@T6G_MB_LIB.T6G(SCH_1):PAGE199_I59@PURE_QUANTA.Q_RES(CHIPS)':
 'B': CDS_PINID='B';
NODE_NAME     PR407 2
 '@T6G_MB_LIB.T6G(SCH_1):PAGE199_I60@PURE_QUANTA.Q_RES(CHIPS)':
 'B': CDS_PINID='B';
NODE_NAME     PR406 2
 '@T6G_MB_LIB.T6G(SCH_1):PAGE199_I70@PURE_QUANTA.Q_RES(CHIPS)':
 'B': CDS_PINID='B';
NODE_NAME     PC96 2
 '@T6G_MB_LIB.T6G(SCH_1):PAGE199_I72@PURE_QUANTA.Q_CAP(CHIPS)':
 'B': CDS_PINID='B';
NODE_NAME     PC95 2
 '@T6G_MB_LIB.T6G(SCH_1):PAGE199_I73@PURE_QUANTA.Q_CAP(CHIPS)':
 'B': CDS_PINID='B';
NODE_NAME     PC644 2
 '@T6G_MB_LIB.T6G(SCH_1):PAGE199_I80@PURE_QUANTA.Q_CAP(CHIPS)':
 'B': CDS_PINID='B';
NODE_NAME     PC645 2
 '@T6G_MB_LIB.T6G(SCH_1):PAGE199_I81@PURE_QUANTA.Q_CAP(CHIPS)':
 'B': CDS_PINID='B';
NODE_NAME     PU54 31
 '@T6G_MB_LIB.T6G(SCH_1):PAGE199_I86@PURE_QUANTA.RAA229621GNPHA0(CHIPS)':
 'RGND1': CDS_PINID='RGND1';
NODE_NAME     PU54 18
 '@T6G_MB_LIB.T6G(SCH_1):PAGE199_I86@PURE_QUANTA.RAA229621GNPHA0(CHIPS)':
 'SVC': CDS_PINID='SVC';
NODE_NAME     PU54 17
 '@T6G_MB_LIB.T6G(SCH_1):PAGE199_I86@PURE_QUANTA.RAA229621GNPHA0(CHIPS)':
 'SVD': CDS_PINID='SVD';
NODE_NAME     PU54 20
 '@T6G_MB_LIB.T6G(SCH_1):PAGE199_I86@PURE_QUANTA.RAA229621GNPHA0(CHIPS)':
 'SVTI': CDS_PINID='SVTI';
NODE_NAME     PU54 TH
 '@T6G_MB_LIB.T6G(SCH_1):PAGE199_I86@PURE_QUANTA.RAA229621GNPHA0(CHIPS)':
 'TH_GND': CDS_PINID='TH_GND';
NODE_NAME     PU54 32
 '@T6G_MB_LIB.T6G(SCH_1):PAGE199_I86@PURE_QUANTA.RAA229621GNPHA0(CHIPS)':
 'VSEN1': CDS_PINID='VSEN1';
NODE_NAME     PC504_2 2
 '@T6G_MB_LIB.T6G(SCH_1):PAGE200_I8@PURE_QUANTA.Q_CAP(CHIPS)':
 'B': CDS_PINID='B';
NODE_NAME     PC506 2
 '@T6G_MB_LIB.T6G(SCH_1):PAGE200_I10@PURE_QUANTA.Q_CAP(CHIPS)':
 'B': CDS_PINID='B';
NODE_NAME     PR329 1
 '@T6G_MB_LIB.T6G(SCH_1):PAGE200_I12@PURE_QUANTA.Q_RES(CHIPS)':
 'A': CDS_PINID='A';
NODE_NAME     PC508_11P1_2 2
 '@T6G_MB_LIB.T6G(SCH_1):PAGE200_I17@PURE_QUANTA.Q_CAP(CHIPS)':
 'B': CDS_PINID='B';
NODE_NAME     PU44 2
 '@T6G_MB_LIB.T6G(SCH_1):PAGE200_I22@PURE_QUANTA.ISL99390FRZTR5935(CHIPS)':
 'AGND': CDS_PINID='AGND';
NODE_NAME     PU44 5
 '@T6G_MB_LIB.T6G(SCH_1):PAGE200_I22@PURE_QUANTA.ISL99390FRZTR5935(CHIPS)':
 'PGND1': CDS_PINID='PGND1';
NODE_NAME     PU44 7_9-20_24
 '@T6G_MB_LIB.T6G(SCH_1):PAGE200_I22@PURE_QUANTA.ISL99390FRZTR5935(CHIPS)':
 'PGND2': CDS_PINID='PGND2';
NODE_NAME     PU44 40
 '@T6G_MB_LIB.T6G(SCH_1):PAGE200_I22@PURE_QUANTA.ISL99390FRZTR5935(CHIPS)':
 'PGND3': CDS_PINID='PGND3';
NODE_NAME     PC514_2 2
 '@T6G_MB_LIB.T6G(SCH_1):PAGE200_I30@PURE_QUANTA.Q_CAP(CHIPS)':
 'B': CDS_PINID='B';
NODE_NAME     PC516_2 2
 '@T6G_MB_LIB.T6G(SCH_1):PAGE200_I31@PURE_QUANTA.Q_CAP(CHIPS)':
 'B': CDS_PINID='B';
NODE_NAME     PR520 2
 '@T6G_MB_LIB.T6G(SCH_1):PAGE200_I33@PURE_QUANTA.Q_RES(CHIPS)':
 'B': CDS_PINID='B';
NODE_NAME     PC505 2
 '@T6G_MB_LIB.T6G(SCH_1):PAGE200_I36@PURE_QUANTA.Q_CAP(CHIPS)':
 'B': CDS_PINID='B';
NODE_NAME     PC511_1 2
 '@T6G_MB_LIB.T6G(SCH_1):PAGE200_I45@PURE_QUANTA.Q_CAP(CHIPS)':
 'B': CDS_PINID='B';
NODE_NAME     PC513_1 2
 '@T6G_MB_LIB.T6G(SCH_1):PAGE200_I49@PURE_QUANTA.Q_CAP(CHIPS)':
 'B': CDS_PINID='B';
NODE_NAME     PC515_1 2
 '@T6G_MB_LIB.T6G(SCH_1):PAGE200_I50@PURE_QUANTA.Q_CAP(CHIPS)':
 'B': CDS_PINID='B';
NODE_NAME     PC517_1 2
 '@T6G_MB_LIB.T6G(SCH_1):PAGE200_I51@PURE_QUANTA.Q_CAP(CHIPS)':
 'B': CDS_PINID='B';
NODE_NAME     PC523_2 2
 '@T6G_MB_LIB.T6G(SCH_1):PAGE200_I56@PURE_QUANTA.Q_CAP(CHIPS)':
 'B': CDS_PINID='B';
NODE_NAME     PC27 2
 '@T6G_MB_LIB.T6G(SCH_1):PAGE200_I58@PURE_QUANTA.Q_CAP(CHIPS)':
 'B': CDS_PINID='B';
NODE_NAME     PC525 2
 '@T6G_MB_LIB.T6G(SCH_1):PAGE200_I62@PURE_QUANTA.Q_CAPP(CHIPS)':
 'B': CDS_PINID='B';
NODE_NAME     PC802 2
 '@T6G_MB_LIB.T6G(SCH_1):PAGE200_I65@PURE_QUANTA.Q_CAPP(CHIPS)':
 'B': CDS_PINID='B';
NODE_NAME     PC531 2
 '@T6G_MB_LIB.T6G(SCH_1):PAGE200_I72@PURE_QUANTA.Q_CAPP(CHIPS)':
 'B': CDS_PINID='B';
NODE_NAME     PC532 2
 '@T6G_MB_LIB.T6G(SCH_1):PAGE200_I73@PURE_QUANTA.Q_CAPP(CHIPS)':
 'B': CDS_PINID='B';
NODE_NAME     PC803 2
 '@T6G_MB_LIB.T6G(SCH_1):PAGE200_I75@PURE_QUANTA.Q_CAPP(CHIPS)':
 'B': CDS_PINID='B';
NODE_NAME     PC521_1 2
 '@T6G_MB_LIB.T6G(SCH_1):PAGE200_I80@PURE_QUANTA.Q_CAP(CHIPS)':
 'B': CDS_PINID='B';
NODE_NAME     PC524 2
 '@T6G_MB_LIB.T6G(SCH_1):PAGE200_I82@PURE_QUANTA.Q_CAP(CHIPS)':
 'B': CDS_PINID='B';
NODE_NAME     PC511 2
 '@T6G_MB_LIB.T6G(SCH_1):PAGE200_I85@PURE_QUANTA.Q_CAP(CHIPS)':
 'B': CDS_PINID='B';
NODE_NAME     PC526_1 2
 '@T6G_MB_LIB.T6G(SCH_1):PAGE200_I87@PURE_QUANTA.Q_CAP(CHIPS)':
 'B': CDS_PINID='B';
NODE_NAME     PC529_1 2
 '@T6G_MB_LIB.T6G(SCH_1):PAGE200_I88@PURE_QUANTA.Q_CAP(CHIPS)':
 'B': CDS_PINID='B';
NODE_NAME     PR395 2
 '@T6G_MB_LIB.T6G(SCH_1):PAGE200_I89@PURE_QUANTA.Q_RES(CHIPS)':
 'B': CDS_PINID='B';
NODE_NAME     PC512_2 2
 '@T6G_MB_LIB.T6G(SCH_1):PAGE200_I91@PURE_QUANTA.Q_CAP(CHIPS)':
 'B': CDS_PINID='B';
NODE_NAME     PU45 2
 '@T6G_MB_LIB.T6G(SCH_1):PAGE200_I92@PURE_QUANTA.ISL99390FRZTR5935(CHIPS)':
 'AGND': CDS_PINID='AGND';
NODE_NAME     PU45 5
 '@T6G_MB_LIB.T6G(SCH_1):PAGE200_I92@PURE_QUANTA.ISL99390FRZTR5935(CHIPS)':
 'PGND1': CDS_PINID='PGND1';
NODE_NAME     PU45 7_9-20_24
 '@T6G_MB_LIB.T6G(SCH_1):PAGE200_I92@PURE_QUANTA.ISL99390FRZTR5935(CHIPS)':
 'PGND2': CDS_PINID='PGND2';
NODE_NAME     PU45 40
 '@T6G_MB_LIB.T6G(SCH_1):PAGE200_I92@PURE_QUANTA.ISL99390FRZTR5935(CHIPS)':
 'PGND3': CDS_PINID='PGND3';
NODE_NAME     PR398 1
 '@T6G_MB_LIB.T6G(SCH_1):PAGE201_I14@PURE_QUANTA.Q_RES(CHIPS)':
 'A': CDS_PINID='A';
NODE_NAME     PR399 1
 '@T6G_MB_LIB.T6G(SCH_1):PAGE201_I29@PURE_QUANTA.Q_RES(CHIPS)':
 'A': CDS_PINID='A';
NODE_NAME     PC84 2
 '@T6G_MB_LIB.T6G(SCH_1):PAGE201_I40@PURE_QUANTA.Q_CAP(CHIPS)':
 'B': CDS_PINID='B';
NODE_NAME     PC87 2
 '@T6G_MB_LIB.T6G(SCH_1):PAGE201_I41@PURE_QUANTA.Q_CAP(CHIPS)':
 'B': CDS_PINID='B';
NODE_NAME     PC21 2
 '@T6G_MB_LIB.T6G(SCH_1):PAGE201_I47@PURE_QUANTA.Q_CAP(CHIPS)':
 'B': CDS_PINID='B';
NODE_NAME     PC60 2
 '@T6G_MB_LIB.T6G(SCH_1):PAGE201_I54@PURE_QUANTA.Q_CAP(CHIPS)':
 'B': CDS_PINID='B';
NODE_NAME     U18 A1
 '@T6G_MB_LIB.T6G(SCH_1):PAGE81_I1@PURE_QUANTA.LCMXO3LF9400C5BG484C(CHIPS)':
 'GND1': CDS_PINID='GND1';
NODE_NAME     U18 A22
 '@T6G_MB_LIB.T6G(SCH_1):PAGE81_I1@PURE_QUANTA.LCMXO3LF9400C5BG484C(CHIPS)':
 'GND2': CDS_PINID='GND2';
NODE_NAME     U18 B7
 '@T6G_MB_LIB.T6G(SCH_1):PAGE81_I1@PURE_QUANTA.LCMXO3LF9400C5BG484C(CHIPS)':
 'GND3': CDS_PINID='GND3';
NODE_NAME     U18 B16
 '@T6G_MB_LIB.T6G(SCH_1):PAGE81_I1@PURE_QUANTA.LCMXO3LF9400C5BG484C(CHIPS)':
 'GND4': CDS_PINID='GND4';
NODE_NAME     U18 C2
 '@T6G_MB_LIB.T6G(SCH_1):PAGE81_I1@PURE_QUANTA.LCMXO3LF9400C5BG484C(CHIPS)':
 'GND5': CDS_PINID='GND5';
NODE_NAME     U18 C11
 '@T6G_MB_LIB.T6G(SCH_1):PAGE81_I1@PURE_QUANTA.LCMXO3LF9400C5BG484C(CHIPS)':
 'GND6': CDS_PINID='GND6';
NODE_NAME     U18 E5
 '@T6G_MB_LIB.T6G(SCH_1):PAGE81_I1@PURE_QUANTA.LCMXO3LF9400C5BG484C(CHIPS)':
 'GND7': CDS_PINID='GND7';
NODE_NAME     U18 E18
 '@T6G_MB_LIB.T6G(SCH_1):PAGE81_I1@PURE_QUANTA.LCMXO3LF9400C5BG484C(CHIPS)':
 'GND8': CDS_PINID='GND8';
NODE_NAME     U18 F2
 '@T6G_MB_LIB.T6G(SCH_1):PAGE81_I1@PURE_QUANTA.LCMXO3LF9400C5BG484C(CHIPS)':
 'GND9': CDS_PINID='GND9';
NODE_NAME     U18 F21
 '@T6G_MB_LIB.T6G(SCH_1):PAGE81_I1@PURE_QUANTA.LCMXO3LF9400C5BG484C(CHIPS)':
 'GND10': CDS_PINID='GND10';
NODE_NAME     U18 H8
 '@T6G_MB_LIB.T6G(SCH_1):PAGE81_I1@PURE_QUANTA.LCMXO3LF9400C5BG484C(CHIPS)':
 'GND11': CDS_PINID='GND11';
NODE_NAME     U18 H10
 '@T6G_MB_LIB.T6G(SCH_1):PAGE81_I1@PURE_QUANTA.LCMXO3LF9400C5BG484C(CHIPS)':
 'GND12': CDS_PINID='GND12';
NODE_NAME     U18 H13
 '@T6G_MB_LIB.T6G(SCH_1):PAGE81_I1@PURE_QUANTA.LCMXO3LF9400C5BG484C(CHIPS)':
 'GND13': CDS_PINID='GND13';
NODE_NAME     U18 H15
 '@T6G_MB_LIB.T6G(SCH_1):PAGE81_I1@PURE_QUANTA.LCMXO3LF9400C5BG484C(CHIPS)':
 'GND14': CDS_PINID='GND14';
NODE_NAME     U18 J9
 '@T6G_MB_LIB.T6G(SCH_1):PAGE81_I1@PURE_QUANTA.LCMXO3LF9400C5BG484C(CHIPS)':
 'GND15': CDS_PINID='GND15';
NODE_NAME     U18 J10
 '@T6G_MB_LIB.T6G(SCH_1):PAGE81_I1@PURE_QUANTA.LCMXO3LF9400C5BG484C(CHIPS)':
 'GND16': CDS_PINID='GND16';
NODE_NAME     U18 J11
 '@T6G_MB_LIB.T6G(SCH_1):PAGE81_I1@PURE_QUANTA.LCMXO3LF9400C5BG484C(CHIPS)':
 'GND17': CDS_PINID='GND17';
NODE_NAME     U18 J12
 '@T6G_MB_LIB.T6G(SCH_1):PAGE81_I1@PURE_QUANTA.LCMXO3LF9400C5BG484C(CHIPS)':
 'GND18': CDS_PINID='GND18';
NODE_NAME     U18 J13
 '@T6G_MB_LIB.T6G(SCH_1):PAGE81_I1@PURE_QUANTA.LCMXO3LF9400C5BG484C(CHIPS)':
 'GND19': CDS_PINID='GND19';
NODE_NAME     U18 J14
 '@T6G_MB_LIB.T6G(SCH_1):PAGE81_I1@PURE_QUANTA.LCMXO3LF9400C5BG484C(CHIPS)':
 'GND20': CDS_PINID='GND20';
NODE_NAME     U18 K9
 '@T6G_MB_LIB.T6G(SCH_1):PAGE81_I1@PURE_QUANTA.LCMXO3LF9400C5BG484C(CHIPS)':
 'GND21': CDS_PINID='GND21';
NODE_NAME     U18 K14
 '@T6G_MB_LIB.T6G(SCH_1):PAGE81_I1@PURE_QUANTA.LCMXO3LF9400C5BG484C(CHIPS)':
 'GND22': CDS_PINID='GND22';
NODE_NAME     U18 K21
 '@T6G_MB_LIB.T6G(SCH_1):PAGE81_I1@PURE_QUANTA.LCMXO3LF9400C5BG484C(CHIPS)':
 'GND23': CDS_PINID='GND23';
NODE_NAME     U18 L2
 '@T6G_MB_LIB.T6G(SCH_1):PAGE81_I1@PURE_QUANTA.LCMXO3LF9400C5BG484C(CHIPS)':
 'GND24': CDS_PINID='GND24';
NODE_NAME     U18 L9
 '@T6G_MB_LIB.T6G(SCH_1):PAGE81_I1@PURE_QUANTA.LCMXO3LF9400C5BG484C(CHIPS)':
 'GND25': CDS_PINID='GND25';
NODE_NAME     U18 L10
 '@T6G_MB_LIB.T6G(SCH_1):PAGE81_I1@PURE_QUANTA.LCMXO3LF9400C5BG484C(CHIPS)':
 'GND26': CDS_PINID='GND26';
NODE_NAME     U18 L13
 '@T6G_MB_LIB.T6G(SCH_1):PAGE81_I1@PURE_QUANTA.LCMXO3LF9400C5BG484C(CHIPS)':
 'GND27': CDS_PINID='GND27';
NODE_NAME     U18 L14
 '@T6G_MB_LIB.T6G(SCH_1):PAGE81_I1@PURE_QUANTA.LCMXO3LF9400C5BG484C(CHIPS)':
 'GND28': CDS_PINID='GND28';
NODE_NAME     U18 L18
 '@T6G_MB_LIB.T6G(SCH_1):PAGE81_I1@PURE_QUANTA.LCMXO3LF9400C5BG484C(CHIPS)':
 'GND29': CDS_PINID='GND29';
NODE_NAME     U18 M4
 '@T6G_MB_LIB.T6G(SCH_1):PAGE81_I1@PURE_QUANTA.LCMXO3LF9400C5BG484C(CHIPS)':
 'GND30': CDS_PINID='GND30';
NODE_NAME     U18 M9
 '@T6G_MB_LIB.T6G(SCH_1):PAGE81_I1@PURE_QUANTA.LCMXO3LF9400C5BG484C(CHIPS)':
 'GND31': CDS_PINID='GND31';
NODE_NAME     U18 M10
 '@T6G_MB_LIB.T6G(SCH_1):PAGE81_I1@PURE_QUANTA.LCMXO3LF9400C5BG484C(CHIPS)':
 'GND32': CDS_PINID='GND32';
NODE_NAME     U18 M13
 '@T6G_MB_LIB.T6G(SCH_1):PAGE81_I1@PURE_QUANTA.LCMXO3LF9400C5BG484C(CHIPS)':
 'GND33': CDS_PINID='GND33';
NODE_NAME     U18 M14
 '@T6G_MB_LIB.T6G(SCH_1):PAGE81_I1@PURE_QUANTA.LCMXO3LF9400C5BG484C(CHIPS)':
 'GND34': CDS_PINID='GND34';
NODE_NAME     U18 N9
 '@T6G_MB_LIB.T6G(SCH_1):PAGE81_I1@PURE_QUANTA.LCMXO3LF9400C5BG484C(CHIPS)':
 'GND35': CDS_PINID='GND35';
NODE_NAME     U18 N14
 '@T6G_MB_LIB.T6G(SCH_1):PAGE81_I1@PURE_QUANTA.LCMXO3LF9400C5BG484C(CHIPS)':
 'GND36': CDS_PINID='GND36';
NODE_NAME     U18 N21
 '@T6G_MB_LIB.T6G(SCH_1):PAGE81_I1@PURE_QUANTA.LCMXO3LF9400C5BG484C(CHIPS)':
 'GND37': CDS_PINID='GND37';
NODE_NAME     U18 P9
 '@T6G_MB_LIB.T6G(SCH_1):PAGE81_I1@PURE_QUANTA.LCMXO3LF9400C5BG484C(CHIPS)':
 'GND38': CDS_PINID='GND38';
NODE_NAME     U18 P10
 '@T6G_MB_LIB.T6G(SCH_1):PAGE81_I1@PURE_QUANTA.LCMXO3LF9400C5BG484C(CHIPS)':
 'GND39': CDS_PINID='GND39';
NODE_NAME     U18 P11
 '@T6G_MB_LIB.T6G(SCH_1):PAGE81_I1@PURE_QUANTA.LCMXO3LF9400C5BG484C(CHIPS)':
 'GND40': CDS_PINID='GND40';
NODE_NAME     U18 P12
 '@T6G_MB_LIB.T6G(SCH_1):PAGE81_I1@PURE_QUANTA.LCMXO3LF9400C5BG484C(CHIPS)':
 'GND41': CDS_PINID='GND41';
NODE_NAME     U18 P13
 '@T6G_MB_LIB.T6G(SCH_1):PAGE81_I1@PURE_QUANTA.LCMXO3LF9400C5BG484C(CHIPS)':
 'GND42': CDS_PINID='GND42';
NODE_NAME     U18 P14
 '@T6G_MB_LIB.T6G(SCH_1):PAGE81_I1@PURE_QUANTA.LCMXO3LF9400C5BG484C(CHIPS)':
 'GND43': CDS_PINID='GND43';
NODE_NAME     U18 R8
 '@T6G_MB_LIB.T6G(SCH_1):PAGE81_I1@PURE_QUANTA.LCMXO3LF9400C5BG484C(CHIPS)':
 'GND44': CDS_PINID='GND44';
NODE_NAME     U18 R15
 '@T6G_MB_LIB.T6G(SCH_1):PAGE81_I1@PURE_QUANTA.LCMXO3LF9400C5BG484C(CHIPS)':
 'GND45': CDS_PINID='GND45';
NODE_NAME     U18 V2
 '@T6G_MB_LIB.T6G(SCH_1):PAGE81_I1@PURE_QUANTA.LCMXO3LF9400C5BG484C(CHIPS)':
 'GND46': CDS_PINID='GND46';
NODE_NAME     U18 V21
 '@T6G_MB_LIB.T6G(SCH_1):PAGE81_I1@PURE_QUANTA.LCMXO3LF9400C5BG484C(CHIPS)':
 'GND47': CDS_PINID='GND47';
NODE_NAME     U18 W12
 '@T6G_MB_LIB.T6G(SCH_1):PAGE81_I1@PURE_QUANTA.LCMXO3LF9400C5BG484C(CHIPS)':
 'GND48': CDS_PINID='GND48';
NODE_NAME     U18 Y7
 '@T6G_MB_LIB.T6G(SCH_1):PAGE81_I1@PURE_QUANTA.LCMXO3LF9400C5BG484C(CHIPS)':
 'GND49': CDS_PINID='GND49';
NODE_NAME     U18 Y16
 '@T6G_MB_LIB.T6G(SCH_1):PAGE81_I1@PURE_QUANTA.LCMXO3LF9400C5BG484C(CHIPS)':
 'GND50': CDS_PINID='GND50';
NODE_NAME     U18 AB1
 '@T6G_MB_LIB.T6G(SCH_1):PAGE81_I1@PURE_QUANTA.LCMXO3LF9400C5BG484C(CHIPS)':
 'GND51': CDS_PINID='GND51';
NODE_NAME     U18 AB22
 '@T6G_MB_LIB.T6G(SCH_1):PAGE81_I1@PURE_QUANTA.LCMXO3LF9400C5BG484C(CHIPS)':
 'GND52': CDS_PINID='GND52';
NODE_NAME     C1133 2
 '@T6G_MB_LIB.T6G(SCH_1):PAGE82_I81@PURE_QUANTA.Q_CAP(CHIPS)':
 'B': CDS_PINID='B';
NODE_NAME     R10 2
 '@T6G_MB_LIB.T6G(SCH_1):PAGE82_I93@PURE_QUANTA.Q_RES(CHIPS)':
 'B': CDS_PINID='B';
NODE_NAME     R11 2
 '@T6G_MB_LIB.T6G(SCH_1):PAGE82_I94@PURE_QUANTA.Q_RES(CHIPS)':
 'B': CDS_PINID='B';
NODE_NAME     R12 2
 '@T6G_MB_LIB.T6G(SCH_1):PAGE82_I95@PURE_QUANTA.Q_RES(CHIPS)':
 'B': CDS_PINID='B';
NODE_NAME     C362 2
 '@T6G_MB_LIB.T6G(SCH_1):PAGE82_I102@PURE_QUANTA.Q_CAP(CHIPS)':
 'B': CDS_PINID='B';
NODE_NAME     C360 2
 '@T6G_MB_LIB.T6G(SCH_1):PAGE82_I103@PURE_QUANTA.Q_CAP(CHIPS)':
 'B': CDS_PINID='B';
NODE_NAME     C361 2
 '@T6G_MB_LIB.T6G(SCH_1):PAGE82_I104@PURE_QUANTA.Q_CAP(CHIPS)':
 'B': CDS_PINID='B';
NODE_NAME     R800 2
 '@T6G_MB_LIB.T6G(SCH_1):PAGE82_I118@PURE_QUANTA.Q_RES(CHIPS)':
 'B': CDS_PINID='B';
NODE_NAME     R16 2
 '@T6G_MB_LIB.T6G(SCH_1):PAGE82_I124@PURE_QUANTA.Q_RES(CHIPS)':
 'B': CDS_PINID='B';
NODE_NAME     R17 2
 '@T6G_MB_LIB.T6G(SCH_1):PAGE82_I125@PURE_QUANTA.Q_RES(CHIPS)':
 'B': CDS_PINID='B';
NODE_NAME     C359 2
 '@T6G_MB_LIB.T6G(SCH_1):PAGE82_I135@PURE_QUANTA.Q_CAP(CHIPS)':
 'B': CDS_PINID='B';
NODE_NAME     R6144 2
 '@T6G_MB_LIB.T6G(SCH_1):PAGE83_I52@PURE_QUANTA.Q_RES(CHIPS)':
 'B': CDS_PINID='B';
NODE_NAME     Q28 1
 '@T6G_MB_LIB.T6G(SCH_1):PAGE84_I48@PURE_QUANTA.MOSFET_DUAL_6P(CHIPS)':
 'S1': CDS_PINID='S1';
NODE_NAME     Q28 4
 '@T6G_MB_LIB.T6G(SCH_1):PAGE84_I48@PURE_QUANTA.MOSFET_DUAL_6P(CHIPS)':
 'S2': CDS_PINID='S2';
NODE_NAME     R6028 2
 '@T6G_MB_LIB.T6G(SCH_1):PAGE348_I174@PURE_QUANTA.Q_RES(CHIPS)':
 'B': CDS_PINID='B';
NODE_NAME     C62 2
 '@T6G_MB_LIB.T6G(SCH_1):PAGE349_I69@PURE_QUANTA.Q_CAP(CHIPS)':
 'B': CDS_PINID='B';
NODE_NAME     R889 2
 '@T6G_MB_LIB.T6G(SCH_1):PAGE349_I142@PURE_QUANTA.Q_RES(CHIPS)':
 'B': CDS_PINID='B';
NODE_NAME     R891 2
 '@T6G_MB_LIB.T6G(SCH_1):PAGE349_I144@PURE_QUANTA.Q_RES(CHIPS)':
 'B': CDS_PINID='B';
NODE_NAME     PC2340 2
 '@T6G_MB_LIB.T6G(SCH_1):PAGE350_I6@PURE_QUANTA.Q_CAP(CHIPS)':
 'B': CDS_PINID='B';
NODE_NAME     Q39 S
 '@T6G_MB_LIB.T6G(SCH_1):PAGE350_I9@PURE_QUANTA.MOSFET_NCH_GDS_ESD_PROTECTED(CHIPS)':
 'S': CDS_PINID='S';
NODE_NAME     Q125 1
 '@T6G_MB_LIB.T6G(SCH_1):PAGE350_I22@PURE_QUANTA.MOSFET_NCH_DUAL(CHIPS)':
 'S1': CDS_PINID='S1';
NODE_NAME     Q125 4
 '@T6G_MB_LIB.T6G(SCH_1):PAGE350_I24@PURE_QUANTA.MOSFET_NCH_DUAL(CHIPS)':
 'S2': CDS_PINID='S2';
NODE_NAME     PD115 A
 '@T6G_MB_LIB.T6G(SCH_1):PAGE350_I28@PURE_QUANTA.DIODE_TVS(CHIPS)':
 'A': CDS_PINID='A';
NODE_NAME     PR4005 2
 '@T6G_MB_LIB.T6G(SCH_1):PAGE350_I35@PURE_QUANTA.Q_RES(CHIPS)':
 'B': CDS_PINID='B';
NODE_NAME     PR4011 2
 '@T6G_MB_LIB.T6G(SCH_1):PAGE350_I49@PURE_QUANTA.Q_RES(CHIPS)':
 'B': CDS_PINID='B';
NODE_NAME     PU300 A7
 '@T6G_MB_LIB.T6G(SCH_1):PAGE350_I86@PURE_QUANTA.MAX15090BEWIT(CHIPS)':
 'CDLY': CDS_PINID='CDLY';
NODE_NAME     PU300 B7
 '@T6G_MB_LIB.T6G(SCH_1):PAGE350_I86@PURE_QUANTA.MAX15090BEWIT(CHIPS)':
 'EN#': CDS_PINID='\en#\';
NODE_NAME     PU300 B2
 '@T6G_MB_LIB.T6G(SCH_1):PAGE350_I86@PURE_QUANTA.MAX15090BEWIT(CHIPS)':
 'GND_B2': CDS_PINID='GND_B2';
NODE_NAME     PU300 C1
 '@T6G_MB_LIB.T6G(SCH_1):PAGE350_I86@PURE_QUANTA.MAX15090BEWIT(CHIPS)':
 'GND_C1': CDS_PINID='GND_C1';
NODE_NAME     PU300 C2
 '@T6G_MB_LIB.T6G(SCH_1):PAGE350_I86@PURE_QUANTA.MAX15090BEWIT(CHIPS)':
 'GND_C2': CDS_PINID='GND_C2';
NODE_NAME     J6 2
 '@T6G_MB_LIB.T6G(SCH_1):PAGE28_I28@PURE_QUANTA.CONN6_HBC1031L200D8H(CHIPS)':
 '2': CDS_PINID='\2\';
NODE_NAME     J6 4
 '@T6G_MB_LIB.T6G(SCH_1):PAGE28_I28@PURE_QUANTA.CONN6_HBC1031L200D8H(CHIPS)':
 '4': CDS_PINID='\4\';
NODE_NAME     J6 6
 '@T6G_MB_LIB.T6G(SCH_1):PAGE28_I28@PURE_QUANTA.CONN6_HBC1031L200D8H(CHIPS)':
 '6': CDS_PINID='\6\';
NODE_NAME     R582 1
 '@T6G_MB_LIB.T6G(SCH_1):PAGE28_I33@PURE_QUANTA.Q_RES(CHIPS)':
 'A': CDS_PINID='A';
NODE_NAME     R287 1
 '@T6G_MB_LIB.T6G(SCH_1):PAGE28_I36@PURE_QUANTA.Q_RES(CHIPS)':
 'A': CDS_PINID='A';
NODE_NAME     R440 1
 '@T6G_MB_LIB.T6G(SCH_1):PAGE28_I37@PURE_QUANTA.Q_RES(CHIPS)':
 'A': CDS_PINID='A';
NODE_NAME     R5026 1
 '@T6G_MB_LIB.T6G(SCH_1):PAGE28_I40@PURE_QUANTA.Q_RES(CHIPS)':
 'A': CDS_PINID='A';
NODE_NAME     R5027 1
 '@T6G_MB_LIB.T6G(SCH_1):PAGE28_I59@PURE_QUANTA.Q_RES(CHIPS)':
 'A': CDS_PINID='A';
NODE_NAME     R5028 1
 '@T6G_MB_LIB.T6G(SCH_1):PAGE28_I60@PURE_QUANTA.Q_RES(CHIPS)':
 'A': CDS_PINID='A';
NODE_NAME     R5029 1
 '@T6G_MB_LIB.T6G(SCH_1):PAGE28_I62@PURE_QUANTA.Q_RES(CHIPS)':
 'A': CDS_PINID='A';
NODE_NAME     Y2 2
 '@T6G_MB_LIB.T6G(SCH_1):PAGE28_I103@PURE_QUANTA.Q_XTAL_4P_13BI_24GND(CHIPS)':
 'G1': CDS_PINID='G1';
NODE_NAME     Y2 4
 '@T6G_MB_LIB.T6G(SCH_1):PAGE28_I103@PURE_QUANTA.Q_XTAL_4P_13BI_24GND(CHIPS)':
 'G2': CDS_PINID='G2';
NODE_NAME     PC2241 2
 '@T6G_MB_LIB.T6G(SCH_1):PAGE350_I56@PURE_QUANTA.Q_CAP(CHIPS)':
 'B': CDS_PINID='B';
NODE_NAME     PR4002 2
 '@T6G_MB_LIB.T6G(SCH_1):PAGE350_I60@PURE_QUANTA.Q_RES(CHIPS)':
 'B': CDS_PINID='B';
NODE_NAME     PC2240 2
 '@T6G_MB_LIB.T6G(SCH_1):PAGE350_I81@PURE_QUANTA.Q_CAP(CHIPS)':
 'B': CDS_PINID='B';
NODE_NAME     PC2242 2
 '@T6G_MB_LIB.T6G(SCH_1):PAGE350_I84@PURE_QUANTA.Q_CAP(CHIPS)':
 'B': CDS_PINID='B';
NODE_NAME     C1274 2
 '@T6G_MB_LIB.T6G(SCH_1):PAGE337_I3@PURE_QUANTA.Q_CAP(CHIPS)':
 'B': CDS_PINID='B';
NODE_NAME     OSC1 2
 '@T6G_MB_LIB.T6G(SCH_1):PAGE337_I4@PURE_QUANTA.Q_OSC4P(CHIPS)':
 'GND': CDS_PINID='GND';
NODE_NAME     U8082 3
 '@T6G_MB_LIB.T6G(SCH_1):PAGE337_I8@PURE_QUANTA.74LVC1G126SE7(CHIPS)':
 'GND': CDS_PINID='GND';
NODE_NAME     U90 4
 '@T6G_MB_LIB.T6G(SCH_1):PAGE337_I16@PURE_QUANTA.PI6CV304LE(CHIPS)':
 'GND': CDS_PINID='GND';
NODE_NAME     C1275 2
 '@T6G_MB_LIB.T6G(SCH_1):PAGE337_I19@PURE_QUANTA.Q_CAP(CHIPS)':
 'B': CDS_PINID='B';
NODE_NAME     U157 3
 '@T6G_MB_LIB.T6G(SCH_1):PAGE337_I25@PURE_QUANTA.74LVC1G07GV(CHIPS)':
 'GND': CDS_PINID='GND';
NODE_NAME     C36 2
 '@T6G_MB_LIB.T6G(SCH_1):PAGE337_I33@PURE_QUANTA.Q_CAP(CHIPS)':
 'B': CDS_PINID='B';
NODE_NAME     U104 3
 '@T6G_MB_LIB.T6G(SCH_1):PAGE337_I38@PURE_QUANTA.74LVC1G07GV(CHIPS)':
 'GND': CDS_PINID='GND';
NODE_NAME     C1663 2
 '@T6G_MB_LIB.T6G(SCH_1):PAGE337_I47@PURE_QUANTA.Q_CAP(CHIPS)':
 'B': CDS_PINID='B';
NODE_NAME     U225 3
 '@T6G_MB_LIB.T6G(SCH_1):PAGE342_I9@PURE_QUANTA.74LVC1G126SE7(CHIPS)':
 'GND': CDS_PINID='GND';
NODE_NAME     U217 3
 '@T6G_MB_LIB.T6G(SCH_1):PAGE342_I14@PURE_QUANTA.74LVC1G126SE7(CHIPS)':
 'GND': CDS_PINID='GND';
NODE_NAME     C1822 2
 '@T6G_MB_LIB.T6G(SCH_1):PAGE342_I16@PURE_QUANTA.Q_CAP(CHIPS)':
 'B': CDS_PINID='B';
NODE_NAME     U218 3
 '@T6G_MB_LIB.T6G(SCH_1):PAGE342_I22@PURE_QUANTA.74LVC1G07GV(CHIPS)':
 'GND': CDS_PINID='GND';
NODE_NAME     U219 3
 '@T6G_MB_LIB.T6G(SCH_1):PAGE342_I32@PURE_QUANTA.74LVC1G07GV(CHIPS)':
 'GND': CDS_PINID='GND';
NODE_NAME     U59 2
 '@T6G_MB_LIB.T6G(SCH_1):PAGE343_I22@PURE_QUANTA.74LVC2G07DW7(CHIPS)':
 'GND': CDS_PINID='GND';
NODE_NAME     C1810 2
 '@T6G_MB_LIB.T6G(SCH_1):PAGE343_I23@PURE_QUANTA.Q_CAP(CHIPS)':
 'B': CDS_PINID='B';
NODE_NAME     C1809 2
 '@T6G_MB_LIB.T6G(SCH_1):PAGE343_I29@PURE_QUANTA.Q_CAP(CHIPS)':
 'B': CDS_PINID='B';
NODE_NAME     PR3828 2
 '@T6G_MB_LIB.T6G(SCH_1):PAGE343_I31@PURE_QUANTA.Q_RES(CHIPS)':
 'B': CDS_PINID='B';
NODE_NAME     PC2140 2
 '@T6G_MB_LIB.T6G(SCH_1):PAGE343_I55@PURE_QUANTA.Q_CAP(CHIPS)':
 'B': CDS_PINID='B';
NODE_NAME     PC2150 2
 '@T6G_MB_LIB.T6G(SCH_1):PAGE343_I75@PURE_QUANTA.Q_CAP(CHIPS)':
 'B': CDS_PINID='B';
NODE_NAME     PC2151 2
 '@T6G_MB_LIB.T6G(SCH_1):PAGE343_I95@PURE_QUANTA.Q_CAP(CHIPS)':
 'B': CDS_PINID='B';
NODE_NAME     PD109 A
 '@T6G_MB_LIB.T6G(SCH_1):PAGE343_I106@PURE_QUANTA.SCHOTTKY_AC(CHIPS)':
 'A': CDS_PINID='A';
NODE_NAME     PC2137 2
 '@T6G_MB_LIB.T6G(SCH_1):PAGE343_I108@PURE_QUANTA.Q_CAP(CHIPS)':
 'B': CDS_PINID='B';
NODE_NAME     PC2142 2
 '@T6G_MB_LIB.T6G(SCH_1):PAGE343_I112@PURE_QUANTA.Q_CAP(CHIPS)':
 'B': CDS_PINID='B';
NODE_NAME     R4568 2
 '@T6G_MB_LIB.T6G(SCH_1):PAGE369_I7@PURE_QUANTA.Q_RES(CHIPS)':
 'B': CDS_PINID='B';
NODE_NAME     R1791 2
 '@T6G_MB_LIB.T6G(SCH_1):PAGE369_I14@PURE_QUANTA.Q_RES(CHIPS)':
 'B': CDS_PINID='B';
NODE_NAME     C2049 2
 '@T6G_MB_LIB.T6G(SCH_1):PAGE369_I17@PURE_QUANTA.Q_CAP(CHIPS)':
 'B': CDS_PINID='B';
NODE_NAME     R2843 2
 '@T6G_MB_LIB.T6G(SCH_1):PAGE369_I20@PURE_QUANTA.Q_RES(CHIPS)':
 'B': CDS_PINID='B';
NODE_NAME     R1785 2
 '@T6G_MB_LIB.T6G(SCH_1):PAGE369_I26@PURE_QUANTA.Q_RES(CHIPS)':
 'B': CDS_PINID='B';
NODE_NAME     C2048 2
 '@T6G_MB_LIB.T6G(SCH_1):PAGE369_I32@PURE_QUANTA.Q_CAP(CHIPS)':
 'B': CDS_PINID='B';
NODE_NAME     C2050 2
 '@T6G_MB_LIB.T6G(SCH_1):PAGE369_I34@PURE_QUANTA.Q_CAP(CHIPS)':
 'B': CDS_PINID='B';
NODE_NAME     C2045 2
 '@T6G_MB_LIB.T6G(SCH_1):PAGE369_I36@PURE_QUANTA.Q_CAP(CHIPS)':
 'B': CDS_PINID='B';
NODE_NAME     R3668 2
 '@T6G_MB_LIB.T6G(SCH_1):PAGE369_I38@PURE_QUANTA.Q_RES(CHIPS)':
 'B': CDS_PINID='B';
NODE_NAME     R3670 2
 '@T6G_MB_LIB.T6G(SCH_1):PAGE369_I40@PURE_QUANTA.Q_RES(CHIPS)':
 'B': CDS_PINID='B';
NODE_NAME     C2046 2
 '@T6G_MB_LIB.T6G(SCH_1):PAGE369_I44@PURE_QUANTA.Q_CAP(CHIPS)':
 'B': CDS_PINID='B';
NODE_NAME     C1344 2
 '@T6G_MB_LIB.T6G(SCH_1):PAGE369_I46@PURE_QUANTA.Q_CAP(CHIPS)':
 'B': CDS_PINID='B';
NODE_NAME     C2044 2
 '@T6G_MB_LIB.T6G(SCH_1):PAGE369_I52@PURE_QUANTA.Q_CAP(CHIPS)':
 'B': CDS_PINID='B';
NODE_NAME     C2043 2
 '@T6G_MB_LIB.T6G(SCH_1):PAGE369_I55@PURE_QUANTA.Q_CAP(CHIPS)':
 'B': CDS_PINID='B';
NODE_NAME     C2051 2
 '@T6G_MB_LIB.T6G(SCH_1):PAGE369_I71@PURE_QUANTA.Q_CAP(CHIPS)':
 'B': CDS_PINID='B';
NODE_NAME     C2052 2
 '@T6G_MB_LIB.T6G(SCH_1):PAGE369_I72@PURE_QUANTA.Q_CAP(CHIPS)':
 'B': CDS_PINID='B';
NODE_NAME     C2194 2
 '@T6G_MB_LIB.T6G(SCH_1):PAGE369_I76@PURE_QUANTA.Q_CAP(CHIPS)':
 'B': CDS_PINID='B';
NODE_NAME     C35 2
 '@T6G_MB_LIB.T6G(SCH_1):PAGE369_I78@PURE_QUANTA.Q_CAP(CHIPS)':
 'B': CDS_PINID='B';
NODE_NAME     C33 2
 '@T6G_MB_LIB.T6G(SCH_1):PAGE369_I84@PURE_QUANTA.Q_CAP(CHIPS)':
 'B': CDS_PINID='B';
NODE_NAME     C59 2
 '@T6G_MB_LIB.T6G(SCH_1):PAGE369_I87@PURE_QUANTA.Q_CAP(CHIPS)':
 'B': CDS_PINID='B';
NODE_NAME     C2047 2
 '@T6G_MB_LIB.T6G(SCH_1):PAGE369_I98@PURE_QUANTA.Q_CAP(CHIPS)':
 'B': CDS_PINID='B';
NODE_NAME     C2042 2
 '@T6G_MB_LIB.T6G(SCH_1):PAGE369_I99@PURE_QUANTA.Q_CAP(CHIPS)':
 'B': CDS_PINID='B';
NODE_NAME     C37 2
 '@T6G_MB_LIB.T6G(SCH_1):PAGE369_I112@PURE_QUANTA.Q_CAP(CHIPS)':
 'B': CDS_PINID='B';
NODE_NAME     C2176 2
 '@T6G_MB_LIB.T6G(SCH_1):PAGE369_I114@PURE_QUANTA.Q_CAP(CHIPS)':
 'B': CDS_PINID='B';
NODE_NAME     C1347 2
 '@T6G_MB_LIB.T6G(SCH_1):PAGE369_I119@PURE_QUANTA.Q_CAP(CHIPS)':
 'B': CDS_PINID='B';
NODE_NAME     C1767 2
 '@T6G_MB_LIB.T6G(SCH_1):PAGE369_I121@PURE_QUANTA.Q_CAP(CHIPS)':
 'B': CDS_PINID='B';
NODE_NAME     R3690 2
 '@T6G_MB_LIB.T6G(SCH_1):PAGE369_I130@PURE_QUANTA.Q_RES(CHIPS)':
 'B': CDS_PINID='B';
NODE_NAME     U269 4
 '@T6G_MB_LIB.T6G(SCH_1):PAGE369_I142@PURE_QUANTA.ADC128D818CIMTXNOPB(CHIPS)':
 'GND': CDS_PINID='GND';
NODE_NAME     C1757 2
 '@T6G_MB_LIB.T6G(SCH_1):PAGE369_I162@PURE_QUANTA.Q_CAP(CHIPS)':
 'B': CDS_PINID='B';
NODE_NAME     C1768 2
 '@T6G_MB_LIB.T6G(SCH_1):PAGE369_I166@PURE_QUANTA.Q_CAP(CHIPS)':
 'B': CDS_PINID='B';
NODE_NAME     U193 4
 '@T6G_MB_LIB.T6G(SCH_1):PAGE369_I169@PURE_QUANTA.MAX11617EEET(CHIPS)':
 'AIN8': CDS_PINID='AIN8';
NODE_NAME     U193 3
 '@T6G_MB_LIB.T6G(SCH_1):PAGE369_I169@PURE_QUANTA.MAX11617EEET(CHIPS)':
 'AIN9': CDS_PINID='AIN9';
NODE_NAME     U193 2
 '@T6G_MB_LIB.T6G(SCH_1):PAGE369_I169@PURE_QUANTA.MAX11617EEET(CHIPS)':
 'AIN10': CDS_PINID='AIN10';
NODE_NAME     U193 15
 '@T6G_MB_LIB.T6G(SCH_1):PAGE369_I169@PURE_QUANTA.MAX11617EEET(CHIPS)':
 'GND': CDS_PINID='GND';
NODE_NAME     Q50 1
 '@T6G_MB_LIB.T6G(SCH_1):PAGE84_I65@PURE_QUANTA.MOSFET_NCH_DUAL(CHIPS)':
 'S1': CDS_PINID='S1';
NODE_NAME     Q50 4
 '@T6G_MB_LIB.T6G(SCH_1):PAGE84_I73@PURE_QUANTA.MOSFET_NCH_DUAL(CHIPS)':
 'S2': CDS_PINID='S2';
NODE_NAME     C5023 2
 '@T6G_MB_LIB.T6G(SCH_1):PAGE28_I194@PURE_QUANTA.Q_CAP(CHIPS)':
 'B': CDS_PINID='B';
NODE_NAME     C5024 2
 '@T6G_MB_LIB.T6G(SCH_1):PAGE55_I388@PURE_QUANTA.Q_CAP(CHIPS)':
 'B': CDS_PINID='B';
NODE_NAME     R6114 2
 '@T6G_MB_LIB.T6G(SCH_1):PAGE82_I137@PURE_QUANTA.Q_RES(CHIPS)':
 'B': CDS_PINID='B';
NODE_NAME     H53 1
 '@T6G_MB_LIB.T6G(SCH_1):PAGE212_I4@PURE_QUANTA.HOLE(CHIPS)':
 '1': CDS_PINID='\1\';
NODE_NAME     H21 1
 '@T6G_MB_LIB.T6G(SCH_1):PAGE212_I5@PURE_QUANTA.HOLE(CHIPS)':
 '1': CDS_PINID='\1\';
NODE_NAME     H8027 1
 '@T6G_MB_LIB.T6G(SCH_1):PAGE212_I7@PURE_QUANTA.HOLE(CHIPS)':
 '1': CDS_PINID='\1\';
NODE_NAME     H76 1
 '@T6G_MB_LIB.T6G(SCH_1):PAGE212_I10@PURE_QUANTA.HOLE(CHIPS)':
 '1': CDS_PINID='\1\';
NODE_NAME     H77 1
 '@T6G_MB_LIB.T6G(SCH_1):PAGE212_I12@PURE_QUANTA.HOLE(CHIPS)':
 '1': CDS_PINID='\1\';
NODE_NAME     H113 2
 '@T6G_MB_LIB.T6G(SCH_1):PAGE212_I25@PURE_QUANTA.GND_HOLE(CHIPS)':
 'GND2': CDS_PINID='GND2';
NODE_NAME     H113 3
 '@T6G_MB_LIB.T6G(SCH_1):PAGE212_I25@PURE_QUANTA.GND_HOLE(CHIPS)':
 'GND3': CDS_PINID='GND3';
NODE_NAME     H113 4
 '@T6G_MB_LIB.T6G(SCH_1):PAGE212_I25@PURE_QUANTA.GND_HOLE(CHIPS)':
 'GND4': CDS_PINID='GND4';
NODE_NAME     H113 5
 '@T6G_MB_LIB.T6G(SCH_1):PAGE212_I25@PURE_QUANTA.GND_HOLE(CHIPS)':
 'GND5': CDS_PINID='GND5';
NODE_NAME     H113 6
 '@T6G_MB_LIB.T6G(SCH_1):PAGE212_I25@PURE_QUANTA.GND_HOLE(CHIPS)':
 'GND6': CDS_PINID='GND6';
NODE_NAME     H113 7
 '@T6G_MB_LIB.T6G(SCH_1):PAGE212_I25@PURE_QUANTA.GND_HOLE(CHIPS)':
 'GND7': CDS_PINID='GND7';
NODE_NAME     H113 8
 '@T6G_MB_LIB.T6G(SCH_1):PAGE212_I25@PURE_QUANTA.GND_HOLE(CHIPS)':
 'GND8': CDS_PINID='GND8';
NODE_NAME     H113 9
 '@T6G_MB_LIB.T6G(SCH_1):PAGE212_I25@PURE_QUANTA.GND_HOLE(CHIPS)':
 'GND9': CDS_PINID='GND9';
NODE_NAME     H22 1
 '@T6G_MB_LIB.T6G(SCH_1):PAGE212_I26@PURE_QUANTA.HOLE(CHIPS)':
 '1': CDS_PINID='\1\';
NODE_NAME     H8028 1
 '@T6G_MB_LIB.T6G(SCH_1):PAGE212_I27@PURE_QUANTA.HOLE(CHIPS)':
 '1': CDS_PINID='\1\';
NODE_NAME     H114 2
 '@T6G_MB_LIB.T6G(SCH_1):PAGE212_I30@PURE_QUANTA.GND_HOLE(CHIPS)':
 'GND2': CDS_PINID='GND2';
NODE_NAME     H114 3
 '@T6G_MB_LIB.T6G(SCH_1):PAGE212_I30@PURE_QUANTA.GND_HOLE(CHIPS)':
 'GND3': CDS_PINID='GND3';
NODE_NAME     H114 4
 '@T6G_MB_LIB.T6G(SCH_1):PAGE212_I30@PURE_QUANTA.GND_HOLE(CHIPS)':
 'GND4': CDS_PINID='GND4';
NODE_NAME     H114 5
 '@T6G_MB_LIB.T6G(SCH_1):PAGE212_I30@PURE_QUANTA.GND_HOLE(CHIPS)':
 'GND5': CDS_PINID='GND5';
NODE_NAME     H114 6
 '@T6G_MB_LIB.T6G(SCH_1):PAGE212_I30@PURE_QUANTA.GND_HOLE(CHIPS)':
 'GND6': CDS_PINID='GND6';
NODE_NAME     H114 7
 '@T6G_MB_LIB.T6G(SCH_1):PAGE212_I30@PURE_QUANTA.GND_HOLE(CHIPS)':
 'GND7': CDS_PINID='GND7';
NODE_NAME     H114 8
 '@T6G_MB_LIB.T6G(SCH_1):PAGE212_I30@PURE_QUANTA.GND_HOLE(CHIPS)':
 'GND8': CDS_PINID='GND8';
NODE_NAME     H114 9
 '@T6G_MB_LIB.T6G(SCH_1):PAGE212_I30@PURE_QUANTA.GND_HOLE(CHIPS)':
 'GND9': CDS_PINID='GND9';
NODE_NAME     H34 1
 '@T6G_MB_LIB.T6G(SCH_1):PAGE212_I31@PURE_QUANTA.HOLE(CHIPS)':
 '1': CDS_PINID='\1\';
NODE_NAME     H38 1
 '@T6G_MB_LIB.T6G(SCH_1):PAGE212_I33@PURE_QUANTA.HOLE(CHIPS)':
 '1': CDS_PINID='\1\';
NODE_NAME     H33 1
 '@T6G_MB_LIB.T6G(SCH_1):PAGE212_I36@PURE_QUANTA.HOLE(CHIPS)':
 '1': CDS_PINID='\1\';
NODE_NAME     H37 1
 '@T6G_MB_LIB.T6G(SCH_1):PAGE212_I38@PURE_QUANTA.HOLE(CHIPS)':
 '1': CDS_PINID='\1\';
NODE_NAME     H43 1
 '@T6G_MB_LIB.T6G(SCH_1):PAGE212_I40@PURE_QUANTA.HOLE(CHIPS)':
 '1': CDS_PINID='\1\';
NODE_NAME     H115 2
 '@T6G_MB_LIB.T6G(SCH_1):PAGE212_I43@PURE_QUANTA.GND_HOLE(CHIPS)':
 'GND2': CDS_PINID='GND2';
NODE_NAME     H115 3
 '@T6G_MB_LIB.T6G(SCH_1):PAGE212_I43@PURE_QUANTA.GND_HOLE(CHIPS)':
 'GND3': CDS_PINID='GND3';
NODE_NAME     H115 4
 '@T6G_MB_LIB.T6G(SCH_1):PAGE212_I43@PURE_QUANTA.GND_HOLE(CHIPS)':
 'GND4': CDS_PINID='GND4';
NODE_NAME     H115 5
 '@T6G_MB_LIB.T6G(SCH_1):PAGE212_I43@PURE_QUANTA.GND_HOLE(CHIPS)':
 'GND5': CDS_PINID='GND5';
NODE_NAME     H115 6
 '@T6G_MB_LIB.T6G(SCH_1):PAGE212_I43@PURE_QUANTA.GND_HOLE(CHIPS)':
 'GND6': CDS_PINID='GND6';
NODE_NAME     H115 7
 '@T6G_MB_LIB.T6G(SCH_1):PAGE212_I43@PURE_QUANTA.GND_HOLE(CHIPS)':
 'GND7': CDS_PINID='GND7';
NODE_NAME     H115 8
 '@T6G_MB_LIB.T6G(SCH_1):PAGE212_I43@PURE_QUANTA.GND_HOLE(CHIPS)':
 'GND8': CDS_PINID='GND8';
NODE_NAME     H115 9
 '@T6G_MB_LIB.T6G(SCH_1):PAGE212_I43@PURE_QUANTA.GND_HOLE(CHIPS)':
 'GND9': CDS_PINID='GND9';
NODE_NAME     H44 1
 '@T6G_MB_LIB.T6G(SCH_1):PAGE212_I45@PURE_QUANTA.HOLE(CHIPS)':
 '1': CDS_PINID='\1\';
NODE_NAME     H49 1
 '@T6G_MB_LIB.T6G(SCH_1):PAGE212_I46@PURE_QUANTA.HOLE(CHIPS)':
 '1': CDS_PINID='\1\';
NODE_NAME     H50 1
 '@T6G_MB_LIB.T6G(SCH_1):PAGE212_I49@PURE_QUANTA.HOLE(CHIPS)':
 '1': CDS_PINID='\1\';
NODE_NAME     H54 1
 '@T6G_MB_LIB.T6G(SCH_1):PAGE212_I52@PURE_QUANTA.HOLE(CHIPS)':
 '1': CDS_PINID='\1\';
NODE_NAME     H13 1
 '@T6G_MB_LIB.T6G(SCH_1):PAGE212_I55@PURE_QUANTA.HOLE(CHIPS)':
 '1': CDS_PINID='\1\';
NODE_NAME     H11 1
 '@T6G_MB_LIB.T6G(SCH_1):PAGE212_I87@PURE_QUANTA.HOLE(CHIPS)':
 '1': CDS_PINID='\1\';
NODE_NAME     H31 1
 '@T6G_MB_LIB.T6G(SCH_1):PAGE212_I91@PURE_QUANTA.HOLE(CHIPS)':
 '1': CDS_PINID='\1\';
NODE_NAME     H32 1
 '@T6G_MB_LIB.T6G(SCH_1):PAGE212_I93@PURE_QUANTA.HOLE(CHIPS)':
 '1': CDS_PINID='\1\';
NODE_NAME     Q78 1
 '@T6G_MB_LIB.T6G(SCH_1):PAGE254_I24@PURE_QUANTA.MOSFET_NCH_DUAL(CHIPS)':
 'S1': CDS_PINID='S1';
NODE_NAME     R6086 2
 '@T6G_MB_LIB.T6G(SCH_1):PAGE175_I129@PURE_QUANTA.Q_RES(CHIPS)':
 'B': CDS_PINID='B';
NODE_NAME     R6087 2
 '@T6G_MB_LIB.T6G(SCH_1):PAGE185_I135@PURE_QUANTA.Q_RES(CHIPS)':
 'B': CDS_PINID='B';
NODE_NAME     R6088 2
 '@T6G_MB_LIB.T6G(SCH_1):PAGE192_I130@PURE_QUANTA.Q_RES(CHIPS)':
 'B': CDS_PINID='B';
NODE_NAME     R6089 2
 '@T6G_MB_LIB.T6G(SCH_1):PAGE168_I136@PURE_QUANTA.Q_RES(CHIPS)':
 'B': CDS_PINID='B';
NODE_NAME     R6090 2
 '@T6G_MB_LIB.T6G(SCH_1):PAGE84_I77@PURE_QUANTA.Q_RES(CHIPS)':
 'B': CDS_PINID='B';
NODE_NAME     Q87 4
 '@T6G_MB_LIB.T6G(SCH_1):PAGE254_I35@PURE_QUANTA.MOSFET_NCH_DUAL(CHIPS)':
 'S2': CDS_PINID='S2';
NODE_NAME     C1209 2
 '@T6G_MB_LIB.T6G(SCH_1):PAGE84_I88@PURE_QUANTA.Q_CAP(CHIPS)':
 'B': CDS_PINID='B';
NODE_NAME     C10 2
 '@T6G_MB_LIB.T6G(SCH_1):PAGE337_I61@PURE_QUANTA.Q_CAP(CHIPS)':
 'B': CDS_PINID='B';
NODE_NAME     U75 3
 '@T6G_MB_LIB.T6G(SCH_1):PAGE337_I64@PURE_QUANTA.74LVC1G17GW(CHIPS)':
 'GND': CDS_PINID='GND';
NODE_NAME     C1821 2
 '@T6G_MB_LIB.T6G(SCH_1):PAGE342_I55@PURE_QUANTA.Q_CAP(CHIPS)':
 'B': CDS_PINID='B';
NODE_NAME     U207 3
 '@T6G_MB_LIB.T6G(SCH_1):PAGE342_I58@PURE_QUANTA.74LVC1G17GW(CHIPS)':
 'GND': CDS_PINID='GND';
NODE_NAME     R6098 1
 '@T6G_MB_LIB.T6G(SCH_1):PAGE75_I99@PURE_QUANTA.Q_RES(CHIPS)':
 'A': CDS_PINID='A';
NODE_NAME     C5022 1
 '@T6G_MB_LIB.T6G(SCH_1):PAGE192_I131@PURE_QUANTA.Q_CAP(CHIPS)':
 'A': CDS_PINID='A';
NODE_NAME     C5020 1
 '@T6G_MB_LIB.T6G(SCH_1):PAGE192_I133@PURE_QUANTA.Q_CAP(CHIPS)':
 'A': CDS_PINID='A';
NODE_NAME     C5019 1
 '@T6G_MB_LIB.T6G(SCH_1):PAGE185_I137@PURE_QUANTA.Q_CAP(CHIPS)':
 'A': CDS_PINID='A';
NODE_NAME     C5018 1
 '@T6G_MB_LIB.T6G(SCH_1):PAGE168_I138@PURE_QUANTA.Q_CAP(CHIPS)':
 'A': CDS_PINID='A';
NODE_NAME     C5017 1
 '@T6G_MB_LIB.T6G(SCH_1):PAGE168_I139@PURE_QUANTA.Q_CAP(CHIPS)':
 'A': CDS_PINID='A';
NODE_NAME     C5016 2
 '@T6G_MB_LIB.T6G(SCH_1):PAGE201_I55@PURE_QUANTA.Q_CAP(CHIPS)':
 'B': CDS_PINID='B';
NODE_NAME     C5015 2
 '@T6G_MB_LIB.T6G(SCH_1):PAGE245_I68@PURE_QUANTA.Q_CAP(CHIPS)':
 'B': CDS_PINID='B';
NODE_NAME     C5013 2
 '@T6G_MB_LIB.T6G(SCH_1):PAGE175_I130@PURE_QUANTA.Q_CAP(CHIPS)':
 'B': CDS_PINID='B';
NODE_NAME     C5012 2
 '@T6G_MB_LIB.T6G(SCH_1):PAGE185_I139@PURE_QUANTA.Q_CAP(CHIPS)':
 'B': CDS_PINID='B';
NODE_NAME     C5010 2
 '@T6G_MB_LIB.T6G(SCH_1):PAGE199_I88@PURE_QUANTA.Q_CAP(CHIPS)':
 'B': CDS_PINID='B';
NODE_NAME     C5011 2
 '@T6G_MB_LIB.T6G(SCH_1):PAGE168_I142@PURE_QUANTA.Q_CAP(CHIPS)':
 'B': CDS_PINID='B';
NODE_NAME     C5009 2
 '@T6G_MB_LIB.T6G(SCH_1):PAGE182_I88@PURE_QUANTA.Q_CAP(CHIPS)':
 'B': CDS_PINID='B';
NODE_NAME     C5006 1
 '@T6G_MB_LIB.T6G(SCH_1):PAGE192_I136@PURE_QUANTA.Q_CAP(CHIPS)':
 'A': CDS_PINID='A';
NODE_NAME     C5005 1
 '@T6G_MB_LIB.T6G(SCH_1):PAGE175_I133@PURE_QUANTA.Q_CAP(CHIPS)':
 'A': CDS_PINID='A';
NODE_NAME     C5004 1
 '@T6G_MB_LIB.T6G(SCH_1):PAGE175_I135@PURE_QUANTA.Q_CAP(CHIPS)':
 'A': CDS_PINID='A';
NODE_NAME     C5003 1
 '@T6G_MB_LIB.T6G(SCH_1):PAGE185_I141@PURE_QUANTA.Q_CAP(CHIPS)':
 'A': CDS_PINID='A';
NODE_NAME     C5002 2
 '@T6G_MB_LIB.T6G(SCH_1):PAGE167_I43@PURE_QUANTA.Q_CAP(CHIPS)':
 'B': CDS_PINID='B';
NODE_NAME     C5001 2
 '@T6G_MB_LIB.T6G(SCH_1):PAGE184_I56@PURE_QUANTA.Q_CAP(CHIPS)':
 'B': CDS_PINID='B';
NODE_NAME     C5000 2
 '@T6G_MB_LIB.T6G(SCH_1):PAGE34_I124@PURE_QUANTA.Q_CAP(CHIPS)':
 'B': CDS_PINID='B';
NODE_NAME     C86 2
 '@T6G_MB_LIB.T6G(SCH_1):PAGE149_I161@PURE_QUANTA.Q_CAP(CHIPS)':
 'B': CDS_PINID='B';
NODE_NAME     Q87 1
 '@T6G_MB_LIB.T6G(SCH_1):PAGE254_I38@PURE_QUANTA.MOSFET_NCH_DUAL(CHIPS)':
 'S1': CDS_PINID='S1';
NODE_NAME     Q80 4
 '@T6G_MB_LIB.T6G(SCH_1):PAGE374_I3@PURE_QUANTA.MOSFET_NCH_DUAL(CHIPS)':
 'S2': CDS_PINID='S2';
NODE_NAME     Q80 1
 '@T6G_MB_LIB.T6G(SCH_1):PAGE374_I6@PURE_QUANTA.MOSFET_NCH_DUAL(CHIPS)':
 'S1': CDS_PINID='S1';
NODE_NAME     Q79 4
 '@T6G_MB_LIB.T6G(SCH_1):PAGE374_I8@PURE_QUANTA.MOSFET_NCH_DUAL(CHIPS)':
 'S2': CDS_PINID='S2';
NODE_NAME     Q79 1
 '@T6G_MB_LIB.T6G(SCH_1):PAGE374_I18@PURE_QUANTA.MOSFET_NCH_DUAL(CHIPS)':
 'S1': CDS_PINID='S1';
NODE_NAME     Q83 1
 '@T6G_MB_LIB.T6G(SCH_1):PAGE374_I23@PURE_QUANTA.MOSFET_NCH_DUAL(CHIPS)':
 'S1': CDS_PINID='S1';
NODE_NAME     Q81 4
 '@T6G_MB_LIB.T6G(SCH_1):PAGE374_I27@PURE_QUANTA.MOSFET_NCH_DUAL(CHIPS)':
 'S2': CDS_PINID='S2';
NODE_NAME     Q81 1
 '@T6G_MB_LIB.T6G(SCH_1):PAGE374_I35@PURE_QUANTA.MOSFET_NCH_DUAL(CHIPS)':
 'S1': CDS_PINID='S1';
NODE_NAME     Q85 4
 '@T6G_MB_LIB.T6G(SCH_1):PAGE375_I2@PURE_QUANTA.MOSFET_NCH_DUAL(CHIPS)':
 'S2': CDS_PINID='S2';
NODE_NAME     Q85 1
 '@T6G_MB_LIB.T6G(SCH_1):PAGE375_I7@PURE_QUANTA.MOSFET_NCH_DUAL(CHIPS)':
 'S1': CDS_PINID='S1';
NODE_NAME     Q84 4
 '@T6G_MB_LIB.T6G(SCH_1):PAGE375_I10@PURE_QUANTA.MOSFET_NCH_DUAL(CHIPS)':
 'S2': CDS_PINID='S2';
NODE_NAME     Q84 1
 '@T6G_MB_LIB.T6G(SCH_1):PAGE375_I11@PURE_QUANTA.MOSFET_NCH_DUAL(CHIPS)':
 'S1': CDS_PINID='S1';
NODE_NAME     Q86 4
 '@T6G_MB_LIB.T6G(SCH_1):PAGE375_I29@PURE_QUANTA.MOSFET_NCH_DUAL(CHIPS)':
 'S2': CDS_PINID='S2';
NODE_NAME     Q86 1
 '@T6G_MB_LIB.T6G(SCH_1):PAGE375_I30@PURE_QUANTA.MOSFET_NCH_DUAL(CHIPS)':
 'S1': CDS_PINID='S1';
NODE_NAME     R6115 2
 '@T6G_MB_LIB.T6G(SCH_1):PAGE82_I141@PURE_QUANTA.Q_RES(CHIPS)':
 'B': CDS_PINID='B';
NODE_NAME     R6143 2
 '@T6G_MB_LIB.T6G(SCH_1):PAGE83_I36@PURE_QUANTA.Q_RES(CHIPS)':
 'B': CDS_PINID='B';
NODE_NAME     R6127 2
 '@T6G_MB_LIB.T6G(SCH_1):PAGE83_I46@PURE_QUANTA.Q_RES(CHIPS)':
 'B': CDS_PINID='B';
NODE_NAME     R6128 2
 '@T6G_MB_LIB.T6G(SCH_1):PAGE83_I64@PURE_QUANTA.Q_RES(CHIPS)':
 'B': CDS_PINID='B';
NODE_NAME     R6129 2
 '@T6G_MB_LIB.T6G(SCH_1):PAGE83_I65@PURE_QUANTA.Q_RES(CHIPS)':
 'B': CDS_PINID='B';
NODE_NAME     U6000 25
 '@T6G_MB_LIB.T6G(SCH_1):PAGE111_I1@PURE_QUANTA.DS125BR111RTWR(CHIPS)':
 'TH_GND': CDS_PINID='TH_GND';
NODE_NAME     U6000 16
 '@T6G_MB_LIB.T6G(SCH_1):PAGE111_I1@PURE_QUANTA.DS125BR111RTWR(CHIPS)':
 'VDD_SEL': CDS_PINID='VDD_SEL';
NODE_NAME     C6009 2
 '@T6G_MB_LIB.T6G(SCH_1):PAGE111_I3@PURE_QUANTA.Q_CAP(CHIPS)':
 'B': CDS_PINID='B';
NODE_NAME     C6010 2
 '@T6G_MB_LIB.T6G(SCH_1):PAGE111_I5@PURE_QUANTA.Q_CAP(CHIPS)':
 'B': CDS_PINID='B';
NODE_NAME     C6011 2
 '@T6G_MB_LIB.T6G(SCH_1):PAGE111_I6@PURE_QUANTA.Q_CAP(CHIPS)':
 'B': CDS_PINID='B';
NODE_NAME     C6012 2
 '@T6G_MB_LIB.T6G(SCH_1):PAGE111_I7@PURE_QUANTA.Q_CAP(CHIPS)':
 'B': CDS_PINID='B';
NODE_NAME     R6160 2
 '@T6G_MB_LIB.T6G(SCH_1):PAGE111_I12@PURE_QUANTA.Q_RES(CHIPS)':
 'B': CDS_PINID='B';
NODE_NAME     R6164 2
 '@T6G_MB_LIB.T6G(SCH_1):PAGE111_I32@PURE_QUANTA.Q_RES(CHIPS)':
 'B': CDS_PINID='B';
NODE_NAME     R6166 2
 '@T6G_MB_LIB.T6G(SCH_1):PAGE111_I40@PURE_QUANTA.Q_RES(CHIPS)':
 'B': CDS_PINID='B';
NODE_NAME     R6174 2
 '@T6G_MB_LIB.T6G(SCH_1):PAGE111_I45@PURE_QUANTA.Q_RES(CHIPS)':
 'B': CDS_PINID='B';
NODE_NAME     R6172 2
 '@T6G_MB_LIB.T6G(SCH_1):PAGE111_I49@PURE_QUANTA.Q_RES(CHIPS)':
 'B': CDS_PINID='B';
NODE_NAME     R6168 2
 '@T6G_MB_LIB.T6G(SCH_1):PAGE111_I58@PURE_QUANTA.Q_RES(CHIPS)':
 'B': CDS_PINID='B';
NODE_NAME     R6170 2
 '@T6G_MB_LIB.T6G(SCH_1):PAGE111_I60@PURE_QUANTA.Q_RES(CHIPS)':
 'B': CDS_PINID='B';
NODE_NAME     R6176 2
 '@T6G_MB_LIB.T6G(SCH_1):PAGE111_I64@PURE_QUANTA.Q_RES(CHIPS)':
 'B': CDS_PINID='B';
NODE_NAME     R6178 2
 '@T6G_MB_LIB.T6G(SCH_1):PAGE111_I68@PURE_QUANTA.Q_RES(CHIPS)':
 'B': CDS_PINID='B';
NODE_NAME     R6180 2
 '@T6G_MB_LIB.T6G(SCH_1):PAGE111_I73@PURE_QUANTA.Q_RES(CHIPS)':
 'B': CDS_PINID='B';
NODE_NAME     PC2188 2
 '@T6G_MB_LIB.T6G(SCH_1):PAGE267_I46@PURE_QUANTA.Q_CAP(CHIPS)':
 'B': CDS_PINID='B';
NODE_NAME     PD111 1
 '@T6G_MB_LIB.T6G(SCH_1):PAGE267_I89@PURE_QUANTA.SS15P3SM386A(CHIPS)':
 'ANODE_1': CDS_PINID='ANODE_1';
NODE_NAME     PD111 2
 '@T6G_MB_LIB.T6G(SCH_1):PAGE267_I89@PURE_QUANTA.SS15P3SM386A(CHIPS)':
 'ANODE_2': CDS_PINID='ANODE_2';
NODE_NAME     PD15 A
 '@T6G_MB_LIB.T6G(SCH_1):PAGE372_I1@PURE_QUANTA.ZENER_AC(CHIPS)':
 'A': CDS_PINID='A';
NODE_NAME     PD13 A
 '@T6G_MB_LIB.T6G(SCH_1):PAGE372_I3@PURE_QUANTA.ZENER_AC(CHIPS)':
 'A': CDS_PINID='A';
NODE_NAME     C1797 2
 '@T6G_MB_LIB.T6G(SCH_1):PAGE372_I9@PURE_QUANTA.Q_CAP(CHIPS)':
 'B': CDS_PINID='B';
NODE_NAME     R3907 2
 '@T6G_MB_LIB.T6G(SCH_1):PAGE372_I10@PURE_QUANTA.Q_RES(CHIPS)':
 'B': CDS_PINID='B';
NODE_NAME     U290 S
 '@T6G_MB_LIB.T6G(SCH_1):PAGE372_I11@PURE_QUANTA.MOSFET_NCH_GDS_ESD_PROTECTED(CHIPS)':
 'S': CDS_PINID='S';
NODE_NAME     R2585 2
 '@T6G_MB_LIB.T6G(SCH_1):PAGE372_I13@PURE_QUANTA.Q_RES(CHIPS)':
 'B': CDS_PINID='B';
NODE_NAME     JP4003 3
 '@T6G_MB_LIB.T6G(SCH_1):PAGE372_I18@PURE_QUANTA.CONN3_210HP1030BR1(CHIPS)':
 '3': CDS_PINID='\3\';
NODE_NAME     C2179 2
 '@T6G_MB_LIB.T6G(SCH_1):PAGE372_I22@PURE_QUANTA.Q_CAP(CHIPS)':
 'B': CDS_PINID='B';
NODE_NAME     PD17 1
 '@T6G_MB_LIB.T6G(SCH_1):PAGE302_I72@PURE_QUANTA.SS15P3SM386A(CHIPS)':
 'ANODE_1': CDS_PINID='ANODE_1';
NODE_NAME     PD17 2
 '@T6G_MB_LIB.T6G(SCH_1):PAGE302_I72@PURE_QUANTA.SS15P3SM386A(CHIPS)':
 'ANODE_2': CDS_PINID='ANODE_2';
NODE_NAME     C1787 2
 '@T6G_MB_LIB.T6G(SCH_1):PAGE371_I6@PURE_QUANTA.Q_CAP(CHIPS)':
 'B': CDS_PINID='B';
NODE_NAME     U143 5
 '@T6G_MB_LIB.T6G(SCH_1):PAGE371_I8@PURE_QUANTA.NCT7718W(CHIPS)':
 'GND': CDS_PINID='GND';
NODE_NAME     PC1789 2
 '@T6G_MB_LIB.T6G(SCH_1):PAGE371_I28@PURE_QUANTA.Q_CAP(CHIPS)':
 'B': CDS_PINID='B';
NODE_NAME     U38 2
 '@T6G_MB_LIB.T6G(SCH_1):PAGE264_I8@PURE_QUANTA.SN74LVC1G11DCKR(CHIPS)':
 'GND': CDS_PINID='GND';
NODE_NAME     R1441 2
 '@T6G_MB_LIB.T6G(SCH_1):PAGE264_I24@PURE_QUANTA.Q_RES(CHIPS)':
 'B': CDS_PINID='B';
NODE_NAME     R1443 2
 '@T6G_MB_LIB.T6G(SCH_1):PAGE264_I27@PURE_QUANTA.Q_RES(CHIPS)':
 'B': CDS_PINID='B';
NODE_NAME     Q19 1
 '@T6G_MB_LIB.T6G(SCH_1):PAGE264_I33@PURE_QUANTA.BSS138DW7F(CHIPS)':
 'S1': CDS_PINID='S1';
NODE_NAME     Q19 4
 '@T6G_MB_LIB.T6G(SCH_1):PAGE264_I33@PURE_QUANTA.BSS138DW7F(CHIPS)':
 'S2': CDS_PINID='S2';
NODE_NAME     Q18 1
 '@T6G_MB_LIB.T6G(SCH_1):PAGE264_I36@PURE_QUANTA.BSS138DW7F(CHIPS)':
 'S1': CDS_PINID='S1';
NODE_NAME     Q18 4
 '@T6G_MB_LIB.T6G(SCH_1):PAGE264_I36@PURE_QUANTA.BSS138DW7F(CHIPS)':
 'S2': CDS_PINID='S2';
NODE_NAME     C347 2
 '@T6G_MB_LIB.T6G(SCH_1):PAGE264_I47@PURE_QUANTA.Q_CAP(CHIPS)':
 'B': CDS_PINID='B';
NODE_NAME     C5014 2
 '@T6G_MB_LIB.T6G(SCH_1):PAGE264_I49@PURE_QUANTA.Q_CAP(CHIPS)':
 'B': CDS_PINID='B';
NODE_NAME     H6000 1
 '@T6G_MB_LIB.T6G(SCH_1):PAGE212_I113@PURE_QUANTA.HOLE(CHIPS)':
 '1': CDS_PINID='\1\';
NODE_NAME     H6001 1
 '@T6G_MB_LIB.T6G(SCH_1):PAGE212_I116@PURE_QUANTA.HOLE(CHIPS)':
 '1': CDS_PINID='\1\';
NODE_NAME     R1318 2
 '@T6G_MB_LIB.T6G(SCH_1):PAGE148_I378@PURE_QUANTA.Q_RES(CHIPS)':
 'B': CDS_PINID='B';
NODE_NAME     R1313 2
 '@T6G_MB_LIB.T6G(SCH_1):PAGE148_I383@PURE_QUANTA.Q_RES(CHIPS)':
 'B': CDS_PINID='B';
NODE_NAME     U6 5
 '@T6G_MB_LIB.T6G(SCH_1):PAGE138_I67@PURE_QUANTA.PI3CSW12ZUAEX(CHIPS)':
 'GND': CDS_PINID='GND';
NODE_NAME     C25 2
 '@T6G_MB_LIB.T6G(SCH_1):PAGE138_I69@PURE_QUANTA.Q_CAP(CHIPS)':
 'B': CDS_PINID='B';
NODE_NAME     R6185 2
 '@T6G_MB_LIB.T6G(SCH_1):PAGE82_I143@PURE_QUANTA.Q_RES(CHIPS)':
 'B': CDS_PINID='B';
NODE_NAME     R6187 2
 '@T6G_MB_LIB.T6G(SCH_1):PAGE82_I151@PURE_QUANTA.Q_RES(CHIPS)':
 'B': CDS_PINID='B';
NODE_NAME     PJ38 11
 '@T6G_MB_LIB.T6G(SCH_1):PAGE371_I42@PURE_QUANTA.SCONN21_9193031121LF(CHIPS)':
 '11': CDS_PINID='\11\';
NODE_NAME     PJ38 21
 '@T6G_MB_LIB.T6G(SCH_1):PAGE371_I42@PURE_QUANTA.SCONN21_9193031121LF(CHIPS)':
 '21': CDS_PINID='\21\';
NODE_NAME     PJ38 G1
 '@T6G_MB_LIB.T6G(SCH_1):PAGE371_I42@PURE_QUANTA.SCONN21_9193031121LF(CHIPS)':
 'G1': CDS_PINID='G1';
NODE_NAME     PJ38 G2
 '@T6G_MB_LIB.T6G(SCH_1):PAGE371_I42@PURE_QUANTA.SCONN21_9193031121LF(CHIPS)':
 'G2': CDS_PINID='G2';
NODE_NAME     U96 4
 '@T6G_MB_LIB.T6G(SCH_1):PAGE137_I51@PURE_QUANTA.PCA9617ADP(CHIPS)':
 'GND': CDS_PINID='GND';
NODE_NAME     U6001 TH
 '@T6G_MB_LIB.T6G(SCH_1):PAGE153_I1@PURE_QUANTA.CYUSB330468LTXI(CHIPS)':
 'EPAD': CDS_PINID='EPAD';
NODE_NAME     U6001 40
 '@T6G_MB_LIB.T6G(SCH_1):PAGE153_I1@PURE_QUANTA.CYUSB330468LTXI(CHIPS)':
 'GND': CDS_PINID='GND';
NODE_NAME     Y9 2
 '@T6G_MB_LIB.T6G(SCH_1):PAGE153_I14@PURE_QUANTA.Q_XTAL_4P_13BI_24GND(CHIPS)':
 'G1': CDS_PINID='G1';
NODE_NAME     Y9 4
 '@T6G_MB_LIB.T6G(SCH_1):PAGE153_I14@PURE_QUANTA.Q_XTAL_4P_13BI_24GND(CHIPS)':
 'G2': CDS_PINID='G2';
NODE_NAME     R4453 2
 '@T6G_MB_LIB.T6G(SCH_1):PAGE153_I23@PURE_QUANTA.Q_RES(CHIPS)':
 'B': CDS_PINID='B';
NODE_NAME     C2317 2
 '@T6G_MB_LIB.T6G(SCH_1):PAGE153_I25@PURE_QUANTA.Q_CAP(CHIPS)':
 'B': CDS_PINID='B';
NODE_NAME     C6027 2
 '@T6G_MB_LIB.T6G(SCH_1):PAGE153_I28@PURE_QUANTA.Q_CAP(CHIPS)':
 'B': CDS_PINID='B';
NODE_NAME     C6028 2
 '@T6G_MB_LIB.T6G(SCH_1):PAGE153_I29@PURE_QUANTA.Q_CAP(CHIPS)':
 'B': CDS_PINID='B';
NODE_NAME     R6202 1
 '@T6G_MB_LIB.T6G(SCH_1):PAGE153_I37@PURE_QUANTA.Q_RES(CHIPS)':
 'A': CDS_PINID='A';
NODE_NAME     R6203 1
 '@T6G_MB_LIB.T6G(SCH_1):PAGE153_I39@PURE_QUANTA.Q_RES(CHIPS)':
 'A': CDS_PINID='A';
NODE_NAME     R6209 2
 '@T6G_MB_LIB.T6G(SCH_1):PAGE153_I48@PURE_QUANTA.Q_RES(CHIPS)':
 'B': CDS_PINID='B';
NODE_NAME     C6040 2
 '@T6G_MB_LIB.T6G(SCH_1):PAGE154_I5@PURE_QUANTA.Q_CAP(CHIPS)':
 'B': CDS_PINID='B';
NODE_NAME     C6041 2
 '@T6G_MB_LIB.T6G(SCH_1):PAGE154_I7@PURE_QUANTA.Q_CAP(CHIPS)':
 'B': CDS_PINID='B';
NODE_NAME     C6042 2
 '@T6G_MB_LIB.T6G(SCH_1):PAGE154_I9@PURE_QUANTA.Q_CAP(CHIPS)':
 'B': CDS_PINID='B';
NODE_NAME     C6043 2
 '@T6G_MB_LIB.T6G(SCH_1):PAGE154_I10@PURE_QUANTA.Q_CAP(CHIPS)':
 'B': CDS_PINID='B';
NODE_NAME     C6044 2
 '@T6G_MB_LIB.T6G(SCH_1):PAGE154_I12@PURE_QUANTA.Q_CAP(CHIPS)':
 'B': CDS_PINID='B';
NODE_NAME     C6045 2
 '@T6G_MB_LIB.T6G(SCH_1):PAGE154_I13@PURE_QUANTA.Q_CAP(CHIPS)':
 'B': CDS_PINID='B';
NODE_NAME     C6046 2
 '@T6G_MB_LIB.T6G(SCH_1):PAGE154_I14@PURE_QUANTA.Q_CAP(CHIPS)':
 'B': CDS_PINID='B';
NODE_NAME     C6047 2
 '@T6G_MB_LIB.T6G(SCH_1):PAGE154_I15@PURE_QUANTA.Q_CAP(CHIPS)':
 'B': CDS_PINID='B';
NODE_NAME     C6048 2
 '@T6G_MB_LIB.T6G(SCH_1):PAGE154_I17@PURE_QUANTA.Q_CAP(CHIPS)':
 'B': CDS_PINID='B';
NODE_NAME     C6049 2
 '@T6G_MB_LIB.T6G(SCH_1):PAGE154_I19@PURE_QUANTA.Q_CAP(CHIPS)':
 'B': CDS_PINID='B';
NODE_NAME     C6050 2
 '@T6G_MB_LIB.T6G(SCH_1):PAGE154_I20@PURE_QUANTA.Q_CAP(CHIPS)':
 'B': CDS_PINID='B';
NODE_NAME     C6051 2
 '@T6G_MB_LIB.T6G(SCH_1):PAGE154_I21@PURE_QUANTA.Q_CAP(CHIPS)':
 'B': CDS_PINID='B';
NODE_NAME     C6053 2
 '@T6G_MB_LIB.T6G(SCH_1):PAGE154_I22@PURE_QUANTA.Q_CAP(CHIPS)':
 'B': CDS_PINID='B';
NODE_NAME     C6052 2
 '@T6G_MB_LIB.T6G(SCH_1):PAGE154_I23@PURE_QUANTA.Q_CAP(CHIPS)':
 'B': CDS_PINID='B';
NODE_NAME     C6030 2
 '@T6G_MB_LIB.T6G(SCH_1):PAGE154_I27@PURE_QUANTA.Q_CAP(CHIPS)':
 'B': CDS_PINID='B';
NODE_NAME     C6031 2
 '@T6G_MB_LIB.T6G(SCH_1):PAGE154_I29@PURE_QUANTA.Q_CAP(CHIPS)':
 'B': CDS_PINID='B';
NODE_NAME     C6035 2
 '@T6G_MB_LIB.T6G(SCH_1):PAGE154_I31@PURE_QUANTA.Q_CAP(CHIPS)':
 'B': CDS_PINID='B';
NODE_NAME     C6034 2
 '@T6G_MB_LIB.T6G(SCH_1):PAGE154_I32@PURE_QUANTA.Q_CAP(CHIPS)':
 'B': CDS_PINID='B';
NODE_NAME     C6033 2
 '@T6G_MB_LIB.T6G(SCH_1):PAGE154_I34@PURE_QUANTA.Q_CAP(CHIPS)':
 'B': CDS_PINID='B';
NODE_NAME     C6032 2
 '@T6G_MB_LIB.T6G(SCH_1):PAGE154_I35@PURE_QUANTA.Q_CAP(CHIPS)':
 'B': CDS_PINID='B';
NODE_NAME     C6036 2
 '@T6G_MB_LIB.T6G(SCH_1):PAGE154_I37@PURE_QUANTA.Q_CAP(CHIPS)':
 'B': CDS_PINID='B';
NODE_NAME     C6037 2
 '@T6G_MB_LIB.T6G(SCH_1):PAGE154_I38@PURE_QUANTA.Q_CAP(CHIPS)':
 'B': CDS_PINID='B';
NODE_NAME     C6039 2
 '@T6G_MB_LIB.T6G(SCH_1):PAGE154_I40@PURE_QUANTA.Q_CAP(CHIPS)':
 'B': CDS_PINID='B';
NODE_NAME     C6038 2
 '@T6G_MB_LIB.T6G(SCH_1):PAGE154_I41@PURE_QUANTA.Q_CAP(CHIPS)':
 'B': CDS_PINID='B';
NODE_NAME     C6054 2
 '@T6G_MB_LIB.T6G(SCH_1):PAGE154_I43@PURE_QUANTA.Q_CAP(CHIPS)':
 'B': CDS_PINID='B';
NODE_NAME     C6055 2
 '@T6G_MB_LIB.T6G(SCH_1):PAGE154_I44@PURE_QUANTA.Q_CAP(CHIPS)':
 'B': CDS_PINID='B';
NODE_NAME     C6056 2
 '@T6G_MB_LIB.T6G(SCH_1):PAGE154_I46@PURE_QUANTA.Q_CAP(CHIPS)':
 'B': CDS_PINID='B';
NODE_NAME     C6057 2
 '@T6G_MB_LIB.T6G(SCH_1):PAGE154_I47@PURE_QUANTA.Q_CAP(CHIPS)':
 'B': CDS_PINID='B';
NODE_NAME     C6058 2
 '@T6G_MB_LIB.T6G(SCH_1):PAGE154_I49@PURE_QUANTA.Q_CAP(CHIPS)':
 'B': CDS_PINID='B';
NODE_NAME     C6059 2
 '@T6G_MB_LIB.T6G(SCH_1):PAGE154_I50@PURE_QUANTA.Q_CAP(CHIPS)':
 'B': CDS_PINID='B';
NODE_NAME     C6060 2
 '@T6G_MB_LIB.T6G(SCH_1):PAGE154_I52@PURE_QUANTA.Q_CAP(CHIPS)':
 'B': CDS_PINID='B';
NODE_NAME     C6061 2
 '@T6G_MB_LIB.T6G(SCH_1):PAGE154_I53@PURE_QUANTA.Q_CAP(CHIPS)':
 'B': CDS_PINID='B';
NODE_NAME     C6062 2
 '@T6G_MB_LIB.T6G(SCH_1):PAGE154_I55@PURE_QUANTA.Q_CAP(CHIPS)':
 'B': CDS_PINID='B';
NODE_NAME     C6063 2
 '@T6G_MB_LIB.T6G(SCH_1):PAGE154_I56@PURE_QUANTA.Q_CAP(CHIPS)':
 'B': CDS_PINID='B';
NODE_NAME     C6064 2
 '@T6G_MB_LIB.T6G(SCH_1):PAGE154_I58@PURE_QUANTA.Q_CAP(CHIPS)':
 'B': CDS_PINID='B';
NODE_NAME     C6065 2
 '@T6G_MB_LIB.T6G(SCH_1):PAGE154_I59@PURE_QUANTA.Q_CAP(CHIPS)':
 'B': CDS_PINID='B';
NODE_NAME     C6066 2
 '@T6G_MB_LIB.T6G(SCH_1):PAGE154_I60@PURE_QUANTA.Q_CAP(CHIPS)':
 'B': CDS_PINID='B';
NODE_NAME     C6069 2
 '@T6G_MB_LIB.T6G(SCH_1):PAGE154_I63@PURE_QUANTA.Q_CAP(CHIPS)':
 'B': CDS_PINID='B';
NODE_NAME     C6079 2
 '@T6G_MB_LIB.T6G(SCH_1):PAGE154_I64@PURE_QUANTA.Q_CAP(CHIPS)':
 'B': CDS_PINID='B';
NODE_NAME     C6078 2
 '@T6G_MB_LIB.T6G(SCH_1):PAGE154_I65@PURE_QUANTA.Q_CAP(CHIPS)':
 'B': CDS_PINID='B';
NODE_NAME     C6077 2
 '@T6G_MB_LIB.T6G(SCH_1):PAGE154_I66@PURE_QUANTA.Q_CAP(CHIPS)':
 'B': CDS_PINID='B';
NODE_NAME     C6076 2
 '@T6G_MB_LIB.T6G(SCH_1):PAGE154_I68@PURE_QUANTA.Q_CAP(CHIPS)':
 'B': CDS_PINID='B';
NODE_NAME     C6075 2
 '@T6G_MB_LIB.T6G(SCH_1):PAGE154_I69@PURE_QUANTA.Q_CAP(CHIPS)':
 'B': CDS_PINID='B';
NODE_NAME     C6074 2
 '@T6G_MB_LIB.T6G(SCH_1):PAGE154_I71@PURE_QUANTA.Q_CAP(CHIPS)':
 'B': CDS_PINID='B';
NODE_NAME     C6073 2
 '@T6G_MB_LIB.T6G(SCH_1):PAGE154_I73@PURE_QUANTA.Q_CAP(CHIPS)':
 'B': CDS_PINID='B';
NODE_NAME     C6072 2
 '@T6G_MB_LIB.T6G(SCH_1):PAGE154_I74@PURE_QUANTA.Q_CAP(CHIPS)':
 'B': CDS_PINID='B';
NODE_NAME     C6071 2
 '@T6G_MB_LIB.T6G(SCH_1):PAGE154_I75@PURE_QUANTA.Q_CAP(CHIPS)':
 'B': CDS_PINID='B';
NODE_NAME     C6070 2
 '@T6G_MB_LIB.T6G(SCH_1):PAGE154_I76@PURE_QUANTA.Q_CAP(CHIPS)':
 'B': CDS_PINID='B';
NODE_NAME     C6068 2
 '@T6G_MB_LIB.T6G(SCH_1):PAGE154_I78@PURE_QUANTA.Q_CAP(CHIPS)':
 'B': CDS_PINID='B';
NODE_NAME     C6067 2
 '@T6G_MB_LIB.T6G(SCH_1):PAGE154_I79@PURE_QUANTA.Q_CAP(CHIPS)':
 'B': CDS_PINID='B';
NODE_NAME     C6080 2
 '@T6G_MB_LIB.T6G(SCH_1):PAGE154_I81@PURE_QUANTA.Q_CAP(CHIPS)':
 'B': CDS_PINID='B';
NODE_NAME     C6081 2
 '@T6G_MB_LIB.T6G(SCH_1):PAGE154_I82@PURE_QUANTA.Q_CAP(CHIPS)':
 'B': CDS_PINID='B';
NODE_NAME     C6082 2
 '@T6G_MB_LIB.T6G(SCH_1):PAGE154_I83@PURE_QUANTA.Q_CAP(CHIPS)':
 'B': CDS_PINID='B';
NODE_NAME     U6003 4
 '@T6G_MB_LIB.T6G(SCH_1):PAGE153_I64@PURE_QUANTA.M24128BWMN6TP(CHIPS)':
 'VSS': CDS_PINID='VSS';
NODE_NAME     R6219 2
 '@T6G_MB_LIB.T6G(SCH_1):PAGE153_I66@PURE_QUANTA.Q_RES(CHIPS)':
 'B': CDS_PINID='B';
NODE_NAME     R6221 2
 '@T6G_MB_LIB.T6G(SCH_1):PAGE153_I67@PURE_QUANTA.Q_RES(CHIPS)':
 'B': CDS_PINID='B';
NODE_NAME     R6217 2
 '@T6G_MB_LIB.T6G(SCH_1):PAGE153_I68@PURE_QUANTA.Q_RES(CHIPS)':
 'B': CDS_PINID='B';
NODE_NAME     C6083 2
 '@T6G_MB_LIB.T6G(SCH_1):PAGE153_I75@PURE_QUANTA.Q_CAP(CHIPS)':
 'B': CDS_PINID='B';
NODE_NAME     R6223 2
 '@T6G_MB_LIB.T6G(SCH_1):PAGE153_I77@PURE_QUANTA.Q_RES(CHIPS)':
 'B': CDS_PINID='B';
NODE_NAME     U142 2
 '@T6G_MB_LIB.T6G(SCH_1):PAGE371_I50@PURE_QUANTA.LT6700CS61TRPBF(CHIPS)':
 'GND': CDS_PINID='GND';
NODE_NAME     R6233 2
 '@T6G_MB_LIB.T6G(SCH_1):PAGE371_I57@PURE_QUANTA.Q_RES(CHIPS)':
 'B': CDS_PINID='B';
NODE_NAME     R6235 2
 '@T6G_MB_LIB.T6G(SCH_1):PAGE371_I58@PURE_QUANTA.Q_RES(CHIPS)':
 'B': CDS_PINID='B';
NODE_NAME     R6237 2
 '@T6G_MB_LIB.T6G(SCH_1):PAGE371_I66@PURE_QUANTA.Q_RES(CHIPS)':
 'B': CDS_PINID='B';
NODE_NAME     U6004 S
 '@T6G_MB_LIB.T6G(SCH_1):PAGE371_I68@PURE_QUANTA.MOSFET_NCH_GDS_ESD_PROTECTED(CHIPS)':
 'S': CDS_PINID='S';
NODE_NAME     PC6020 2
 '@T6G_MB_LIB.T6G(SCH_1):PAGE315_I5@PURE_QUANTA.Q_CAP(CHIPS)':
 'B': CDS_PINID='B';
NODE_NAME     PC6012 2
 '@T6G_MB_LIB.T6G(SCH_1):PAGE315_I8@PURE_QUANTA.Q_CAP(CHIPS)':
 'B': CDS_PINID='B';
NODE_NAME     PC6014 2
 '@T6G_MB_LIB.T6G(SCH_1):PAGE315_I10@PURE_QUANTA.Q_CAP(CHIPS)':
 'B': CDS_PINID='B';
NODE_NAME     PR6003 2
 '@T6G_MB_LIB.T6G(SCH_1):PAGE315_I12@PURE_QUANTA.Q_RES(CHIPS)':
 'B': CDS_PINID='B';
NODE_NAME     PC6008 2
 '@T6G_MB_LIB.T6G(SCH_1):PAGE315_I13@PURE_QUANTA.Q_CAP(CHIPS)':
 'B': CDS_PINID='B';
NODE_NAME     PR6006 1
 '@T6G_MB_LIB.T6G(SCH_1):PAGE315_I15@PURE_QUANTA.Q_RES(CHIPS)':
 'A': CDS_PINID='A';
NODE_NAME     PU6000 7
 '@T6G_MB_LIB.T6G(SCH_1):PAGE315_I18@PURE_QUANTA.MPQ8626GDZ(CHIPS)':
 'AGND': CDS_PINID='AGND';
NODE_NAME     PU6000 1
 '@T6G_MB_LIB.T6G(SCH_1):PAGE315_I18@PURE_QUANTA.MPQ8626GDZ(CHIPS)':
 'PGND1': CDS_PINID='PGND1';
NODE_NAME     PU6000 14
 '@T6G_MB_LIB.T6G(SCH_1):PAGE315_I18@PURE_QUANTA.MPQ8626GDZ(CHIPS)':
 'PGND2': CDS_PINID='PGND2';
NODE_NAME     PC6010 2
 '@T6G_MB_LIB.T6G(SCH_1):PAGE315_I19@PURE_QUANTA.Q_CAP(CHIPS)':
 'B': CDS_PINID='B';
NODE_NAME     PC384 2
 '@T6G_MB_LIB.T6G(SCH_1):PAGE315_I21@PURE_QUANTA.Q_CAP(CHIPS)':
 'B': CDS_PINID='B';
NODE_NAME     PR6010 2
 '@T6G_MB_LIB.T6G(SCH_1):PAGE315_I23@PURE_QUANTA.Q_RES(CHIPS)':
 'B': CDS_PINID='B';
NODE_NAME     PC6021 2
 '@T6G_MB_LIB.T6G(SCH_1):PAGE315_I27@PURE_QUANTA.Q_CAP(CHIPS)':
 'B': CDS_PINID='B';
NODE_NAME     PC865 2
 '@T6G_MB_LIB.T6G(SCH_1):PAGE315_I29@PURE_QUANTA.Q_CAP(CHIPS)':
 'B': CDS_PINID='B';
NODE_NAME     PC866 2
 '@T6G_MB_LIB.T6G(SCH_1):PAGE315_I34@PURE_QUANTA.Q_CAP(CHIPS)':
 'B': CDS_PINID='B';
NODE_NAME     PC867 2
 '@T6G_MB_LIB.T6G(SCH_1):PAGE315_I36@PURE_QUANTA.Q_CAP(CHIPS)':
 'B': CDS_PINID='B';
NODE_NAME     PC850 2
 '@T6G_MB_LIB.T6G(SCH_1):PAGE315_I37@PURE_QUANTA.Q_CAP(CHIPS)':
 'B': CDS_PINID='B';
NODE_NAME     PC6013 2
 '@T6G_MB_LIB.T6G(SCH_1):PAGE380_I3@PURE_QUANTA.Q_CAP(CHIPS)':
 'B': CDS_PINID='B';
NODE_NAME     PR6004 2
 '@T6G_MB_LIB.T6G(SCH_1):PAGE380_I6@PURE_QUANTA.Q_RES(CHIPS)':
 'B': CDS_PINID='B';
NODE_NAME     PC6009 2
 '@T6G_MB_LIB.T6G(SCH_1):PAGE380_I7@PURE_QUANTA.Q_CAP(CHIPS)':
 'B': CDS_PINID='B';
NODE_NAME     PC6015 2
 '@T6G_MB_LIB.T6G(SCH_1):PAGE380_I10@PURE_QUANTA.Q_CAP(CHIPS)':
 'B': CDS_PINID='B';
NODE_NAME     PR6005 1
 '@T6G_MB_LIB.T6G(SCH_1):PAGE380_I11@PURE_QUANTA.Q_RES(CHIPS)':
 'A': CDS_PINID='A';
NODE_NAME     PC6011 2
 '@T6G_MB_LIB.T6G(SCH_1):PAGE380_I12@PURE_QUANTA.Q_CAP(CHIPS)':
 'B': CDS_PINID='B';
NODE_NAME     PU6001 7
 '@T6G_MB_LIB.T6G(SCH_1):PAGE380_I16@PURE_QUANTA.MPQ8626GDZ(CHIPS)':
 'AGND': CDS_PINID='AGND';
NODE_NAME     PU6001 1
 '@T6G_MB_LIB.T6G(SCH_1):PAGE380_I16@PURE_QUANTA.MPQ8626GDZ(CHIPS)':
 'PGND1': CDS_PINID='PGND1';
NODE_NAME     PU6001 14
 '@T6G_MB_LIB.T6G(SCH_1):PAGE380_I16@PURE_QUANTA.MPQ8626GDZ(CHIPS)':
 'PGND2': CDS_PINID='PGND2';
NODE_NAME     PC6016 2
 '@T6G_MB_LIB.T6G(SCH_1):PAGE380_I17@PURE_QUANTA.Q_CAP(CHIPS)':
 'B': CDS_PINID='B';
NODE_NAME     PR6011 2
 '@T6G_MB_LIB.T6G(SCH_1):PAGE380_I21@PURE_QUANTA.Q_RES(CHIPS)':
 'B': CDS_PINID='B';
NODE_NAME     PC6022 2
 '@T6G_MB_LIB.T6G(SCH_1):PAGE380_I23@PURE_QUANTA.Q_CAP(CHIPS)':
 'B': CDS_PINID='B';
NODE_NAME     PC6024 2
 '@T6G_MB_LIB.T6G(SCH_1):PAGE380_I28@PURE_QUANTA.Q_CAP(CHIPS)':
 'B': CDS_PINID='B';
NODE_NAME     PC6025 2
 '@T6G_MB_LIB.T6G(SCH_1):PAGE380_I29@PURE_QUANTA.Q_CAP(CHIPS)':
 'B': CDS_PINID='B';
NODE_NAME     PC6026 2
 '@T6G_MB_LIB.T6G(SCH_1):PAGE380_I32@PURE_QUANTA.Q_CAP(CHIPS)':
 'B': CDS_PINID='B';
NODE_NAME     PC6018 2
 '@T6G_MB_LIB.T6G(SCH_1):PAGE380_I33@PURE_QUANTA.Q_CAP(CHIPS)':
 'B': CDS_PINID='B';
NODE_NAME     PC6023 2
 '@T6G_MB_LIB.T6G(SCH_1):PAGE380_I35@PURE_QUANTA.Q_CAP(CHIPS)':
 'B': CDS_PINID='B';
NODE_NAME     C345 2
 '@T6G_MB_LIB.T6G(SCH_1):PAGE315_I41@PURE_QUANTA.Q_CAP(CHIPS)':
 'B': CDS_PINID='B';
NODE_NAME     C6085 2
 '@T6G_MB_LIB.T6G(SCH_1):PAGE380_I41@PURE_QUANTA.Q_CAP(CHIPS)':
 'B': CDS_PINID='B';
NODE_NAME     Q6000 1
 '@T6G_MB_LIB.T6G(SCH_1):PAGE254_I47@PURE_QUANTA.MOSFET_NCH_DUAL(CHIPS)':
 'S1': CDS_PINID='S1';
NODE_NAME     C6092 2
 '@T6G_MB_LIB.T6G(SCH_1):PAGE157_I21@PURE_QUANTA.Q_CAP(CHIPS)':
 'B': CDS_PINID='B';
NODE_NAME     C6094 2
 '@T6G_MB_LIB.T6G(SCH_1):PAGE157_I22@PURE_QUANTA.Q_CAP(CHIPS)':
 'B': CDS_PINID='B';
NODE_NAME     C6095 2
 '@T6G_MB_LIB.T6G(SCH_1):PAGE157_I23@PURE_QUANTA.Q_CAP(CHIPS)':
 'B': CDS_PINID='B';
NODE_NAME     C6093 2
 '@T6G_MB_LIB.T6G(SCH_1):PAGE157_I24@PURE_QUANTA.Q_CAP(CHIPS)':
 'B': CDS_PINID='B';
NODE_NAME     C6098 2
 '@T6G_MB_LIB.T6G(SCH_1):PAGE157_I25@PURE_QUANTA.Q_CAP(CHIPS)':
 'B': CDS_PINID='B';
NODE_NAME     C6097 2
 '@T6G_MB_LIB.T6G(SCH_1):PAGE157_I26@PURE_QUANTA.Q_CAP(CHIPS)':
 'B': CDS_PINID='B';
NODE_NAME     C6096 2
 '@T6G_MB_LIB.T6G(SCH_1):PAGE157_I27@PURE_QUANTA.Q_CAP(CHIPS)':
 'B': CDS_PINID='B';
NODE_NAME     C6101 2
 '@T6G_MB_LIB.T6G(SCH_1):PAGE157_I28@PURE_QUANTA.Q_CAP(CHIPS)':
 'B': CDS_PINID='B';
NODE_NAME     C6100 2
 '@T6G_MB_LIB.T6G(SCH_1):PAGE157_I29@PURE_QUANTA.Q_CAP(CHIPS)':
 'B': CDS_PINID='B';
NODE_NAME     C6099 2
 '@T6G_MB_LIB.T6G(SCH_1):PAGE157_I30@PURE_QUANTA.Q_CAP(CHIPS)':
 'B': CDS_PINID='B';
NODE_NAME     C6104 2
 '@T6G_MB_LIB.T6G(SCH_1):PAGE157_I31@PURE_QUANTA.Q_CAP(CHIPS)':
 'B': CDS_PINID='B';
NODE_NAME     C6103 2
 '@T6G_MB_LIB.T6G(SCH_1):PAGE157_I32@PURE_QUANTA.Q_CAP(CHIPS)':
 'B': CDS_PINID='B';
NODE_NAME     C6102 2
 '@T6G_MB_LIB.T6G(SCH_1):PAGE157_I33@PURE_QUANTA.Q_CAP(CHIPS)':
 'B': CDS_PINID='B';
NODE_NAME     C6105 2
 '@T6G_MB_LIB.T6G(SCH_1):PAGE157_I36@PURE_QUANTA.Q_CAP(CHIPS)':
 'B': CDS_PINID='B';
NODE_NAME     C6108 2
 '@T6G_MB_LIB.T6G(SCH_1):PAGE157_I39@PURE_QUANTA.Q_CAP(CHIPS)':
 'B': CDS_PINID='B';
NODE_NAME     C6107 2
 '@T6G_MB_LIB.T6G(SCH_1):PAGE157_I40@PURE_QUANTA.Q_CAP(CHIPS)':
 'B': CDS_PINID='B';
NODE_NAME     C6106 2
 '@T6G_MB_LIB.T6G(SCH_1):PAGE157_I41@PURE_QUANTA.Q_CAP(CHIPS)':
 'B': CDS_PINID='B';
NODE_NAME     C6111 2
 '@T6G_MB_LIB.T6G(SCH_1):PAGE157_I42@PURE_QUANTA.Q_CAP(CHIPS)':
 'B': CDS_PINID='B';
NODE_NAME     C6110 2
 '@T6G_MB_LIB.T6G(SCH_1):PAGE157_I43@PURE_QUANTA.Q_CAP(CHIPS)':
 'B': CDS_PINID='B';
NODE_NAME     C6109 2
 '@T6G_MB_LIB.T6G(SCH_1):PAGE157_I44@PURE_QUANTA.Q_CAP(CHIPS)':
 'B': CDS_PINID='B';
NODE_NAME     C6114 2
 '@T6G_MB_LIB.T6G(SCH_1):PAGE157_I45@PURE_QUANTA.Q_CAP(CHIPS)':
 'B': CDS_PINID='B';
NODE_NAME     C6113 2
 '@T6G_MB_LIB.T6G(SCH_1):PAGE157_I46@PURE_QUANTA.Q_CAP(CHIPS)':
 'B': CDS_PINID='B';
NODE_NAME     C6112 2
 '@T6G_MB_LIB.T6G(SCH_1):PAGE157_I47@PURE_QUANTA.Q_CAP(CHIPS)':
 'B': CDS_PINID='B';
NODE_NAME     C6117 2
 '@T6G_MB_LIB.T6G(SCH_1):PAGE157_I48@PURE_QUANTA.Q_CAP(CHIPS)':
 'B': CDS_PINID='B';
NODE_NAME     C6116 2
 '@T6G_MB_LIB.T6G(SCH_1):PAGE157_I49@PURE_QUANTA.Q_CAP(CHIPS)':
 'B': CDS_PINID='B';
NODE_NAME     C6115 2
 '@T6G_MB_LIB.T6G(SCH_1):PAGE157_I50@PURE_QUANTA.Q_CAP(CHIPS)':
 'B': CDS_PINID='B';
NODE_NAME     C6121 2
 '@T6G_MB_LIB.T6G(SCH_1):PAGE157_I51@PURE_QUANTA.Q_CAP(CHIPS)':
 'B': CDS_PINID='B';
NODE_NAME     C6120 2
 '@T6G_MB_LIB.T6G(SCH_1):PAGE157_I52@PURE_QUANTA.Q_CAP(CHIPS)':
 'B': CDS_PINID='B';
NODE_NAME     C6119 2
 '@T6G_MB_LIB.T6G(SCH_1):PAGE157_I53@PURE_QUANTA.Q_CAP(CHIPS)':
 'B': CDS_PINID='B';
NODE_NAME     C6118 2
 '@T6G_MB_LIB.T6G(SCH_1):PAGE157_I54@PURE_QUANTA.Q_CAP(CHIPS)':
 'B': CDS_PINID='B';
NODE_NAME     C6086 2
 '@T6G_MB_LIB.T6G(SCH_1):PAGE271_I11@PURE_QUANTA.Q_CAP(CHIPS)':
 'B': CDS_PINID='B';
NODE_NAME     R6251 1
 '@T6G_MB_LIB.T6G(SCH_1):PAGE271_I14@PURE_QUANTA.Q_RES(CHIPS)':
 'A': CDS_PINID='A';
NODE_NAME     C6087 2
 '@T6G_MB_LIB.T6G(SCH_1):PAGE271_I22@PURE_QUANTA.Q_CAP(CHIPS)':
 'B': CDS_PINID='B';
NODE_NAME     U6005 10
 '@T6G_MB_LIB.T6G(SCH_1):PAGE271_I28@PURE_QUANTA.ISL28022FRZT(CHIPS)':
 'GND': CDS_PINID='GND';
NODE_NAME     U6005 TH
 '@T6G_MB_LIB.T6G(SCH_1):PAGE271_I28@PURE_QUANTA.ISL28022FRZT(CHIPS)':
 'TH_GND': CDS_PINID='TH_GND';
NODE_NAME     R6250 1
 '@T6G_MB_LIB.T6G(SCH_1):PAGE271_I30@PURE_QUANTA.Q_RES(CHIPS)':
 'A': CDS_PINID='A';
NODE_NAME     R6293 2
 '@T6G_MB_LIB.T6G(SCH_1):PAGE157_I79@PURE_QUANTA.Q_RES(CHIPS)':
 'B': CDS_PINID='B';
NODE_NAME     R6326 2
 '@T6G_MB_LIB.T6G(SCH_1):PAGE155_I89@PURE_QUANTA.Q_RES(CHIPS)':
 'B': CDS_PINID='B';
NODE_NAME     R3 2
 '@T6G_MB_LIB.T6G(SCH_1):PAGE82_I154@PURE_QUANTA.Q_RES(CHIPS)':
 'B': CDS_PINID='B';
NODE_NAME     C1 2
 '@T6G_MB_LIB.T6G(SCH_1):PAGE361_I110@PURE_QUANTA.Q_CAP(CHIPS)':
 'B': CDS_PINID='B';
NODE_NAME     R44 2
 '@T6G_MB_LIB.T6G(SCH_1):PAGE361_I115@PURE_QUANTA.Q_RES(CHIPS)':
 'B': CDS_PINID='B';
NODE_NAME     U1 4
 '@T6G_MB_LIB.T6G(SCH_1):PAGE361_I97@PURE_QUANTA.M24128BWMN6TP(CHIPS)':
 'VSS': CDS_PINID='VSS';
NODE_NAME     R62 2
 '@T6G_MB_LIB.T6G(SCH_1):PAGE361_I104@PURE_QUANTA.Q_RES(CHIPS)':
 'B': CDS_PINID='B';
NODE_NAME     R54 2
 '@T6G_MB_LIB.T6G(SCH_1):PAGE361_I107@PURE_QUANTA.Q_RES(CHIPS)':
 'B': CDS_PINID='B';
NODE_NAME     R69 2
 '@T6G_MB_LIB.T6G(SCH_1):PAGE361_I121@PURE_QUANTA.Q_RES(CHIPS)':
 'B': CDS_PINID='B';
NODE_NAME     R136 2
 '@T6G_MB_LIB.T6G(SCH_1):PAGE82_I162@PURE_QUANTA.Q_RES(CHIPS)':
 'B': CDS_PINID='B';
NODE_NAME     R126 2
 '@T6G_MB_LIB.T6G(SCH_1):PAGE82_I163@PURE_QUANTA.Q_RES(CHIPS)':
 'B': CDS_PINID='B';
NODE_NAME     C11 2
 '@T6G_MB_LIB.T6G(SCH_1):PAGE138_I89@PURE_QUANTA.Q_CAP(CHIPS)':
 'B': CDS_PINID='B';
NODE_NAME     C3 2
 '@T6G_MB_LIB.T6G(SCH_1):PAGE137_I56@PURE_QUANTA.Q_CAP(CHIPS)':
 'B': CDS_PINID='B';
NODE_NAME     C2 2
 '@T6G_MB_LIB.T6G(SCH_1):PAGE137_I59@PURE_QUANTA.Q_CAP(CHIPS)':
 'B': CDS_PINID='B';
NODE_NAME     R339 2
 '@T6G_MB_LIB.T6G(SCH_1):PAGE158_I120@PURE_QUANTA.Q_RES(CHIPS)':
 'B': CDS_PINID='B';
NODE_NAME     R340 2
 '@T6G_MB_LIB.T6G(SCH_1):PAGE158_I121@PURE_QUANTA.Q_RES(CHIPS)':
 'B': CDS_PINID='B';
NODE_NAME     R345 2
 '@T6G_MB_LIB.T6G(SCH_1):PAGE158_I124@PURE_QUANTA.Q_RES(CHIPS)':
 'B': CDS_PINID='B';
NODE_NAME     R343 2
 '@T6G_MB_LIB.T6G(SCH_1):PAGE158_I125@PURE_QUANTA.Q_RES(CHIPS)':
 'B': CDS_PINID='B';
NODE_NAME     R346 2
 '@T6G_MB_LIB.T6G(SCH_1):PAGE158_I126@PURE_QUANTA.Q_RES(CHIPS)':
 'B': CDS_PINID='B';
NODE_NAME     R344 2
 '@T6G_MB_LIB.T6G(SCH_1):PAGE158_I127@PURE_QUANTA.Q_RES(CHIPS)':
 'B': CDS_PINID='B';
NODE_NAME     PJ1 1
 '@T6G_MB_LIB.T6G(SCH_1):PAGE168_I143@PURE_QUANTA.CONN3_210HP1030BR1(CHIPS)':
 '1': CDS_PINID='\1\';
NODE_NAME     R6214 2
 '@T6G_MB_LIB.T6G(SCH_1):PAGE153_I88@PURE_QUANTA.Q_RES(CHIPS)':
 'B': CDS_PINID='B';
NODE_NAME     R6216 2
 '@T6G_MB_LIB.T6G(SCH_1):PAGE153_I90@PURE_QUANTA.Q_RES(CHIPS)':
 'B': CDS_PINID='B';
NODE_NAME     R341 2
 '@T6G_MB_LIB.T6G(SCH_1):PAGE158_I145@PURE_QUANTA.Q_RES(CHIPS)':
 'B': CDS_PINID='B';
NODE_NAME     R342 2
 '@T6G_MB_LIB.T6G(SCH_1):PAGE158_I146@PURE_QUANTA.Q_RES(CHIPS)':
 'B': CDS_PINID='B';
NODE_NAME     PR159 2
 '@T6G_MB_LIB.T6G(SCH_1):PAGE185_I142@PURE_QUANTA.Q_RES(CHIPS)':
 'B': CDS_PINID='B';
NODE_NAME     PR3002 1
 '@T6G_MB_LIB.T6G(SCH_1):PAGE372_I27@PURE_QUANTA.Q_RES(CHIPS)':
 'A': CDS_PINID='A';
NODE_NAME     R2227 2
 '@T6G_MB_LIB.T6G(SCH_1):PAGE372_I29@PURE_QUANTA.Q_RES(CHIPS)':
 'B': CDS_PINID='B';
NODE_NAME     R2222 2
 '@T6G_MB_LIB.T6G(SCH_1):PAGE372_I33@PURE_QUANTA.Q_RES(CHIPS)':
 'B': CDS_PINID='B';
NODE_NAME     U325 S
 '@T6G_MB_LIB.T6G(SCH_1):PAGE372_I42@PURE_QUANTA.MOSFET_N(CHIPS)':
 'SOURCE': CDS_PINID='SOURCE';
NODE_NAME     U206 2
 '@T6G_MB_LIB.T6G(SCH_1):PAGE372_I49@PURE_QUANTA.LT6700CS61TRPBF(CHIPS)':
 'GND': CDS_PINID='GND';
NODE_NAME     J45 B3
 '@T6G_MB_LIB.T6G(SCH_1):PAGE363_I466@PURE_QUANTA.CONN60_101062636003K02LF(CHIPS)':
 'B3': CDS_PINID='B3';
NODE_NAME     J45 P1_1
 '@T6G_MB_LIB.T6G(SCH_1):PAGE363_I466@PURE_QUANTA.CONN60_101062636003K02LF(CHIPS)':
 'P1_1': CDS_PINID='P1_1';
NODE_NAME     J45 P1_2
 '@T6G_MB_LIB.T6G(SCH_1):PAGE363_I466@PURE_QUANTA.CONN60_101062636003K02LF(CHIPS)':
 'P1_2': CDS_PINID='P1_2';
NODE_NAME     J45 P1_3
 '@T6G_MB_LIB.T6G(SCH_1):PAGE363_I466@PURE_QUANTA.CONN60_101062636003K02LF(CHIPS)':
 'P1_3': CDS_PINID='P1_3';
NODE_NAME     J45 P1_4
 '@T6G_MB_LIB.T6G(SCH_1):PAGE363_I466@PURE_QUANTA.CONN60_101062636003K02LF(CHIPS)':
 'P1_4': CDS_PINID='P1_4';
NODE_NAME     J45 P1_5
 '@T6G_MB_LIB.T6G(SCH_1):PAGE363_I466@PURE_QUANTA.CONN60_101062636003K02LF(CHIPS)':
 'P1_5': CDS_PINID='P1_5';
NODE_NAME     J45 P1_6
 '@T6G_MB_LIB.T6G(SCH_1):PAGE363_I466@PURE_QUANTA.CONN60_101062636003K02LF(CHIPS)':
 'P1_6': CDS_PINID='P1_6';
NODE_NAME     J45 P1_7
 '@T6G_MB_LIB.T6G(SCH_1):PAGE363_I466@PURE_QUANTA.CONN60_101062636003K02LF(CHIPS)':
 'P1_7': CDS_PINID='P1_7';
NODE_NAME     J45 P1_8
 '@T6G_MB_LIB.T6G(SCH_1):PAGE363_I466@PURE_QUANTA.CONN60_101062636003K02LF(CHIPS)':
 'P1_8': CDS_PINID='P1_8';
NODE_NAME     J45 P2_1
 '@T6G_MB_LIB.T6G(SCH_1):PAGE363_I466@PURE_QUANTA.CONN60_101062636003K02LF(CHIPS)':
 'P2_1': CDS_PINID='P2_1';
NODE_NAME     J45 P2_2
 '@T6G_MB_LIB.T6G(SCH_1):PAGE363_I466@PURE_QUANTA.CONN60_101062636003K02LF(CHIPS)':
 'P2_2': CDS_PINID='P2_2';
NODE_NAME     J45 P2_3
 '@T6G_MB_LIB.T6G(SCH_1):PAGE363_I466@PURE_QUANTA.CONN60_101062636003K02LF(CHIPS)':
 'P2_3': CDS_PINID='P2_3';
NODE_NAME     J45 P2_4
 '@T6G_MB_LIB.T6G(SCH_1):PAGE363_I466@PURE_QUANTA.CONN60_101062636003K02LF(CHIPS)':
 'P2_4': CDS_PINID='P2_4';
NODE_NAME     J45 P2_5
 '@T6G_MB_LIB.T6G(SCH_1):PAGE363_I466@PURE_QUANTA.CONN60_101062636003K02LF(CHIPS)':
 'P2_5': CDS_PINID='P2_5';
NODE_NAME     J45 P2_6
 '@T6G_MB_LIB.T6G(SCH_1):PAGE363_I466@PURE_QUANTA.CONN60_101062636003K02LF(CHIPS)':
 'P2_6': CDS_PINID='P2_6';
NODE_NAME     J45 P2_7
 '@T6G_MB_LIB.T6G(SCH_1):PAGE363_I466@PURE_QUANTA.CONN60_101062636003K02LF(CHIPS)':
 'P2_7': CDS_PINID='P2_7';
NODE_NAME     J45 P2_8
 '@T6G_MB_LIB.T6G(SCH_1):PAGE363_I466@PURE_QUANTA.CONN60_101062636003K02LF(CHIPS)':
 'P2_8': CDS_PINID='P2_8';
NODE_NAME     J45 P3_1
 '@T6G_MB_LIB.T6G(SCH_1):PAGE363_I466@PURE_QUANTA.CONN60_101062636003K02LF(CHIPS)':
 'P3_1': CDS_PINID='P3_1';
NODE_NAME     J45 P3_2
 '@T6G_MB_LIB.T6G(SCH_1):PAGE363_I466@PURE_QUANTA.CONN60_101062636003K02LF(CHIPS)':
 'P3_2': CDS_PINID='P3_2';
NODE_NAME     J45 P3_3
 '@T6G_MB_LIB.T6G(SCH_1):PAGE363_I466@PURE_QUANTA.CONN60_101062636003K02LF(CHIPS)':
 'P3_3': CDS_PINID='P3_3';
NODE_NAME     J45 P3_4
 '@T6G_MB_LIB.T6G(SCH_1):PAGE363_I466@PURE_QUANTA.CONN60_101062636003K02LF(CHIPS)':
 'P3_4': CDS_PINID='P3_4';
NODE_NAME     J45 P3_5
 '@T6G_MB_LIB.T6G(SCH_1):PAGE363_I466@PURE_QUANTA.CONN60_101062636003K02LF(CHIPS)':
 'P3_5': CDS_PINID='P3_5';
NODE_NAME     J45 P3_6
 '@T6G_MB_LIB.T6G(SCH_1):PAGE363_I466@PURE_QUANTA.CONN60_101062636003K02LF(CHIPS)':
 'P3_6': CDS_PINID='P3_6';
NODE_NAME     J45 P3_7
 '@T6G_MB_LIB.T6G(SCH_1):PAGE363_I466@PURE_QUANTA.CONN60_101062636003K02LF(CHIPS)':
 'P3_7': CDS_PINID='P3_7';
NODE_NAME     J45 P3_8
 '@T6G_MB_LIB.T6G(SCH_1):PAGE363_I466@PURE_QUANTA.CONN60_101062636003K02LF(CHIPS)':
 'P3_8': CDS_PINID='P3_8';
NODE_NAME     R6125 2
 '@T6G_MB_LIB.T6G(SCH_1):PAGE83_I116@PURE_QUANTA.Q_RES(CHIPS)':
 'B': CDS_PINID='B';
NODE_NAME     R6141 2
 '@T6G_MB_LIB.T6G(SCH_1):PAGE83_I118@PURE_QUANTA.Q_RES(CHIPS)':
 'B': CDS_PINID='B';
NODE_NAME     R6126 2
 '@T6G_MB_LIB.T6G(SCH_1):PAGE83_I119@PURE_QUANTA.Q_RES(CHIPS)':
 'B': CDS_PINID='B';
NODE_NAME     R6142 2
 '@T6G_MB_LIB.T6G(SCH_1):PAGE83_I122@PURE_QUANTA.Q_RES(CHIPS)':
 'B': CDS_PINID='B';
NODE_NAME     PC2167 2
 '@T6G_MB_LIB.T6G(SCH_1):PAGE344_I58@PURE_QUANTA.Q_CAP(CHIPS)':
 'B': CDS_PINID='B';
NODE_NAME     J48 2
 '@T6G_MB_LIB.T6G(SCH_1):PAGE27_I424@PURE_QUANTA.SCONN8_G802M0083150RD3HR(CHIPS)':
 '2': CDS_PINID='\2\';
NODE_NAME     J48 4
 '@T6G_MB_LIB.T6G(SCH_1):PAGE27_I424@PURE_QUANTA.SCONN8_G802M0083150RD3HR(CHIPS)':
 '4': CDS_PINID='\4\';
NODE_NAME     J48 6
 '@T6G_MB_LIB.T6G(SCH_1):PAGE27_I424@PURE_QUANTA.SCONN8_G802M0083150RD3HR(CHIPS)':
 '6': CDS_PINID='\6\';
NODE_NAME     J48 8
 '@T6G_MB_LIB.T6G(SCH_1):PAGE27_I424@PURE_QUANTA.SCONN8_G802M0083150RD3HR(CHIPS)':
 '8': CDS_PINID='\8\';
NODE_NAME     J5 2
 '@T6G_MB_LIB.T6G(SCH_1):PAGE27_I425@PURE_QUANTA.SCONN8_G802M0083150RD3HR(CHIPS)':
 '2': CDS_PINID='\2\';
NODE_NAME     J5 4
 '@T6G_MB_LIB.T6G(SCH_1):PAGE27_I425@PURE_QUANTA.SCONN8_G802M0083150RD3HR(CHIPS)':
 '4': CDS_PINID='\4\';
NODE_NAME     J5 6
 '@T6G_MB_LIB.T6G(SCH_1):PAGE27_I425@PURE_QUANTA.SCONN8_G802M0083150RD3HR(CHIPS)':
 '6': CDS_PINID='\6\';
NODE_NAME     J5 8
 '@T6G_MB_LIB.T6G(SCH_1):PAGE27_I425@PURE_QUANTA.SCONN8_G802M0083150RD3HR(CHIPS)':
 '8': CDS_PINID='\8\';
NODE_NAME     J7 2
 '@T6G_MB_LIB.T6G(SCH_1):PAGE54_I418@PURE_QUANTA.SCONN8_G802M0083150RD3HR(CHIPS)':
 '2': CDS_PINID='\2\';
NODE_NAME     J7 4
 '@T6G_MB_LIB.T6G(SCH_1):PAGE54_I418@PURE_QUANTA.SCONN8_G802M0083150RD3HR(CHIPS)':
 '4': CDS_PINID='\4\';
NODE_NAME     J7 6
 '@T6G_MB_LIB.T6G(SCH_1):PAGE54_I418@PURE_QUANTA.SCONN8_G802M0083150RD3HR(CHIPS)':
 '6': CDS_PINID='\6\';
NODE_NAME     J7 8
 '@T6G_MB_LIB.T6G(SCH_1):PAGE54_I418@PURE_QUANTA.SCONN8_G802M0083150RD3HR(CHIPS)':
 '8': CDS_PINID='\8\';
NODE_NAME     J49 2
 '@T6G_MB_LIB.T6G(SCH_1):PAGE54_I419@PURE_QUANTA.SCONN8_G802M0083150RD3HR(CHIPS)':
 '2': CDS_PINID='\2\';
NODE_NAME     J49 4
 '@T6G_MB_LIB.T6G(SCH_1):PAGE54_I419@PURE_QUANTA.SCONN8_G802M0083150RD3HR(CHIPS)':
 '4': CDS_PINID='\4\';
NODE_NAME     J49 6
 '@T6G_MB_LIB.T6G(SCH_1):PAGE54_I419@PURE_QUANTA.SCONN8_G802M0083150RD3HR(CHIPS)':
 '6': CDS_PINID='\6\';
NODE_NAME     J49 8
 '@T6G_MB_LIB.T6G(SCH_1):PAGE54_I419@PURE_QUANTA.SCONN8_G802M0083150RD3HR(CHIPS)':
 '8': CDS_PINID='\8\';
NODE_NAME     Y8004 2
 '@T6G_MB_LIB.T6G(SCH_1):PAGE358_I210@PURE_QUANTA.Q_XTAL_4P_13BI_24GND(CHIPS)':
 'G1': CDS_PINID='G1';
NODE_NAME     Y8004 4
 '@T6G_MB_LIB.T6G(SCH_1):PAGE358_I210@PURE_QUANTA.Q_XTAL_4P_13BI_24GND(CHIPS)':
 'G2': CDS_PINID='G2';
NODE_NAME     PR464 1
 '@T6G_MB_LIB.T6G(SCH_1):PAGE199_I89@PURE_QUANTA.Q_RES(CHIPS)':
 'A': CDS_PINID='A';
NODE_NAME     U6002 TH
 '@T6G_MB_LIB.T6G(SCH_1):PAGE155_I101@PURE_QUANTA.TUSB8042AIRGCR(CHIPS)':
 'TH_VSS': CDS_PINID='TH_VSS';
NODE_NAME     R6272 2
 '@T6G_MB_LIB.T6G(SCH_1):PAGE155_I105@PURE_QUANTA.Q_RES(CHIPS)':
 'B': CDS_PINID='B';
NODE_NAME     R6333 2
 '@T6G_MB_LIB.T6G(SCH_1):PAGE155_I111@PURE_QUANTA.Q_RES(CHIPS)':
 'B': CDS_PINID='B';
NODE_NAME     R6325 2
 '@T6G_MB_LIB.T6G(SCH_1):PAGE155_I116@PURE_QUANTA.Q_RES(CHIPS)':
 'B': CDS_PINID='B';
NODE_NAME     R6319 2
 '@T6G_MB_LIB.T6G(SCH_1):PAGE155_I121@PURE_QUANTA.Q_RES(CHIPS)':
 'B': CDS_PINID='B';
NODE_NAME     C6088 2
 '@T6G_MB_LIB.T6G(SCH_1):PAGE155_I127@PURE_QUANTA.Q_CAP(CHIPS)':
 'B': CDS_PINID='B';
NODE_NAME     R6321 2
 '@T6G_MB_LIB.T6G(SCH_1):PAGE155_I129@PURE_QUANTA.Q_RES(CHIPS)':
 'B': CDS_PINID='B';
NODE_NAME     R6278 2
 '@T6G_MB_LIB.T6G(SCH_1):PAGE157_I124@PURE_QUANTA.Q_RES(CHIPS)':
 'B': CDS_PINID='B';
NODE_NAME     C6089 2
 '@T6G_MB_LIB.T6G(SCH_1):PAGE155_I145@PURE_QUANTA.Q_CAP(CHIPS)':
 'B': CDS_PINID='B';
NODE_NAME     R6281 2
 '@T6G_MB_LIB.T6G(SCH_1):PAGE157_I139@PURE_QUANTA.Q_RES(CHIPS)':
 'B': CDS_PINID='B';
NODE_NAME     R6302 2
 '@T6G_MB_LIB.T6G(SCH_1):PAGE155_I175@PURE_QUANTA.Q_RES(CHIPS)':
 'B': CDS_PINID='B';
NODE_NAME     R6307 2
 '@T6G_MB_LIB.T6G(SCH_1):PAGE157_I156@PURE_QUANTA.Q_RES(CHIPS)':
 'B': CDS_PINID='B';
NODE_NAME     R6309 2
 '@T6G_MB_LIB.T6G(SCH_1):PAGE157_I158@PURE_QUANTA.Q_RES(CHIPS)':
 'B': CDS_PINID='B';
NODE_NAME     R6330 1
 '@T6G_MB_LIB.T6G(SCH_1):PAGE155_I188@PURE_QUANTA.Q_RES(CHIPS)':
 'A': CDS_PINID='A';
NODE_NAME     Y6000 2
 '@T6G_MB_LIB.T6G(SCH_1):PAGE157_I164@PURE_QUANTA.Q_XTAL_4P_13BI_24GND(CHIPS)':
 'G1': CDS_PINID='G1';
NODE_NAME     Y6000 4
 '@T6G_MB_LIB.T6G(SCH_1):PAGE157_I164@PURE_QUANTA.Q_XTAL_4P_13BI_24GND(CHIPS)':
 'G2': CDS_PINID='G2';
NODE_NAME     R6288 2
 '@T6G_MB_LIB.T6G(SCH_1):PAGE155_I198@PURE_QUANTA.Q_RES(CHIPS)':
 'B': CDS_PINID='B';
NODE_NAME     R6331 2
 '@T6G_MB_LIB.T6G(SCH_1):PAGE155_I207@PURE_QUANTA.Q_RES(CHIPS)':
 'B': CDS_PINID='B';
NODE_NAME     R6332 2
 '@T6G_MB_LIB.T6G(SCH_1):PAGE155_I208@PURE_QUANTA.Q_RES(CHIPS)':
 'B': CDS_PINID='B';
NODE_NAME     U100 2
 '@T6G_MB_LIB.T6G(SCH_1):PAGE273_I77@PURE_QUANTA.RT9818C44GV(CHIPS)':
 'GND': CDS_PINID='GND';
NODE_NAME     C6122 2
 '@T6G_MB_LIB.T6G(SCH_1):PAGE273_I79@PURE_QUANTA.Q_CAP(CHIPS)':
 'B': CDS_PINID='B';
NODE_NAME     R480 2
 '@T6G_MB_LIB.T6G(SCH_1):PAGE273_I84@PURE_QUANTA.Q_RES(CHIPS)':
 'B': CDS_PINID='B';
NODE_NAME     R6050 2
 '@T6G_MB_LIB.T6G(SCH_1):PAGE273_I91@PURE_QUANTA.Q_RES(CHIPS)':
 'B': CDS_PINID='B';
NODE_NAME     Q1 1
 '@T6G_MB_LIB.T6G(SCH_1):PAGE273_I97@PURE_QUANTA.MOSFET_NCH_DUAL(CHIPS)':
 'S1': CDS_PINID='S1';
NODE_NAME     Q1 4
 '@T6G_MB_LIB.T6G(SCH_1):PAGE273_I98@PURE_QUANTA.MOSFET_NCH_DUAL(CHIPS)':
 'S2': CDS_PINID='S2';
NODE_NAME     Q3 1
 '@T6G_MB_LIB.T6G(SCH_1):PAGE273_I107@PURE_QUANTA.MOSFET_NCH_DUAL(CHIPS)':
 'S1': CDS_PINID='S1';
NODE_NAME     Q3 4
 '@T6G_MB_LIB.T6G(SCH_1):PAGE273_I108@PURE_QUANTA.MOSFET_NCH_DUAL(CHIPS)':
 'S2': CDS_PINID='S2';
NODE_NAME     C29 2
 '@T6G_MB_LIB.T6G(SCH_1):PAGE273_I116@PURE_QUANTA.Q_CAP(CHIPS)':
 'B': CDS_PINID='B';
NODE_NAME     Q27 1
 '@T6G_MB_LIB.T6G(SCH_1):PAGE273_I123@PURE_QUANTA.BSS138DW7F(CHIPS)':
 'S1': CDS_PINID='S1';
NODE_NAME     Q27 4
 '@T6G_MB_LIB.T6G(SCH_1):PAGE273_I123@PURE_QUANTA.BSS138DW7F(CHIPS)':
 'S2': CDS_PINID='S2';
NODE_NAME     U6006 1
 '@T6G_MB_LIB.T6G(SCH_1):PAGE273_I131@PURE_QUANTA.APX80929SAG7(CHIPS)':
 'GND': CDS_PINID='GND';
NODE_NAME     C6500 2
 '@T6G_MB_LIB.T6G(SCH_1):PAGE273_I133@PURE_QUANTA.Q_CAP(CHIPS)':
 'B': CDS_PINID='B';
NODE_NAME     R6501 2
 '@T6G_MB_LIB.T6G(SCH_1):PAGE273_I139@PURE_QUANTA.Q_RES(CHIPS)':
 'B': CDS_PINID='B';
NODE_NAME     H111 2
 '@T6G_MB_LIB.T6G(SCH_1):PAGE212_I120@PURE_QUANTA.GND_HOLE(CHIPS)':
 'GND2': CDS_PINID='GND2';
NODE_NAME     H111 3
 '@T6G_MB_LIB.T6G(SCH_1):PAGE212_I120@PURE_QUANTA.GND_HOLE(CHIPS)':
 'GND3': CDS_PINID='GND3';
NODE_NAME     H111 4
 '@T6G_MB_LIB.T6G(SCH_1):PAGE212_I120@PURE_QUANTA.GND_HOLE(CHIPS)':
 'GND4': CDS_PINID='GND4';
NODE_NAME     H111 5
 '@T6G_MB_LIB.T6G(SCH_1):PAGE212_I120@PURE_QUANTA.GND_HOLE(CHIPS)':
 'GND5': CDS_PINID='GND5';
NODE_NAME     H111 6
 '@T6G_MB_LIB.T6G(SCH_1):PAGE212_I120@PURE_QUANTA.GND_HOLE(CHIPS)':
 'GND6': CDS_PINID='GND6';
NODE_NAME     H111 7
 '@T6G_MB_LIB.T6G(SCH_1):PAGE212_I120@PURE_QUANTA.GND_HOLE(CHIPS)':
 'GND7': CDS_PINID='GND7';
NODE_NAME     H111 8
 '@T6G_MB_LIB.T6G(SCH_1):PAGE212_I120@PURE_QUANTA.GND_HOLE(CHIPS)':
 'GND8': CDS_PINID='GND8';
NODE_NAME     H111 9
 '@T6G_MB_LIB.T6G(SCH_1):PAGE212_I120@PURE_QUANTA.GND_HOLE(CHIPS)':
 'GND9': CDS_PINID='GND9';
NODE_NAME     H112 2
 '@T6G_MB_LIB.T6G(SCH_1):PAGE212_I123@PURE_QUANTA.GND_HOLE(CHIPS)':
 'GND2': CDS_PINID='GND2';
NODE_NAME     H112 3
 '@T6G_MB_LIB.T6G(SCH_1):PAGE212_I123@PURE_QUANTA.GND_HOLE(CHIPS)':
 'GND3': CDS_PINID='GND3';
NODE_NAME     H112 4
 '@T6G_MB_LIB.T6G(SCH_1):PAGE212_I123@PURE_QUANTA.GND_HOLE(CHIPS)':
 'GND4': CDS_PINID='GND4';
NODE_NAME     H112 5
 '@T6G_MB_LIB.T6G(SCH_1):PAGE212_I123@PURE_QUANTA.GND_HOLE(CHIPS)':
 'GND5': CDS_PINID='GND5';
NODE_NAME     H112 6
 '@T6G_MB_LIB.T6G(SCH_1):PAGE212_I123@PURE_QUANTA.GND_HOLE(CHIPS)':
 'GND6': CDS_PINID='GND6';
NODE_NAME     H112 7
 '@T6G_MB_LIB.T6G(SCH_1):PAGE212_I123@PURE_QUANTA.GND_HOLE(CHIPS)':
 'GND7': CDS_PINID='GND7';
NODE_NAME     H112 8
 '@T6G_MB_LIB.T6G(SCH_1):PAGE212_I123@PURE_QUANTA.GND_HOLE(CHIPS)':
 'GND8': CDS_PINID='GND8';
NODE_NAME     H112 9
 '@T6G_MB_LIB.T6G(SCH_1):PAGE212_I123@PURE_QUANTA.GND_HOLE(CHIPS)':
 'GND9': CDS_PINID='GND9';
NODE_NAME     R6502 2
 '@T6G_MB_LIB.T6G(SCH_1):PAGE28_I224@PURE_QUANTA.Q_RES(CHIPS)':
 'B': CDS_PINID='B';
NODE_NAME     R6503 2
 '@T6G_MB_LIB.T6G(SCH_1):PAGE55_I392@PURE_QUANTA.Q_RES(CHIPS)':
 'B': CDS_PINID='B';
NODE_NAME     U320 3
 '@T6G_MB_LIB.T6G(SCH_1):PAGE337_I82@PURE_QUANTA.74LVC1G66GV(CHIPS)':
 'GND': CDS_PINID='GND';
NODE_NAME     U321 3
 '@T6G_MB_LIB.T6G(SCH_1):PAGE342_I76@PURE_QUANTA.74LVC1G66GV(CHIPS)':
 'GND': CDS_PINID='GND';
NODE_NAME     H86 1
 '@T6G_MB_LIB.T6G(SCH_1):PAGE212_I125@PURE_QUANTA.HOLE(CHIPS)':
 '1': CDS_PINID='\1\';
NODE_NAME     H87 1
 '@T6G_MB_LIB.T6G(SCH_1):PAGE212_I127@PURE_QUANTA.HOLE(CHIPS)':
 '1': CDS_PINID='\1\';
NODE_NAME     H88 1
 '@T6G_MB_LIB.T6G(SCH_1):PAGE212_I129@PURE_QUANTA.HOLE(CHIPS)':
 '1': CDS_PINID='\1\';
NODE_NAME     H89 1
 '@T6G_MB_LIB.T6G(SCH_1):PAGE212_I132@PURE_QUANTA.HOLE(CHIPS)':
 '1': CDS_PINID='\1\';
NODE_NAME     H91 1
 '@T6G_MB_LIB.T6G(SCH_1):PAGE212_I133@PURE_QUANTA.HOLE(CHIPS)':
 '1': CDS_PINID='\1\';
NODE_NAME     H92 1
 '@T6G_MB_LIB.T6G(SCH_1):PAGE212_I135@PURE_QUANTA.HOLE(CHIPS)':
 '1': CDS_PINID='\1\';
NODE_NAME     H93 1
 '@T6G_MB_LIB.T6G(SCH_1):PAGE212_I138@PURE_QUANTA.HOLE(CHIPS)':
 '1': CDS_PINID='\1\';
NODE_NAME     H94 1
 '@T6G_MB_LIB.T6G(SCH_1):PAGE212_I140@PURE_QUANTA.HOLE(CHIPS)':
 '1': CDS_PINID='\1\';
NODE_NAME     H95 1
 '@T6G_MB_LIB.T6G(SCH_1):PAGE212_I141@PURE_QUANTA.HOLE(CHIPS)':
 '1': CDS_PINID='\1\';
NODE_NAME     H96 1
 '@T6G_MB_LIB.T6G(SCH_1):PAGE212_I142@PURE_QUANTA.HOLE(CHIPS)':
 '1': CDS_PINID='\1\';
NODE_NAME     H97 1
 '@T6G_MB_LIB.T6G(SCH_1):PAGE212_I145@PURE_QUANTA.HOLE(CHIPS)':
 '1': CDS_PINID='\1\';
NODE_NAME     H98 1
 '@T6G_MB_LIB.T6G(SCH_1):PAGE212_I147@PURE_QUANTA.HOLE(CHIPS)':
 '1': CDS_PINID='\1\';
NODE_NAME     H99 1
 '@T6G_MB_LIB.T6G(SCH_1):PAGE212_I149@PURE_QUANTA.HOLE(CHIPS)':
 '1': CDS_PINID='\1\';
NODE_NAME     H100 1
 '@T6G_MB_LIB.T6G(SCH_1):PAGE212_I152@PURE_QUANTA.HOLE(CHIPS)':
 '1': CDS_PINID='\1\';
NODE_NAME     H101 1
 '@T6G_MB_LIB.T6G(SCH_1):PAGE212_I153@PURE_QUANTA.HOLE(CHIPS)':
 '1': CDS_PINID='\1\';
NODE_NAME     H102 1
 '@T6G_MB_LIB.T6G(SCH_1):PAGE212_I156@PURE_QUANTA.HOLE(CHIPS)':
 '1': CDS_PINID='\1\';
NODE_NAME     H103 1
 '@T6G_MB_LIB.T6G(SCH_1):PAGE212_I157@PURE_QUANTA.HOLE(CHIPS)':
 '1': CDS_PINID='\1\';
NODE_NAME     H104 1
 '@T6G_MB_LIB.T6G(SCH_1):PAGE212_I159@PURE_QUANTA.HOLE(CHIPS)':
 '1': CDS_PINID='\1\';
NODE_NAME     H105 1
 '@T6G_MB_LIB.T6G(SCH_1):PAGE212_I161@PURE_QUANTA.HOLE(CHIPS)':
 '1': CDS_PINID='\1\';
NODE_NAME     H106 1
 '@T6G_MB_LIB.T6G(SCH_1):PAGE212_I163@PURE_QUANTA.HOLE(CHIPS)':
 '1': CDS_PINID='\1\';
NODE_NAME     H128 1
 '@T6G_MB_LIB.T6G(SCH_1):PAGE212_I166@PURE_QUANTA.HOLE(CHIPS)':
 '1': CDS_PINID='\1\';
NODE_NAME     H6002 1
 '@T6G_MB_LIB.T6G(SCH_1):PAGE212_I168@PURE_QUANTA.HOLE(CHIPS)':
 '1': CDS_PINID='\1\';
NODE_NAME     Q9000 1
 '@T6G_MB_LIB.T6G(SCH_1):PAGE330_I21@PURE_QUANTA.MOSFET_NCH_DUAL(CHIPS)':
 'S1': CDS_PINID='S1';
NODE_NAME     Q8000 4
 '@T6G_MB_LIB.T6G(SCH_1):PAGE330_I30@PURE_QUANTA.MOSFET_NCH_DUAL(CHIPS)':
 'S2': CDS_PINID='S2';
NODE_NAME     C8001 2
 '@T6G_MB_LIB.T6G(SCH_1):PAGE258_I68@PURE_QUANTA.Q_CAP(CHIPS)':
 'B': CDS_PINID='B';
NODE_NAME     C8002 2
 '@T6G_MB_LIB.T6G(SCH_1):PAGE258_I70@PURE_QUANTA.Q_CAP(CHIPS)':
 'B': CDS_PINID='B';
NODE_NAME     C8003 2
 '@T6G_MB_LIB.T6G(SCH_1):PAGE258_I72@PURE_QUANTA.Q_CAP(CHIPS)':
 'B': CDS_PINID='B';
NODE_NAME     C8004 2
 '@T6G_MB_LIB.T6G(SCH_1):PAGE258_I74@PURE_QUANTA.Q_CAP(CHIPS)':
 'B': CDS_PINID='B';
NODE_NAME     D8000 C
 '@T6G_MB_LIB.T6G(SCH_1):PAGE375_I42@PURE_QUANTA.Q_LED(CHIPS)':
 'C': CDS_PINID='C';
NODE_NAME     D8001 C
 '@T6G_MB_LIB.T6G(SCH_1):PAGE375_I52@PURE_QUANTA.Q_LED(CHIPS)':
 'C': CDS_PINID='C';
NODE_NAME     Q8001 1
 '@T6G_MB_LIB.T6G(SCH_1):PAGE375_I57@PURE_QUANTA.MOSFET_NCH_DUAL(CHIPS)':
 'S1': CDS_PINID='S1';
NODE_NAME     Q8001 4
 '@T6G_MB_LIB.T6G(SCH_1):PAGE375_I58@PURE_QUANTA.MOSFET_NCH_DUAL(CHIPS)':
 'S2': CDS_PINID='S2';
NODE_NAME     R1800 2
 '@T6G_MB_LIB.T6G(SCH_1):PAGE369_I170@PURE_QUANTA.Q_RES(CHIPS)':
 'B': CDS_PINID='B';
NODE_NAME     C8005 2
 '@T6G_MB_LIB.T6G(SCH_1):PAGE84_I101@PURE_QUANTA.Q_CAP(CHIPS)':
 'B': CDS_PINID='B';
NODE_NAME     C6 2
 '@T6G_MB_LIB.T6G(SCH_1):PAGE331_I111@PURE_QUANTA.Q_CAP(CHIPS)':
 'B': CDS_PINID='B';
NODE_NAME     C8006 2
 '@T6G_MB_LIB.T6G(SCH_1):PAGE149_I163@PURE_QUANTA.Q_CAP(CHIPS)':
 'B': CDS_PINID='B';
NODE_NAME     R1895 2
 '@T6G_MB_LIB.T6G(SCH_1):PAGE335_I169@PURE_QUANTA.Q_RES(CHIPS)':
 'B': CDS_PINID='B';
NODE_NAME     U8000 2
 '@T6G_MB_LIB.T6G(SCH_1):PAGE130_I1@PURE_QUANTA.NC7SB3157P6X(CHIPS)':
 'GND': CDS_PINID='GND';
NODE_NAME     C8007 2
 '@T6G_MB_LIB.T6G(SCH_1):PAGE130_I4@PURE_QUANTA.Q_CAP(CHIPS)':
 'B': CDS_PINID='B';
NODE_NAME     R8033 2
 '@T6G_MB_LIB.T6G(SCH_1):PAGE82_I170@PURE_QUANTA.Q_RES(CHIPS)':
 'B': CDS_PINID='B';
NODE_NAME     C8010 2
 '@T6G_MB_LIB.T6G(SCH_1):PAGE323_I64@PURE_QUANTA.Q_CAP(CHIPS)':
 'B': CDS_PINID='B';
NODE_NAME     U8003 1
 '@T6G_MB_LIB.T6G(SCH_1):PAGE323_I65@PURE_QUANTA.APX80929SAG7(CHIPS)':
 'GND': CDS_PINID='GND';
NODE_NAME     R8099 2
 '@T6G_MB_LIB.T6G(SCH_1):PAGE323_I68@PURE_QUANTA.Q_RES(CHIPS)':
 'B': CDS_PINID='B';
NODE_NAME     C8011 2
 '@T6G_MB_LIB.T6G(SCH_1):PAGE363_I469@PURE_QUANTA.Q_CAP(CHIPS)':
 'B': CDS_PINID='B';
NODE_NAME     U8004 3
 '@T6G_MB_LIB.T6G(SCH_1):PAGE365_I16@PURE_QUANTA.74LVC2G07DW7(CHIPS)':
 '2A': CDS_PINID='\2a\';
NODE_NAME     U8004 2
 '@T6G_MB_LIB.T6G(SCH_1):PAGE365_I16@PURE_QUANTA.74LVC2G07DW7(CHIPS)':
 'GND': CDS_PINID='GND';
NODE_NAME     C8013 2
 '@T6G_MB_LIB.T6G(SCH_1):PAGE365_I23@PURE_QUANTA.Q_CAP(CHIPS)':
 'B': CDS_PINID='B';
NODE_NAME     C8012 2
 '@T6G_MB_LIB.T6G(SCH_1):PAGE365_I25@PURE_QUANTA.Q_CAP(CHIPS)':
 'B': CDS_PINID='B';
NODE_NAME     C2030 2
 '@T6G_MB_LIB.T6G(SCH_1):PAGE358_I211@PURE_QUANTA.Q_CAP(CHIPS)':
 'B': CDS_PINID='B';
NODE_NAME     C2029 2
 '@T6G_MB_LIB.T6G(SCH_1):PAGE358_I212@PURE_QUANTA.Q_CAP(CHIPS)':
 'B': CDS_PINID='B';
NODE_NAME     C91 2
 '@T6G_MB_LIB.T6G(SCH_1):PAGE153_I92@PURE_QUANTA.Q_CAP(CHIPS)':
 'B': CDS_PINID='B';
NODE_NAME     R8109 2
 '@T6G_MB_LIB.T6G(SCH_1):PAGE371_I82@PURE_QUANTA.Q_RES(CHIPS)':
 'B': CDS_PINID='B';
NODE_NAME     C8014 2
 '@T6G_MB_LIB.T6G(SCH_1):PAGE371_I87@PURE_QUANTA.Q_CAP(CHIPS)':
 'B': CDS_PINID='B';
NODE_NAME     C8015 2
 '@T6G_MB_LIB.T6G(SCH_1):PAGE371_I89@PURE_QUANTA.Q_CAP(CHIPS)':
 'B': CDS_PINID='B';
NODE_NAME     C8016 2
 '@T6G_MB_LIB.T6G(SCH_1):PAGE371_I95@PURE_QUANTA.Q_CAP(CHIPS)':
 'B': CDS_PINID='B';
NODE_NAME     U8005 2
 '@T6G_MB_LIB.T6G(SCH_1):PAGE371_I101@PURE_QUANTA.LM4040AIM3X25NOPB(CHIPS)':
 '2-': CDS_PINID='\2-\';
NODE_NAME     U8006 2
 '@T6G_MB_LIB.T6G(SCH_1):PAGE371_I104@PURE_QUANTA.AP331AWG7(CHIPS)':
 'GND': CDS_PINID='GND';
NODE_NAME     U8007 2
 '@T6G_MB_LIB.T6G(SCH_1):PAGE372_I51@PURE_QUANTA.LM4040AIM3X25NOPB(CHIPS)':
 '2-': CDS_PINID='\2-\';
NODE_NAME     R8115 2
 '@T6G_MB_LIB.T6G(SCH_1):PAGE372_I55@PURE_QUANTA.Q_RES(CHIPS)':
 'B': CDS_PINID='B';
NODE_NAME     C8017 2
 '@T6G_MB_LIB.T6G(SCH_1):PAGE372_I59@PURE_QUANTA.Q_CAP(CHIPS)':
 'B': CDS_PINID='B';
NODE_NAME     C8018 2
 '@T6G_MB_LIB.T6G(SCH_1):PAGE372_I61@PURE_QUANTA.Q_CAP(CHIPS)':
 'B': CDS_PINID='B';
NODE_NAME     C8019 2
 '@T6G_MB_LIB.T6G(SCH_1):PAGE372_I66@PURE_QUANTA.Q_CAP(CHIPS)':
 'B': CDS_PINID='B';
NODE_NAME     U8008 2
 '@T6G_MB_LIB.T6G(SCH_1):PAGE372_I71@PURE_QUANTA.AP331AWG7(CHIPS)':
 'GND': CDS_PINID='GND';
NODE_NAME     R8122 2
 '@T6G_MB_LIB.T6G(SCH_1):PAGE372_I75@PURE_QUANTA.Q_RES(CHIPS)':
 'B': CDS_PINID='B';
NODE_NAME     C8020 2
 '@T6G_MB_LIB.T6G(SCH_1):PAGE372_I79@PURE_QUANTA.Q_CAP(CHIPS)':
 'B': CDS_PINID='B';
NODE_NAME     U8010 2
 '@T6G_MB_LIB.T6G(SCH_1):PAGE372_I80@PURE_QUANTA.AP331AWG7(CHIPS)':
 'GND': CDS_PINID='GND';
NODE_NAME     C8022 2
 '@T6G_MB_LIB.T6G(SCH_1):PAGE372_I84@PURE_QUANTA.Q_CAP(CHIPS)':
 'B': CDS_PINID='B';
NODE_NAME     C8021 2
 '@T6G_MB_LIB.T6G(SCH_1):PAGE372_I92@PURE_QUANTA.Q_CAP(CHIPS)':
 'B': CDS_PINID='B';
NODE_NAME     U8009 2
 '@T6G_MB_LIB.T6G(SCH_1):PAGE372_I93@PURE_QUANTA.LM4040AIM3X25NOPB(CHIPS)':
 '2-': CDS_PINID='\2-\';
NODE_NAME     PC8000 2
 '@T6G_MB_LIB.T6G(SCH_1):PAGE167_I44@PURE_QUANTA.Q_CAP(CHIPS)':
 'B': CDS_PINID='B';
NODE_NAME     PC8001 2
 '@T6G_MB_LIB.T6G(SCH_1):PAGE167_I45@PURE_QUANTA.Q_CAP(CHIPS)':
 'B': CDS_PINID='B';
NODE_NAME     PC8002 2
 '@T6G_MB_LIB.T6G(SCH_1):PAGE184_I57@PURE_QUANTA.Q_CAP(CHIPS)':
 'B': CDS_PINID='B';
NODE_NAME     PC8003 2
 '@T6G_MB_LIB.T6G(SCH_1):PAGE201_I57@PURE_QUANTA.Q_CAP(CHIPS)':
 'B': CDS_PINID='B';
NODE_NAME     PC8004 2
 '@T6G_MB_LIB.T6G(SCH_1):PAGE183_I93@PURE_QUANTA.Q_CAP(CHIPS)':
 'B': CDS_PINID='B';
NODE_NAME     PC8005 2
 '@T6G_MB_LIB.T6G(SCH_1):PAGE183_I94@PURE_QUANTA.Q_CAP(CHIPS)':
 'B': CDS_PINID='B';
NODE_NAME     PC8006 2
 '@T6G_MB_LIB.T6G(SCH_1):PAGE200_I93@PURE_QUANTA.Q_CAP(CHIPS)':
 'B': CDS_PINID='B';
NODE_NAME     PC8007 2
 '@T6G_MB_LIB.T6G(SCH_1):PAGE200_I94@PURE_QUANTA.Q_CAP(CHIPS)':
 'B': CDS_PINID='B';
NODE_NAME     PC8009 2
 '@T6G_MB_LIB.T6G(SCH_1):PAGE173_I87@PURE_QUANTA.Q_CAP(CHIPS)':
 'B': CDS_PINID='B';
NODE_NAME     PC8010 2
 '@T6G_MB_LIB.T6G(SCH_1):PAGE173_I88@PURE_QUANTA.Q_CAP(CHIPS)':
 'B': CDS_PINID='B';
NODE_NAME     PC8011 2
 '@T6G_MB_LIB.T6G(SCH_1):PAGE190_I87@PURE_QUANTA.Q_CAP(CHIPS)':
 'B': CDS_PINID='B';
NODE_NAME     PC8012 2
 '@T6G_MB_LIB.T6G(SCH_1):PAGE190_I88@PURE_QUANTA.Q_CAP(CHIPS)':
 'B': CDS_PINID='B';
NODE_NAME     PC8013 2
 '@T6G_MB_LIB.T6G(SCH_1):PAGE245_I70@PURE_QUANTA.Q_CAP(CHIPS)':
 'B': CDS_PINID='B';
NODE_NAME     PC8014 2
 '@T6G_MB_LIB.T6G(SCH_1):PAGE245_I71@PURE_QUANTA.Q_CAP(CHIPS)':
 'B': CDS_PINID='B';
NODE_NAME     U6014 AC13
 '@T6G_MB_LIB.T6G(SCH_1):PAGE400_I2@PURE_QUANTA.PT5161LRS(CHIPS)':
 'GND1': CDS_PINID='GND1';
NODE_NAME     U6014 AC22
 '@T6G_MB_LIB.T6G(SCH_1):PAGE400_I2@PURE_QUANTA.PT5161LRS(CHIPS)':
 'GND2': CDS_PINID='GND2';
NODE_NAME     U6014 AC32
 '@T6G_MB_LIB.T6G(SCH_1):PAGE400_I2@PURE_QUANTA.PT5161LRS(CHIPS)':
 'GND3': CDS_PINID='GND3';
NODE_NAME     U6014 AC4
 '@T6G_MB_LIB.T6G(SCH_1):PAGE400_I2@PURE_QUANTA.PT5161LRS(CHIPS)':
 'GND4': CDS_PINID='GND4';
NODE_NAME     U6014 AD2
 '@T6G_MB_LIB.T6G(SCH_1):PAGE400_I2@PURE_QUANTA.PT5161LRS(CHIPS)':
 'GND5': CDS_PINID='GND5';
NODE_NAME     U6014 AD34
 '@T6G_MB_LIB.T6G(SCH_1):PAGE400_I2@PURE_QUANTA.PT5161LRS(CHIPS)':
 'GND6': CDS_PINID='GND6';
NODE_NAME     U6014 AE1
 '@T6G_MB_LIB.T6G(SCH_1):PAGE400_I2@PURE_QUANTA.PT5161LRS(CHIPS)':
 'GND7': CDS_PINID='GND7';
NODE_NAME     U6014 AE35
 '@T6G_MB_LIB.T6G(SCH_1):PAGE400_I2@PURE_QUANTA.PT5161LRS(CHIPS)':
 'GND8': CDS_PINID='GND8';
NODE_NAME     U6014 AK13
 '@T6G_MB_LIB.T6G(SCH_1):PAGE400_I2@PURE_QUANTA.PT5161LRS(CHIPS)':
 'GND9': CDS_PINID='GND9';
NODE_NAME     U6014 AK22
 '@T6G_MB_LIB.T6G(SCH_1):PAGE400_I2@PURE_QUANTA.PT5161LRS(CHIPS)':
 'GND10': CDS_PINID='GND10';
NODE_NAME     U6014 AK32
 '@T6G_MB_LIB.T6G(SCH_1):PAGE400_I2@PURE_QUANTA.PT5161LRS(CHIPS)':
 'GND11': CDS_PINID='GND11';
NODE_NAME     U6014 AK4
 '@T6G_MB_LIB.T6G(SCH_1):PAGE400_I2@PURE_QUANTA.PT5161LRS(CHIPS)':
 'GND12': CDS_PINID='GND12';
NODE_NAME     U6014 AL2
 '@T6G_MB_LIB.T6G(SCH_1):PAGE400_I2@PURE_QUANTA.PT5161LRS(CHIPS)':
 'GND13': CDS_PINID='GND13';
NODE_NAME     U6014 AL34
 '@T6G_MB_LIB.T6G(SCH_1):PAGE400_I2@PURE_QUANTA.PT5161LRS(CHIPS)':
 'GND14': CDS_PINID='GND14';
NODE_NAME     U6014 AM1
 '@T6G_MB_LIB.T6G(SCH_1):PAGE400_I2@PURE_QUANTA.PT5161LRS(CHIPS)':
 'GND15': CDS_PINID='GND15';
NODE_NAME     U6014 AM35
 '@T6G_MB_LIB.T6G(SCH_1):PAGE400_I2@PURE_QUANTA.PT5161LRS(CHIPS)':
 'GND16': CDS_PINID='GND16';
NODE_NAME     U6014 AU13
 '@T6G_MB_LIB.T6G(SCH_1):PAGE400_I2@PURE_QUANTA.PT5161LRS(CHIPS)':
 'GND17': CDS_PINID='GND17';
NODE_NAME     U6014 AU22
 '@T6G_MB_LIB.T6G(SCH_1):PAGE400_I2@PURE_QUANTA.PT5161LRS(CHIPS)':
 'GND18': CDS_PINID='GND18';
NODE_NAME     U6014 AU32
 '@T6G_MB_LIB.T6G(SCH_1):PAGE400_I2@PURE_QUANTA.PT5161LRS(CHIPS)':
 'GND19': CDS_PINID='GND19';
NODE_NAME     U6014 AU4
 '@T6G_MB_LIB.T6G(SCH_1):PAGE400_I2@PURE_QUANTA.PT5161LRS(CHIPS)':
 'GND20': CDS_PINID='GND20';
NODE_NAME     U6014 AV2
 '@T6G_MB_LIB.T6G(SCH_1):PAGE400_I2@PURE_QUANTA.PT5161LRS(CHIPS)':
 'GND21': CDS_PINID='GND21';
NODE_NAME     U6014 AV34
 '@T6G_MB_LIB.T6G(SCH_1):PAGE400_I2@PURE_QUANTA.PT5161LRS(CHIPS)':
 'GND22': CDS_PINID='GND22';
NODE_NAME     U6014 AW1
 '@T6G_MB_LIB.T6G(SCH_1):PAGE400_I2@PURE_QUANTA.PT5161LRS(CHIPS)':
 'GND23': CDS_PINID='GND23';
NODE_NAME     U6014 AW35
 '@T6G_MB_LIB.T6G(SCH_1):PAGE400_I2@PURE_QUANTA.PT5161LRS(CHIPS)':
 'GND24': CDS_PINID='GND24';
NODE_NAME     U6014 B19
 '@T6G_MB_LIB.T6G(SCH_1):PAGE400_I2@PURE_QUANTA.PT5161LRS(CHIPS)':
 'GND25': CDS_PINID='GND25';
NODE_NAME     U6014 BD13
 '@T6G_MB_LIB.T6G(SCH_1):PAGE400_I2@PURE_QUANTA.PT5161LRS(CHIPS)':
 'GND26': CDS_PINID='GND26';
NODE_NAME     U6014 BD22
 '@T6G_MB_LIB.T6G(SCH_1):PAGE400_I2@PURE_QUANTA.PT5161LRS(CHIPS)':
 'GND27': CDS_PINID='GND27';
NODE_NAME     U6014 BD32
 '@T6G_MB_LIB.T6G(SCH_1):PAGE400_I2@PURE_QUANTA.PT5161LRS(CHIPS)':
 'GND28': CDS_PINID='GND28';
NODE_NAME     U6014 BD4
 '@T6G_MB_LIB.T6G(SCH_1):PAGE400_I2@PURE_QUANTA.PT5161LRS(CHIPS)':
 'GND29': CDS_PINID='GND29';
NODE_NAME     U6014 BE2
 '@T6G_MB_LIB.T6G(SCH_1):PAGE400_I2@PURE_QUANTA.PT5161LRS(CHIPS)':
 'GND30': CDS_PINID='GND30';
NODE_NAME     U6014 BE34
 '@T6G_MB_LIB.T6G(SCH_1):PAGE400_I2@PURE_QUANTA.PT5161LRS(CHIPS)':
 'GND31': CDS_PINID='GND31';
NODE_NAME     U6014 BF1
 '@T6G_MB_LIB.T6G(SCH_1):PAGE400_I2@PURE_QUANTA.PT5161LRS(CHIPS)':
 'GND32': CDS_PINID='GND32';
NODE_NAME     U6014 BF35
 '@T6G_MB_LIB.T6G(SCH_1):PAGE400_I2@PURE_QUANTA.PT5161LRS(CHIPS)':
 'GND33': CDS_PINID='GND33';
NODE_NAME     U6014 BL13
 '@T6G_MB_LIB.T6G(SCH_1):PAGE400_I2@PURE_QUANTA.PT5161LRS(CHIPS)':
 'GND34': CDS_PINID='GND34';
NODE_NAME     U6014 BL22
 '@T6G_MB_LIB.T6G(SCH_1):PAGE400_I2@PURE_QUANTA.PT5161LRS(CHIPS)':
 'GND35': CDS_PINID='GND35';
NODE_NAME     U6014 BL32
 '@T6G_MB_LIB.T6G(SCH_1):PAGE400_I2@PURE_QUANTA.PT5161LRS(CHIPS)':
 'GND36': CDS_PINID='GND36';
NODE_NAME     U6014 BL4
 '@T6G_MB_LIB.T6G(SCH_1):PAGE400_I2@PURE_QUANTA.PT5161LRS(CHIPS)':
 'GND37': CDS_PINID='GND37';
NODE_NAME     U6014 BM2
 '@T6G_MB_LIB.T6G(SCH_1):PAGE400_I2@PURE_QUANTA.PT5161LRS(CHIPS)':
 'GND38': CDS_PINID='GND38';
NODE_NAME     U6014 BM34
 '@T6G_MB_LIB.T6G(SCH_1):PAGE400_I2@PURE_QUANTA.PT5161LRS(CHIPS)':
 'GND39': CDS_PINID='GND39';
NODE_NAME     U6014 BN1
 '@T6G_MB_LIB.T6G(SCH_1):PAGE400_I2@PURE_QUANTA.PT5161LRS(CHIPS)':
 'GND40': CDS_PINID='GND40';
NODE_NAME     U6014 BN35
 '@T6G_MB_LIB.T6G(SCH_1):PAGE400_I2@PURE_QUANTA.PT5161LRS(CHIPS)':
 'GND41': CDS_PINID='GND41';
NODE_NAME     U6014 BV13
 '@T6G_MB_LIB.T6G(SCH_1):PAGE400_I2@PURE_QUANTA.PT5161LRS(CHIPS)':
 'GND42': CDS_PINID='GND42';
NODE_NAME     U6014 BV22
 '@T6G_MB_LIB.T6G(SCH_1):PAGE400_I2@PURE_QUANTA.PT5161LRS(CHIPS)':
 'GND43': CDS_PINID='GND43';
NODE_NAME     U6014 BV32
 '@T6G_MB_LIB.T6G(SCH_1):PAGE400_I2@PURE_QUANTA.PT5161LRS(CHIPS)':
 'GND44': CDS_PINID='GND44';
NODE_NAME     U6014 BV4
 '@T6G_MB_LIB.T6G(SCH_1):PAGE400_I2@PURE_QUANTA.PT5161LRS(CHIPS)':
 'GND45': CDS_PINID='GND45';
NODE_NAME     U6014 BW2
 '@T6G_MB_LIB.T6G(SCH_1):PAGE400_I2@PURE_QUANTA.PT5161LRS(CHIPS)':
 'GND46': CDS_PINID='GND46';
NODE_NAME     U6014 BW34
 '@T6G_MB_LIB.T6G(SCH_1):PAGE400_I2@PURE_QUANTA.PT5161LRS(CHIPS)':
 'GND47': CDS_PINID='GND47';
NODE_NAME     U6014 BY1
 '@T6G_MB_LIB.T6G(SCH_1):PAGE400_I2@PURE_QUANTA.PT5161LRS(CHIPS)':
 'GND48': CDS_PINID='GND48';
NODE_NAME     U6014 BY35
 '@T6G_MB_LIB.T6G(SCH_1):PAGE400_I2@PURE_QUANTA.PT5161LRS(CHIPS)':
 'GND49': CDS_PINID='GND49';
NODE_NAME     U6014 CE13
 '@T6G_MB_LIB.T6G(SCH_1):PAGE400_I2@PURE_QUANTA.PT5161LRS(CHIPS)':
 'GND50': CDS_PINID='GND50';
NODE_NAME     U6014 CE22
 '@T6G_MB_LIB.T6G(SCH_1):PAGE400_I2@PURE_QUANTA.PT5161LRS(CHIPS)':
 'GND51': CDS_PINID='GND51';
NODE_NAME     U6014 CE32
 '@T6G_MB_LIB.T6G(SCH_1):PAGE400_I2@PURE_QUANTA.PT5161LRS(CHIPS)':
 'GND52': CDS_PINID='GND52';
NODE_NAME     U6014 CE4
 '@T6G_MB_LIB.T6G(SCH_1):PAGE400_I2@PURE_QUANTA.PT5161LRS(CHIPS)':
 'GND53': CDS_PINID='GND53';
NODE_NAME     U6014 CF2
 '@T6G_MB_LIB.T6G(SCH_1):PAGE400_I2@PURE_QUANTA.PT5161LRS(CHIPS)':
 'GND54': CDS_PINID='GND54';
NODE_NAME     U6014 CF34
 '@T6G_MB_LIB.T6G(SCH_1):PAGE400_I2@PURE_QUANTA.PT5161LRS(CHIPS)':
 'GND55': CDS_PINID='GND55';
NODE_NAME     U6014 CG1
 '@T6G_MB_LIB.T6G(SCH_1):PAGE400_I2@PURE_QUANTA.PT5161LRS(CHIPS)':
 'GND56': CDS_PINID='GND56';
NODE_NAME     U6014 CG35
 '@T6G_MB_LIB.T6G(SCH_1):PAGE400_I2@PURE_QUANTA.PT5161LRS(CHIPS)':
 'GND57': CDS_PINID='GND57';
NODE_NAME     U6014 CM13
 '@T6G_MB_LIB.T6G(SCH_1):PAGE400_I2@PURE_QUANTA.PT5161LRS(CHIPS)':
 'GND58': CDS_PINID='GND58';
NODE_NAME     U6014 CM22
 '@T6G_MB_LIB.T6G(SCH_1):PAGE400_I2@PURE_QUANTA.PT5161LRS(CHIPS)':
 'GND59': CDS_PINID='GND59';
NODE_NAME     U6014 CM32
 '@T6G_MB_LIB.T6G(SCH_1):PAGE400_I2@PURE_QUANTA.PT5161LRS(CHIPS)':
 'GND60': CDS_PINID='GND60';
NODE_NAME     U6014 CM4
 '@T6G_MB_LIB.T6G(SCH_1):PAGE400_I2@PURE_QUANTA.PT5161LRS(CHIPS)':
 'GND61': CDS_PINID='GND61';
NODE_NAME     U6014 CN2
 '@T6G_MB_LIB.T6G(SCH_1):PAGE400_I2@PURE_QUANTA.PT5161LRS(CHIPS)':
 'GND62': CDS_PINID='GND62';
NODE_NAME     U6014 CN34
 '@T6G_MB_LIB.T6G(SCH_1):PAGE400_I2@PURE_QUANTA.PT5161LRS(CHIPS)':
 'GND63': CDS_PINID='GND63';
NODE_NAME     U6014 CP1
 '@T6G_MB_LIB.T6G(SCH_1):PAGE400_I2@PURE_QUANTA.PT5161LRS(CHIPS)':
 'GND64': CDS_PINID='GND64';
NODE_NAME     U6014 CP35
 '@T6G_MB_LIB.T6G(SCH_1):PAGE400_I2@PURE_QUANTA.PT5161LRS(CHIPS)':
 'GND65': CDS_PINID='GND65';
NODE_NAME     U6014 CW13
 '@T6G_MB_LIB.T6G(SCH_1):PAGE400_I2@PURE_QUANTA.PT5161LRS(CHIPS)':
 'GND66': CDS_PINID='GND66';
NODE_NAME     U6014 CW22
 '@T6G_MB_LIB.T6G(SCH_1):PAGE400_I2@PURE_QUANTA.PT5161LRS(CHIPS)':
 'GND67': CDS_PINID='GND67';
NODE_NAME     U6014 CW32
 '@T6G_MB_LIB.T6G(SCH_1):PAGE400_I2@PURE_QUANTA.PT5161LRS(CHIPS)':
 'GND68': CDS_PINID='GND68';
NODE_NAME     U6014 CW4
 '@T6G_MB_LIB.T6G(SCH_1):PAGE400_I2@PURE_QUANTA.PT5161LRS(CHIPS)':
 'GND69': CDS_PINID='GND69';
NODE_NAME     U6014 CY2
 '@T6G_MB_LIB.T6G(SCH_1):PAGE400_I2@PURE_QUANTA.PT5161LRS(CHIPS)':
 'GND70': CDS_PINID='GND70';
NODE_NAME     U6014 CY34
 '@T6G_MB_LIB.T6G(SCH_1):PAGE400_I2@PURE_QUANTA.PT5161LRS(CHIPS)':
 'GND71': CDS_PINID='GND71';
NODE_NAME     U6014 DA1
 '@T6G_MB_LIB.T6G(SCH_1):PAGE400_I2@PURE_QUANTA.PT5161LRS(CHIPS)':
 'GND72': CDS_PINID='GND72';
NODE_NAME     U6014 DA35
 '@T6G_MB_LIB.T6G(SCH_1):PAGE400_I2@PURE_QUANTA.PT5161LRS(CHIPS)':
 'GND73': CDS_PINID='GND73';
NODE_NAME     U6014 DF13
 '@T6G_MB_LIB.T6G(SCH_1):PAGE400_I2@PURE_QUANTA.PT5161LRS(CHIPS)':
 'GND74': CDS_PINID='GND74';
NODE_NAME     U6014 DF22
 '@T6G_MB_LIB.T6G(SCH_1):PAGE400_I2@PURE_QUANTA.PT5161LRS(CHIPS)':
 'GND75': CDS_PINID='GND75';
NODE_NAME     U6014 DF32
 '@T6G_MB_LIB.T6G(SCH_1):PAGE400_I2@PURE_QUANTA.PT5161LRS(CHIPS)':
 'GND76': CDS_PINID='GND76';
NODE_NAME     U6014 DF4
 '@T6G_MB_LIB.T6G(SCH_1):PAGE400_I2@PURE_QUANTA.PT5161LRS(CHIPS)':
 'GND77': CDS_PINID='GND77';
NODE_NAME     U6014 DG2
 '@T6G_MB_LIB.T6G(SCH_1):PAGE400_I2@PURE_QUANTA.PT5161LRS(CHIPS)':
 'GND78': CDS_PINID='GND78';
NODE_NAME     U6014 DG34
 '@T6G_MB_LIB.T6G(SCH_1):PAGE400_I2@PURE_QUANTA.PT5161LRS(CHIPS)':
 'GND79': CDS_PINID='GND79';
NODE_NAME     U6014 DH1
 '@T6G_MB_LIB.T6G(SCH_1):PAGE400_I2@PURE_QUANTA.PT5161LRS(CHIPS)':
 'GND80': CDS_PINID='GND80';
NODE_NAME     U6014 DH35
 '@T6G_MB_LIB.T6G(SCH_1):PAGE400_I2@PURE_QUANTA.PT5161LRS(CHIPS)':
 'GND81': CDS_PINID='GND81';
NODE_NAME     U6014 DN13
 '@T6G_MB_LIB.T6G(SCH_1):PAGE400_I2@PURE_QUANTA.PT5161LRS(CHIPS)':
 'GND82': CDS_PINID='GND82';
NODE_NAME     U6014 DN22
 '@T6G_MB_LIB.T6G(SCH_1):PAGE400_I2@PURE_QUANTA.PT5161LRS(CHIPS)':
 'GND83': CDS_PINID='GND83';
NODE_NAME     U6014 DN32
 '@T6G_MB_LIB.T6G(SCH_1):PAGE400_I2@PURE_QUANTA.PT5161LRS(CHIPS)':
 'GND84': CDS_PINID='GND84';
NODE_NAME     U6014 DN4
 '@T6G_MB_LIB.T6G(SCH_1):PAGE400_I2@PURE_QUANTA.PT5161LRS(CHIPS)':
 'GND85': CDS_PINID='GND85';
NODE_NAME     U6014 DP2
 '@T6G_MB_LIB.T6G(SCH_1):PAGE400_I2@PURE_QUANTA.PT5161LRS(CHIPS)':
 'GND86': CDS_PINID='GND86';
NODE_NAME     U6014 DP34
 '@T6G_MB_LIB.T6G(SCH_1):PAGE400_I2@PURE_QUANTA.PT5161LRS(CHIPS)':
 'GND87': CDS_PINID='GND87';
NODE_NAME     U6014 DR1
 '@T6G_MB_LIB.T6G(SCH_1):PAGE400_I2@PURE_QUANTA.PT5161LRS(CHIPS)':
 'GND88': CDS_PINID='GND88';
NODE_NAME     U6014 DR35
 '@T6G_MB_LIB.T6G(SCH_1):PAGE400_I2@PURE_QUANTA.PT5161LRS(CHIPS)':
 'GND89': CDS_PINID='GND89';
NODE_NAME     U6014 DY13
 '@T6G_MB_LIB.T6G(SCH_1):PAGE400_I2@PURE_QUANTA.PT5161LRS(CHIPS)':
 'GND90': CDS_PINID='GND90';
NODE_NAME     U6014 DY22
 '@T6G_MB_LIB.T6G(SCH_1):PAGE400_I2@PURE_QUANTA.PT5161LRS(CHIPS)':
 'GND91': CDS_PINID='GND91';
NODE_NAME     U6014 DY32
 '@T6G_MB_LIB.T6G(SCH_1):PAGE400_I2@PURE_QUANTA.PT5161LRS(CHIPS)':
 'GND92': CDS_PINID='GND92';
NODE_NAME     U6014 DY4
 '@T6G_MB_LIB.T6G(SCH_1):PAGE400_I2@PURE_QUANTA.PT5161LRS(CHIPS)':
 'GND93': CDS_PINID='GND93';
NODE_NAME     U6014 E14
 '@T6G_MB_LIB.T6G(SCH_1):PAGE400_I2@PURE_QUANTA.PT5161LRS(CHIPS)':
 'GND94': CDS_PINID='GND94';
NODE_NAME     U6014 E27
 '@T6G_MB_LIB.T6G(SCH_1):PAGE400_I2@PURE_QUANTA.PT5161LRS(CHIPS)':
 'GND95': CDS_PINID='GND95';
NODE_NAME     U6014 E33
 '@T6G_MB_LIB.T6G(SCH_1):PAGE400_I2@PURE_QUANTA.PT5161LRS(CHIPS)':
 'GND96': CDS_PINID='GND96';
NODE_NAME     U6014 EA2
 '@T6G_MB_LIB.T6G(SCH_1):PAGE400_I2@PURE_QUANTA.PT5161LRS(CHIPS)':
 'GND97': CDS_PINID='GND97';
NODE_NAME     U6014 EA34
 '@T6G_MB_LIB.T6G(SCH_1):PAGE400_I2@PURE_QUANTA.PT5161LRS(CHIPS)':
 'GND98': CDS_PINID='GND98';
NODE_NAME     U6014 EB1
 '@T6G_MB_LIB.T6G(SCH_1):PAGE400_I2@PURE_QUANTA.PT5161LRS(CHIPS)':
 'GND99': CDS_PINID='GND99';
NODE_NAME     U6014 EB35
 '@T6G_MB_LIB.T6G(SCH_1):PAGE400_I2@PURE_QUANTA.PT5161LRS(CHIPS)':
 'GND100': CDS_PINID='GND100';
NODE_NAME     U6014 EG13
 '@T6G_MB_LIB.T6G(SCH_1):PAGE400_I2@PURE_QUANTA.PT5161LRS(CHIPS)':
 'GND101': CDS_PINID='GND101';
NODE_NAME     U6014 EG22
 '@T6G_MB_LIB.T6G(SCH_1):PAGE400_I2@PURE_QUANTA.PT5161LRS(CHIPS)':
 'GND102': CDS_PINID='GND102';
NODE_NAME     U6014 EG32
 '@T6G_MB_LIB.T6G(SCH_1):PAGE400_I2@PURE_QUANTA.PT5161LRS(CHIPS)':
 'GND103': CDS_PINID='GND103';
NODE_NAME     U6014 EG4
 '@T6G_MB_LIB.T6G(SCH_1):PAGE400_I2@PURE_QUANTA.PT5161LRS(CHIPS)':
 'GND104': CDS_PINID='GND104';
NODE_NAME     U6014 EH2
 '@T6G_MB_LIB.T6G(SCH_1):PAGE400_I2@PURE_QUANTA.PT5161LRS(CHIPS)':
 'GND105': CDS_PINID='GND105';
NODE_NAME     U6014 EH34
 '@T6G_MB_LIB.T6G(SCH_1):PAGE400_I2@PURE_QUANTA.PT5161LRS(CHIPS)':
 'GND106': CDS_PINID='GND106';
NODE_NAME     U6014 EJ1
 '@T6G_MB_LIB.T6G(SCH_1):PAGE400_I2@PURE_QUANTA.PT5161LRS(CHIPS)':
 'GND107': CDS_PINID='GND107';
NODE_NAME     U6014 EJ35
 '@T6G_MB_LIB.T6G(SCH_1):PAGE400_I2@PURE_QUANTA.PT5161LRS(CHIPS)':
 'GND108': CDS_PINID='GND108';
NODE_NAME     U6014 EP13
 '@T6G_MB_LIB.T6G(SCH_1):PAGE400_I2@PURE_QUANTA.PT5161LRS(CHIPS)':
 'GND109': CDS_PINID='GND109';
NODE_NAME     U6014 EP22
 '@T6G_MB_LIB.T6G(SCH_1):PAGE400_I2@PURE_QUANTA.PT5161LRS(CHIPS)':
 'GND110': CDS_PINID='GND110';
NODE_NAME     U6014 EP32
 '@T6G_MB_LIB.T6G(SCH_1):PAGE400_I2@PURE_QUANTA.PT5161LRS(CHIPS)':
 'GND111': CDS_PINID='GND111';
NODE_NAME     U6014 EP4
 '@T6G_MB_LIB.T6G(SCH_1):PAGE400_I2@PURE_QUANTA.PT5161LRS(CHIPS)':
 'GND112': CDS_PINID='GND112';
NODE_NAME     U6014 ER2
 '@T6G_MB_LIB.T6G(SCH_1):PAGE400_I2@PURE_QUANTA.PT5161LRS(CHIPS)':
 'GND113': CDS_PINID='GND113';
NODE_NAME     U6014 ER34
 '@T6G_MB_LIB.T6G(SCH_1):PAGE400_I2@PURE_QUANTA.PT5161LRS(CHIPS)':
 'GND114': CDS_PINID='GND114';
NODE_NAME     U6014 ET1
 '@T6G_MB_LIB.T6G(SCH_1):PAGE400_I2@PURE_QUANTA.PT5161LRS(CHIPS)':
 'GND115': CDS_PINID='GND115';
NODE_NAME     U6014 ET35
 '@T6G_MB_LIB.T6G(SCH_1):PAGE400_I2@PURE_QUANTA.PT5161LRS(CHIPS)':
 'GND116': CDS_PINID='GND116';
NODE_NAME     U6014 FA15
 '@T6G_MB_LIB.T6G(SCH_1):PAGE400_I2@PURE_QUANTA.PT5161LRS(CHIPS)':
 'GND117': CDS_PINID='GND117';
NODE_NAME     U6014 FA32
 '@T6G_MB_LIB.T6G(SCH_1):PAGE400_I2@PURE_QUANTA.PT5161LRS(CHIPS)':
 'GND118': CDS_PINID='GND118';
NODE_NAME     U6014 FB2
 '@T6G_MB_LIB.T6G(SCH_1):PAGE400_I2@PURE_QUANTA.PT5161LRS(CHIPS)':
 'GND119': CDS_PINID='GND119';
NODE_NAME     U6014 FB34
 '@T6G_MB_LIB.T6G(SCH_1):PAGE400_I2@PURE_QUANTA.PT5161LRS(CHIPS)':
 'GND120': CDS_PINID='GND120';
NODE_NAME     U6014 FC19
 '@T6G_MB_LIB.T6G(SCH_1):PAGE400_I2@PURE_QUANTA.PT5161LRS(CHIPS)':
 'GND121': CDS_PINID='GND121';
NODE_NAME     U6014 FC23
 '@T6G_MB_LIB.T6G(SCH_1):PAGE400_I2@PURE_QUANTA.PT5161LRS(CHIPS)':
 'GND122': CDS_PINID='GND122';
NODE_NAME     U6014 FC25
 '@T6G_MB_LIB.T6G(SCH_1):PAGE400_I2@PURE_QUANTA.PT5161LRS(CHIPS)':
 'GND123': CDS_PINID='GND123';
NODE_NAME     U6014 FC28
 '@T6G_MB_LIB.T6G(SCH_1):PAGE400_I2@PURE_QUANTA.PT5161LRS(CHIPS)':
 'GND124': CDS_PINID='GND124';
NODE_NAME     U6014 FC3
 '@T6G_MB_LIB.T6G(SCH_1):PAGE400_I2@PURE_QUANTA.PT5161LRS(CHIPS)':
 'GND125': CDS_PINID='GND125';
NODE_NAME     U6014 FC6
 '@T6G_MB_LIB.T6G(SCH_1):PAGE400_I2@PURE_QUANTA.PT5161LRS(CHIPS)':
 'GND126': CDS_PINID='GND126';
NODE_NAME     U6014 FC9
 '@T6G_MB_LIB.T6G(SCH_1):PAGE400_I2@PURE_QUANTA.PT5161LRS(CHIPS)':
 'GND127': CDS_PINID='GND127';
NODE_NAME     U6014 FD1
 '@T6G_MB_LIB.T6G(SCH_1):PAGE400_I2@PURE_QUANTA.PT5161LRS(CHIPS)':
 'GND128': CDS_PINID='GND128';
NODE_NAME     U6014 FD35
 '@T6G_MB_LIB.T6G(SCH_1):PAGE400_I2@PURE_QUANTA.PT5161LRS(CHIPS)':
 'GND129': CDS_PINID='GND129';
NODE_NAME     U6014 FF14
 '@T6G_MB_LIB.T6G(SCH_1):PAGE400_I2@PURE_QUANTA.PT5161LRS(CHIPS)':
 'GND130': CDS_PINID='GND130';
NODE_NAME     U6014 FF21
 '@T6G_MB_LIB.T6G(SCH_1):PAGE400_I2@PURE_QUANTA.PT5161LRS(CHIPS)':
 'GND131': CDS_PINID='GND131';
NODE_NAME     U6014 FJ12
 '@T6G_MB_LIB.T6G(SCH_1):PAGE400_I2@PURE_QUANTA.PT5161LRS(CHIPS)':
 'GND132': CDS_PINID='GND132';
NODE_NAME     U6014 FJ19
 '@T6G_MB_LIB.T6G(SCH_1):PAGE400_I2@PURE_QUANTA.PT5161LRS(CHIPS)':
 'GND133': CDS_PINID='GND133';
NODE_NAME     U6014 H12
 '@T6G_MB_LIB.T6G(SCH_1):PAGE400_I2@PURE_QUANTA.PT5161LRS(CHIPS)':
 'GND134': CDS_PINID='GND134';
NODE_NAME     U6014 H16
 '@T6G_MB_LIB.T6G(SCH_1):PAGE400_I2@PURE_QUANTA.PT5161LRS(CHIPS)':
 'GND135': CDS_PINID='GND135';
NODE_NAME     U6014 H19
 '@T6G_MB_LIB.T6G(SCH_1):PAGE400_I2@PURE_QUANTA.PT5161LRS(CHIPS)':
 'GND136': CDS_PINID='GND136';
NODE_NAME     U6014 H31
 '@T6G_MB_LIB.T6G(SCH_1):PAGE400_I2@PURE_QUANTA.PT5161LRS(CHIPS)':
 'GND137': CDS_PINID='GND137';
NODE_NAME     U6014 J22
 '@T6G_MB_LIB.T6G(SCH_1):PAGE400_I2@PURE_QUANTA.PT5161LRS(CHIPS)':
 'GND138': CDS_PINID='GND138';
NODE_NAME     U6014 J4
 '@T6G_MB_LIB.T6G(SCH_1):PAGE400_I2@PURE_QUANTA.PT5161LRS(CHIPS)':
 'GND139': CDS_PINID='GND139';
NODE_NAME     U6014 K2
 '@T6G_MB_LIB.T6G(SCH_1):PAGE400_I2@PURE_QUANTA.PT5161LRS(CHIPS)':
 'GND140': CDS_PINID='GND140';
NODE_NAME     U6014 K34
 '@T6G_MB_LIB.T6G(SCH_1):PAGE400_I2@PURE_QUANTA.PT5161LRS(CHIPS)':
 'GND141': CDS_PINID='GND141';
NODE_NAME     U6014 L1
 '@T6G_MB_LIB.T6G(SCH_1):PAGE400_I2@PURE_QUANTA.PT5161LRS(CHIPS)':
 'GND142': CDS_PINID='GND142';
NODE_NAME     U6014 L35
 '@T6G_MB_LIB.T6G(SCH_1):PAGE400_I2@PURE_QUANTA.PT5161LRS(CHIPS)':
 'GND143': CDS_PINID='GND143';
NODE_NAME     U6014 T13
 '@T6G_MB_LIB.T6G(SCH_1):PAGE400_I2@PURE_QUANTA.PT5161LRS(CHIPS)':
 'GND144': CDS_PINID='GND144';
NODE_NAME     U6014 T22
 '@T6G_MB_LIB.T6G(SCH_1):PAGE400_I2@PURE_QUANTA.PT5161LRS(CHIPS)':
 'GND145': CDS_PINID='GND145';
NODE_NAME     U6014 T32
 '@T6G_MB_LIB.T6G(SCH_1):PAGE400_I2@PURE_QUANTA.PT5161LRS(CHIPS)':
 'GND146': CDS_PINID='GND146';
NODE_NAME     U6014 T4
 '@T6G_MB_LIB.T6G(SCH_1):PAGE400_I2@PURE_QUANTA.PT5161LRS(CHIPS)':
 'GND147': CDS_PINID='GND147';
NODE_NAME     U6014 U2
 '@T6G_MB_LIB.T6G(SCH_1):PAGE400_I2@PURE_QUANTA.PT5161LRS(CHIPS)':
 'GND148': CDS_PINID='GND148';
NODE_NAME     U6014 U34
 '@T6G_MB_LIB.T6G(SCH_1):PAGE400_I2@PURE_QUANTA.PT5161LRS(CHIPS)':
 'GND149': CDS_PINID='GND149';
NODE_NAME     U6014 V1
 '@T6G_MB_LIB.T6G(SCH_1):PAGE400_I2@PURE_QUANTA.PT5161LRS(CHIPS)':
 'GND150': CDS_PINID='GND150';
NODE_NAME     U6014 V35
 '@T6G_MB_LIB.T6G(SCH_1):PAGE400_I2@PURE_QUANTA.PT5161LRS(CHIPS)':
 'GND151': CDS_PINID='GND151';
NODE_NAME     U6014 E30
 '@T6G_MB_LIB.T6G(SCH_1):PAGE401_I1@PURE_QUANTA.PT5161LRS(CHIPS)':
 'T_SENSE': CDS_PINID='T_SENSE';
NODE_NAME     R4490 2
 '@T6G_MB_LIB.T6G(SCH_1):PAGE160_I2@PURE_QUANTA.Q_RES(CHIPS)':
 'B': CDS_PINID='B';
NODE_NAME     C78 2
 '@T6G_MB_LIB.T6G(SCH_1):PAGE160_I18@PURE_QUANTA.Q_CAP(CHIPS)':
 'B': CDS_PINID='B';
NODE_NAME     C2334 2
 '@T6G_MB_LIB.T6G(SCH_1):PAGE160_I20@PURE_QUANTA.Q_CAP(CHIPS)':
 'B': CDS_PINID='B';
NODE_NAME     R4492 2
 '@T6G_MB_LIB.T6G(SCH_1):PAGE160_I29@PURE_QUANTA.Q_RES(CHIPS)':
 'B': CDS_PINID='B';
NODE_NAME     C2329 2
 '@T6G_MB_LIB.T6G(SCH_1):PAGE160_I40@PURE_QUANTA.Q_CAP(CHIPS)':
 'B': CDS_PINID='B';
NODE_NAME     C79 2
 '@T6G_MB_LIB.T6G(SCH_1):PAGE160_I41@PURE_QUANTA.Q_CAP(CHIPS)':
 'B': CDS_PINID='B';
NODE_NAME     C80 2
 '@T6G_MB_LIB.T6G(SCH_1):PAGE160_I44@PURE_QUANTA.Q_CAP(CHIPS)':
 'B': CDS_PINID='B';
NODE_NAME     C81 2
 '@T6G_MB_LIB.T6G(SCH_1):PAGE160_I45@PURE_QUANTA.Q_CAP(CHIPS)':
 'B': CDS_PINID='B';
NODE_NAME     C2339 2
 '@T6G_MB_LIB.T6G(SCH_1):PAGE160_I47@PURE_QUANTA.Q_CAP(CHIPS)':
 'B': CDS_PINID='B';
NODE_NAME     R4518 2
 '@T6G_MB_LIB.T6G(SCH_1):PAGE160_I52@PURE_QUANTA.Q_RES(CHIPS)':
 'B': CDS_PINID='B';
NODE_NAME     R4519 2
 '@T6G_MB_LIB.T6G(SCH_1):PAGE160_I53@PURE_QUANTA.Q_RES(CHIPS)':
 'B': CDS_PINID='B';
NODE_NAME     R4520 2
 '@T6G_MB_LIB.T6G(SCH_1):PAGE160_I55@PURE_QUANTA.Q_RES(CHIPS)':
 'B': CDS_PINID='B';
NODE_NAME     U314 33
 '@T6G_MB_LIB.T6G(SCH_1):PAGE160_I63@PURE_QUANTA.9ZXL0451EKILFT(CHIPS)':
 'EPAD_GND': CDS_PINID='EPAD_GND';
NODE_NAME     R585 2
 '@T6G_MB_LIB.T6G(SCH_1):PAGE379_I15@PURE_QUANTA.Q_RES(CHIPS)':
 'B': CDS_PINID='B';
NODE_NAME     C68 2
 '@T6G_MB_LIB.T6G(SCH_1):PAGE379_I24@PURE_QUANTA.Q_CAP(CHIPS)':
 'B': CDS_PINID='B';
NODE_NAME     C84 2
 '@T6G_MB_LIB.T6G(SCH_1):PAGE379_I26@PURE_QUANTA.Q_CAP(CHIPS)':
 'B': CDS_PINID='B';
NODE_NAME     C58 2
 '@T6G_MB_LIB.T6G(SCH_1):PAGE379_I34@PURE_QUANTA.Q_CAP(CHIPS)':
 'B': CDS_PINID='B';
NODE_NAME     C90 2
 '@T6G_MB_LIB.T6G(SCH_1):PAGE379_I35@PURE_QUANTA.Q_CAP(CHIPS)':
 'B': CDS_PINID='B';
NODE_NAME     C98 2
 '@T6G_MB_LIB.T6G(SCH_1):PAGE379_I36@PURE_QUANTA.Q_CAP(CHIPS)':
 'B': CDS_PINID='B';
NODE_NAME     R592 2
 '@T6G_MB_LIB.T6G(SCH_1):PAGE379_I49@PURE_QUANTA.Q_RES(CHIPS)':
 'B': CDS_PINID='B';
NODE_NAME     R593 2
 '@T6G_MB_LIB.T6G(SCH_1):PAGE379_I50@PURE_QUANTA.Q_RES(CHIPS)':
 'B': CDS_PINID='B';
NODE_NAME     R594 2
 '@T6G_MB_LIB.T6G(SCH_1):PAGE379_I51@PURE_QUANTA.Q_RES(CHIPS)':
 'B': CDS_PINID='B';
NODE_NAME     C99 2
 '@T6G_MB_LIB.T6G(SCH_1):PAGE379_I58@PURE_QUANTA.Q_CAP(CHIPS)':
 'B': CDS_PINID='B';
NODE_NAME     C75 2
 '@T6G_MB_LIB.T6G(SCH_1):PAGE379_I60@PURE_QUANTA.Q_CAP(CHIPS)':
 'B': CDS_PINID='B';
NODE_NAME     U10 33
 '@T6G_MB_LIB.T6G(SCH_1):PAGE379_I63@PURE_QUANTA.9ZXL0451EKILFT(CHIPS)':
 'EPAD_GND': CDS_PINID='EPAD_GND';
NODE_NAME     R579 2
 '@T6G_MB_LIB.T6G(SCH_1):PAGE379_I64@PURE_QUANTA.Q_RES(CHIPS)':
 'B': CDS_PINID='B';
NODE_NAME     R1070 2
 '@T6G_MB_LIB.T6G(SCH_1):PAGE419_I7@PURE_QUANTA.Q_RES(CHIPS)':
 'B': CDS_PINID='B';
NODE_NAME     R1074 2
 '@T6G_MB_LIB.T6G(SCH_1):PAGE419_I9@PURE_QUANTA.Q_RES(CHIPS)':
 'B': CDS_PINID='B';
NODE_NAME     R1112 2
 '@T6G_MB_LIB.T6G(SCH_1):PAGE430_I7@PURE_QUANTA.Q_RES(CHIPS)':
 'B': CDS_PINID='B';
NODE_NAME     R1113 2
 '@T6G_MB_LIB.T6G(SCH_1):PAGE430_I8@PURE_QUANTA.Q_RES(CHIPS)':
 'B': CDS_PINID='B';
NODE_NAME     R1115 2
 '@T6G_MB_LIB.T6G(SCH_1):PAGE430_I9@PURE_QUANTA.Q_RES(CHIPS)':
 'B': CDS_PINID='B';
NODE_NAME     J106 A6
 '@T6G_MB_LIB.T6G(SCH_1):PAGE327_I19@PURE_QUANTA.CONN112_10137002101LF(CHIPS)':
 'A6': CDS_PINID='A6';
NODE_NAME     J106 A8
 '@T6G_MB_LIB.T6G(SCH_1):PAGE327_I19@PURE_QUANTA.CONN112_10137002101LF(CHIPS)':
 'A8': CDS_PINID='A8';
NODE_NAME     J106 B5
 '@T6G_MB_LIB.T6G(SCH_1):PAGE327_I19@PURE_QUANTA.CONN112_10137002101LF(CHIPS)':
 'B5': CDS_PINID='B5';
NODE_NAME     J106 B7
 '@T6G_MB_LIB.T6G(SCH_1):PAGE327_I19@PURE_QUANTA.CONN112_10137002101LF(CHIPS)':
 'B7': CDS_PINID='B7';
NODE_NAME     J106 D6
 '@T6G_MB_LIB.T6G(SCH_1):PAGE327_I19@PURE_QUANTA.CONN112_10137002101LF(CHIPS)':
 'D6': CDS_PINID='D6';
NODE_NAME     J106 D8
 '@T6G_MB_LIB.T6G(SCH_1):PAGE327_I19@PURE_QUANTA.CONN112_10137002101LF(CHIPS)':
 'D8': CDS_PINID='D8';
NODE_NAME     J106 E5
 '@T6G_MB_LIB.T6G(SCH_1):PAGE327_I19@PURE_QUANTA.CONN112_10137002101LF(CHIPS)':
 'E5': CDS_PINID='E5';
NODE_NAME     J106 E7
 '@T6G_MB_LIB.T6G(SCH_1):PAGE327_I19@PURE_QUANTA.CONN112_10137002101LF(CHIPS)':
 'E7': CDS_PINID='E7';
NODE_NAME     J106 G6
 '@T6G_MB_LIB.T6G(SCH_1):PAGE327_I19@PURE_QUANTA.CONN112_10137002101LF(CHIPS)':
 'G6': CDS_PINID='G6';
NODE_NAME     J106 G8
 '@T6G_MB_LIB.T6G(SCH_1):PAGE327_I19@PURE_QUANTA.CONN112_10137002101LF(CHIPS)':
 'G8': CDS_PINID='G8';
NODE_NAME     J106 H5
 '@T6G_MB_LIB.T6G(SCH_1):PAGE327_I19@PURE_QUANTA.CONN112_10137002101LF(CHIPS)':
 'H5': CDS_PINID='H5';
NODE_NAME     J106 H7
 '@T6G_MB_LIB.T6G(SCH_1):PAGE327_I19@PURE_QUANTA.CONN112_10137002101LF(CHIPS)':
 'H7': CDS_PINID='H7';
NODE_NAME     J106 J6
 '@T6G_MB_LIB.T6G(SCH_1):PAGE327_I19@PURE_QUANTA.CONN112_10137002101LF(CHIPS)':
 'J6': CDS_PINID='J6';
NODE_NAME     J106 J8
 '@T6G_MB_LIB.T6G(SCH_1):PAGE327_I19@PURE_QUANTA.CONN112_10137002101LF(CHIPS)':
 'J8': CDS_PINID='J8';
NODE_NAME     J106 K5
 '@T6G_MB_LIB.T6G(SCH_1):PAGE327_I19@PURE_QUANTA.CONN112_10137002101LF(CHIPS)':
 'K5': CDS_PINID='K5';
NODE_NAME     J106 K7
 '@T6G_MB_LIB.T6G(SCH_1):PAGE327_I19@PURE_QUANTA.CONN112_10137002101LF(CHIPS)':
 'K7': CDS_PINID='K7';
NODE_NAME     J106 M6
 '@T6G_MB_LIB.T6G(SCH_1):PAGE327_I19@PURE_QUANTA.CONN112_10137002101LF(CHIPS)':
 'M6': CDS_PINID='M6';
NODE_NAME     J106 M8
 '@T6G_MB_LIB.T6G(SCH_1):PAGE327_I19@PURE_QUANTA.CONN112_10137002101LF(CHIPS)':
 'M8': CDS_PINID='M8';
NODE_NAME     J106 N5
 '@T6G_MB_LIB.T6G(SCH_1):PAGE327_I19@PURE_QUANTA.CONN112_10137002101LF(CHIPS)':
 'N5': CDS_PINID='N5';
NODE_NAME     J106 N7
 '@T6G_MB_LIB.T6G(SCH_1):PAGE327_I19@PURE_QUANTA.CONN112_10137002101LF(CHIPS)':
 'N7': CDS_PINID='N7';
NODE_NAME     J106 A2
 '@T6G_MB_LIB.T6G(SCH_1):PAGE327_I74@PURE_QUANTA.CONN112_10137002101LF(CHIPS)':
 'A2': CDS_PINID='A2';
NODE_NAME     J106 A4
 '@T6G_MB_LIB.T6G(SCH_1):PAGE327_I74@PURE_QUANTA.CONN112_10137002101LF(CHIPS)':
 'A4': CDS_PINID='A4';
NODE_NAME     J106 B1
 '@T6G_MB_LIB.T6G(SCH_1):PAGE327_I74@PURE_QUANTA.CONN112_10137002101LF(CHIPS)':
 'B1': CDS_PINID='B1';
NODE_NAME     J106 B3
 '@T6G_MB_LIB.T6G(SCH_1):PAGE327_I74@PURE_QUANTA.CONN112_10137002101LF(CHIPS)':
 'B3': CDS_PINID='B3';
NODE_NAME     J106 D2
 '@T6G_MB_LIB.T6G(SCH_1):PAGE327_I74@PURE_QUANTA.CONN112_10137002101LF(CHIPS)':
 'D2': CDS_PINID='D2';
NODE_NAME     J106 D4
 '@T6G_MB_LIB.T6G(SCH_1):PAGE327_I74@PURE_QUANTA.CONN112_10137002101LF(CHIPS)':
 'D4': CDS_PINID='D4';
NODE_NAME     J106 E1
 '@T6G_MB_LIB.T6G(SCH_1):PAGE327_I74@PURE_QUANTA.CONN112_10137002101LF(CHIPS)':
 'E1': CDS_PINID='E1';
NODE_NAME     J106 E3
 '@T6G_MB_LIB.T6G(SCH_1):PAGE327_I74@PURE_QUANTA.CONN112_10137002101LF(CHIPS)':
 'E3': CDS_PINID='E3';
NODE_NAME     J106 G2
 '@T6G_MB_LIB.T6G(SCH_1):PAGE327_I74@PURE_QUANTA.CONN112_10137002101LF(CHIPS)':
 'G2': CDS_PINID='G2';
NODE_NAME     J106 G4
 '@T6G_MB_LIB.T6G(SCH_1):PAGE327_I74@PURE_QUANTA.CONN112_10137002101LF(CHIPS)':
 'G4': CDS_PINID='G4';
NODE_NAME     J106 H1
 '@T6G_MB_LIB.T6G(SCH_1):PAGE327_I74@PURE_QUANTA.CONN112_10137002101LF(CHIPS)':
 'H1': CDS_PINID='H1';
NODE_NAME     J106 H3
 '@T6G_MB_LIB.T6G(SCH_1):PAGE327_I74@PURE_QUANTA.CONN112_10137002101LF(CHIPS)':
 'H3': CDS_PINID='H3';
NODE_NAME     J106 J2
 '@T6G_MB_LIB.T6G(SCH_1):PAGE327_I74@PURE_QUANTA.CONN112_10137002101LF(CHIPS)':
 'J2': CDS_PINID='J2';
NODE_NAME     J106 J4
 '@T6G_MB_LIB.T6G(SCH_1):PAGE327_I74@PURE_QUANTA.CONN112_10137002101LF(CHIPS)':
 'J4': CDS_PINID='J4';
NODE_NAME     J106 K1
 '@T6G_MB_LIB.T6G(SCH_1):PAGE327_I74@PURE_QUANTA.CONN112_10137002101LF(CHIPS)':
 'K1': CDS_PINID='K1';
NODE_NAME     J106 K3
 '@T6G_MB_LIB.T6G(SCH_1):PAGE327_I74@PURE_QUANTA.CONN112_10137002101LF(CHIPS)':
 'K3': CDS_PINID='K3';
NODE_NAME     J106 M2
 '@T6G_MB_LIB.T6G(SCH_1):PAGE327_I74@PURE_QUANTA.CONN112_10137002101LF(CHIPS)':
 'M2': CDS_PINID='M2';
NODE_NAME     J106 M4
 '@T6G_MB_LIB.T6G(SCH_1):PAGE327_I74@PURE_QUANTA.CONN112_10137002101LF(CHIPS)':
 'M4': CDS_PINID='M4';
NODE_NAME     J106 N1
 '@T6G_MB_LIB.T6G(SCH_1):PAGE327_I74@PURE_QUANTA.CONN112_10137002101LF(CHIPS)':
 'N1': CDS_PINID='N1';
NODE_NAME     J106 N3
 '@T6G_MB_LIB.T6G(SCH_1):PAGE327_I74@PURE_QUANTA.CONN112_10137002101LF(CHIPS)':
 'N3': CDS_PINID='N3';
NODE_NAME     J105 A2
 '@T6G_MB_LIB.T6G(SCH_1):PAGE326_I75@PURE_QUANTA.CONN112_10137002101LF(CHIPS)':
 'A2': CDS_PINID='A2';
NODE_NAME     J105 A4
 '@T6G_MB_LIB.T6G(SCH_1):PAGE326_I75@PURE_QUANTA.CONN112_10137002101LF(CHIPS)':
 'A4': CDS_PINID='A4';
NODE_NAME     J105 B1
 '@T6G_MB_LIB.T6G(SCH_1):PAGE326_I75@PURE_QUANTA.CONN112_10137002101LF(CHIPS)':
 'B1': CDS_PINID='B1';
NODE_NAME     J105 B3
 '@T6G_MB_LIB.T6G(SCH_1):PAGE326_I75@PURE_QUANTA.CONN112_10137002101LF(CHIPS)':
 'B3': CDS_PINID='B3';
NODE_NAME     J105 D2
 '@T6G_MB_LIB.T6G(SCH_1):PAGE326_I75@PURE_QUANTA.CONN112_10137002101LF(CHIPS)':
 'D2': CDS_PINID='D2';
NODE_NAME     J105 D4
 '@T6G_MB_LIB.T6G(SCH_1):PAGE326_I75@PURE_QUANTA.CONN112_10137002101LF(CHIPS)':
 'D4': CDS_PINID='D4';
NODE_NAME     J105 E1
 '@T6G_MB_LIB.T6G(SCH_1):PAGE326_I75@PURE_QUANTA.CONN112_10137002101LF(CHIPS)':
 'E1': CDS_PINID='E1';
NODE_NAME     J105 E3
 '@T6G_MB_LIB.T6G(SCH_1):PAGE326_I75@PURE_QUANTA.CONN112_10137002101LF(CHIPS)':
 'E3': CDS_PINID='E3';
NODE_NAME     J105 G2
 '@T6G_MB_LIB.T6G(SCH_1):PAGE326_I75@PURE_QUANTA.CONN112_10137002101LF(CHIPS)':
 'G2': CDS_PINID='G2';
NODE_NAME     J105 G4
 '@T6G_MB_LIB.T6G(SCH_1):PAGE326_I75@PURE_QUANTA.CONN112_10137002101LF(CHIPS)':
 'G4': CDS_PINID='G4';
NODE_NAME     J105 H1
 '@T6G_MB_LIB.T6G(SCH_1):PAGE326_I75@PURE_QUANTA.CONN112_10137002101LF(CHIPS)':
 'H1': CDS_PINID='H1';
NODE_NAME     J105 H3
 '@T6G_MB_LIB.T6G(SCH_1):PAGE326_I75@PURE_QUANTA.CONN112_10137002101LF(CHIPS)':
 'H3': CDS_PINID='H3';
NODE_NAME     J105 J2
 '@T6G_MB_LIB.T6G(SCH_1):PAGE326_I75@PURE_QUANTA.CONN112_10137002101LF(CHIPS)':
 'J2': CDS_PINID='J2';
NODE_NAME     J105 J4
 '@T6G_MB_LIB.T6G(SCH_1):PAGE326_I75@PURE_QUANTA.CONN112_10137002101LF(CHIPS)':
 'J4': CDS_PINID='J4';
NODE_NAME     J105 K1
 '@T6G_MB_LIB.T6G(SCH_1):PAGE326_I75@PURE_QUANTA.CONN112_10137002101LF(CHIPS)':
 'K1': CDS_PINID='K1';
NODE_NAME     J105 K3
 '@T6G_MB_LIB.T6G(SCH_1):PAGE326_I75@PURE_QUANTA.CONN112_10137002101LF(CHIPS)':
 'K3': CDS_PINID='K3';
NODE_NAME     J105 M2
 '@T6G_MB_LIB.T6G(SCH_1):PAGE326_I75@PURE_QUANTA.CONN112_10137002101LF(CHIPS)':
 'M2': CDS_PINID='M2';
NODE_NAME     J105 M4
 '@T6G_MB_LIB.T6G(SCH_1):PAGE326_I75@PURE_QUANTA.CONN112_10137002101LF(CHIPS)':
 'M4': CDS_PINID='M4';
NODE_NAME     J105 N1
 '@T6G_MB_LIB.T6G(SCH_1):PAGE326_I75@PURE_QUANTA.CONN112_10137002101LF(CHIPS)':
 'N1': CDS_PINID='N1';
NODE_NAME     J105 N3
 '@T6G_MB_LIB.T6G(SCH_1):PAGE326_I75@PURE_QUANTA.CONN112_10137002101LF(CHIPS)':
 'N3': CDS_PINID='N3';
NODE_NAME     J105 A6
 '@T6G_MB_LIB.T6G(SCH_1):PAGE326_I76@PURE_QUANTA.CONN112_10137002101LF(CHIPS)':
 'A6': CDS_PINID='A6';
NODE_NAME     J105 A8
 '@T6G_MB_LIB.T6G(SCH_1):PAGE326_I76@PURE_QUANTA.CONN112_10137002101LF(CHIPS)':
 'A8': CDS_PINID='A8';
NODE_NAME     J105 B5
 '@T6G_MB_LIB.T6G(SCH_1):PAGE326_I76@PURE_QUANTA.CONN112_10137002101LF(CHIPS)':
 'B5': CDS_PINID='B5';
NODE_NAME     J105 B7
 '@T6G_MB_LIB.T6G(SCH_1):PAGE326_I76@PURE_QUANTA.CONN112_10137002101LF(CHIPS)':
 'B7': CDS_PINID='B7';
NODE_NAME     J105 D6
 '@T6G_MB_LIB.T6G(SCH_1):PAGE326_I76@PURE_QUANTA.CONN112_10137002101LF(CHIPS)':
 'D6': CDS_PINID='D6';
NODE_NAME     J105 D8
 '@T6G_MB_LIB.T6G(SCH_1):PAGE326_I76@PURE_QUANTA.CONN112_10137002101LF(CHIPS)':
 'D8': CDS_PINID='D8';
NODE_NAME     J105 E5
 '@T6G_MB_LIB.T6G(SCH_1):PAGE326_I76@PURE_QUANTA.CONN112_10137002101LF(CHIPS)':
 'E5': CDS_PINID='E5';
NODE_NAME     J105 E7
 '@T6G_MB_LIB.T6G(SCH_1):PAGE326_I76@PURE_QUANTA.CONN112_10137002101LF(CHIPS)':
 'E7': CDS_PINID='E7';
NODE_NAME     J105 G6
 '@T6G_MB_LIB.T6G(SCH_1):PAGE326_I76@PURE_QUANTA.CONN112_10137002101LF(CHIPS)':
 'G6': CDS_PINID='G6';
NODE_NAME     J105 G8
 '@T6G_MB_LIB.T6G(SCH_1):PAGE326_I76@PURE_QUANTA.CONN112_10137002101LF(CHIPS)':
 'G8': CDS_PINID='G8';
NODE_NAME     J105 H5
 '@T6G_MB_LIB.T6G(SCH_1):PAGE326_I76@PURE_QUANTA.CONN112_10137002101LF(CHIPS)':
 'H5': CDS_PINID='H5';
NODE_NAME     J105 H7
 '@T6G_MB_LIB.T6G(SCH_1):PAGE326_I76@PURE_QUANTA.CONN112_10137002101LF(CHIPS)':
 'H7': CDS_PINID='H7';
NODE_NAME     J105 J6
 '@T6G_MB_LIB.T6G(SCH_1):PAGE326_I76@PURE_QUANTA.CONN112_10137002101LF(CHIPS)':
 'J6': CDS_PINID='J6';
NODE_NAME     J105 J8
 '@T6G_MB_LIB.T6G(SCH_1):PAGE326_I76@PURE_QUANTA.CONN112_10137002101LF(CHIPS)':
 'J8': CDS_PINID='J8';
NODE_NAME     J105 K5
 '@T6G_MB_LIB.T6G(SCH_1):PAGE326_I76@PURE_QUANTA.CONN112_10137002101LF(CHIPS)':
 'K5': CDS_PINID='K5';
NODE_NAME     J105 K7
 '@T6G_MB_LIB.T6G(SCH_1):PAGE326_I76@PURE_QUANTA.CONN112_10137002101LF(CHIPS)':
 'K7': CDS_PINID='K7';
NODE_NAME     J105 M6
 '@T6G_MB_LIB.T6G(SCH_1):PAGE326_I76@PURE_QUANTA.CONN112_10137002101LF(CHIPS)':
 'M6': CDS_PINID='M6';
NODE_NAME     J105 M8
 '@T6G_MB_LIB.T6G(SCH_1):PAGE326_I76@PURE_QUANTA.CONN112_10137002101LF(CHIPS)':
 'M8': CDS_PINID='M8';
NODE_NAME     J105 N5
 '@T6G_MB_LIB.T6G(SCH_1):PAGE326_I76@PURE_QUANTA.CONN112_10137002101LF(CHIPS)':
 'N5': CDS_PINID='N5';
NODE_NAME     J105 N7
 '@T6G_MB_LIB.T6G(SCH_1):PAGE326_I76@PURE_QUANTA.CONN112_10137002101LF(CHIPS)':
 'N7': CDS_PINID='N7';
NODE_NAME     J107 A2
 '@T6G_MB_LIB.T6G(SCH_1):PAGE317_I49@PURE_QUANTA.CONN112_10137002101LF(CHIPS)':
 'A2': CDS_PINID='A2';
NODE_NAME     J107 A4
 '@T6G_MB_LIB.T6G(SCH_1):PAGE317_I49@PURE_QUANTA.CONN112_10137002101LF(CHIPS)':
 'A4': CDS_PINID='A4';
NODE_NAME     J107 B1
 '@T6G_MB_LIB.T6G(SCH_1):PAGE317_I49@PURE_QUANTA.CONN112_10137002101LF(CHIPS)':
 'B1': CDS_PINID='B1';
NODE_NAME     J107 B3
 '@T6G_MB_LIB.T6G(SCH_1):PAGE317_I49@PURE_QUANTA.CONN112_10137002101LF(CHIPS)':
 'B3': CDS_PINID='B3';
NODE_NAME     J107 D2
 '@T6G_MB_LIB.T6G(SCH_1):PAGE317_I49@PURE_QUANTA.CONN112_10137002101LF(CHIPS)':
 'D2': CDS_PINID='D2';
NODE_NAME     J107 D4
 '@T6G_MB_LIB.T6G(SCH_1):PAGE317_I49@PURE_QUANTA.CONN112_10137002101LF(CHIPS)':
 'D4': CDS_PINID='D4';
NODE_NAME     J107 E1
 '@T6G_MB_LIB.T6G(SCH_1):PAGE317_I49@PURE_QUANTA.CONN112_10137002101LF(CHIPS)':
 'E1': CDS_PINID='E1';
NODE_NAME     J107 E3
 '@T6G_MB_LIB.T6G(SCH_1):PAGE317_I49@PURE_QUANTA.CONN112_10137002101LF(CHIPS)':
 'E3': CDS_PINID='E3';
NODE_NAME     J107 G2
 '@T6G_MB_LIB.T6G(SCH_1):PAGE317_I49@PURE_QUANTA.CONN112_10137002101LF(CHIPS)':
 'G2': CDS_PINID='G2';
NODE_NAME     J107 G4
 '@T6G_MB_LIB.T6G(SCH_1):PAGE317_I49@PURE_QUANTA.CONN112_10137002101LF(CHIPS)':
 'G4': CDS_PINID='G4';
NODE_NAME     J107 H1
 '@T6G_MB_LIB.T6G(SCH_1):PAGE317_I49@PURE_QUANTA.CONN112_10137002101LF(CHIPS)':
 'H1': CDS_PINID='H1';
NODE_NAME     J107 H3
 '@T6G_MB_LIB.T6G(SCH_1):PAGE317_I49@PURE_QUANTA.CONN112_10137002101LF(CHIPS)':
 'H3': CDS_PINID='H3';
NODE_NAME     J107 J2
 '@T6G_MB_LIB.T6G(SCH_1):PAGE317_I49@PURE_QUANTA.CONN112_10137002101LF(CHIPS)':
 'J2': CDS_PINID='J2';
NODE_NAME     J107 J4
 '@T6G_MB_LIB.T6G(SCH_1):PAGE317_I49@PURE_QUANTA.CONN112_10137002101LF(CHIPS)':
 'J4': CDS_PINID='J4';
NODE_NAME     J107 K1
 '@T6G_MB_LIB.T6G(SCH_1):PAGE317_I49@PURE_QUANTA.CONN112_10137002101LF(CHIPS)':
 'K1': CDS_PINID='K1';
NODE_NAME     J107 K3
 '@T6G_MB_LIB.T6G(SCH_1):PAGE317_I49@PURE_QUANTA.CONN112_10137002101LF(CHIPS)':
 'K3': CDS_PINID='K3';
NODE_NAME     J107 M2
 '@T6G_MB_LIB.T6G(SCH_1):PAGE317_I49@PURE_QUANTA.CONN112_10137002101LF(CHIPS)':
 'M2': CDS_PINID='M2';
NODE_NAME     J107 M4
 '@T6G_MB_LIB.T6G(SCH_1):PAGE317_I49@PURE_QUANTA.CONN112_10137002101LF(CHIPS)':
 'M4': CDS_PINID='M4';
NODE_NAME     J107 N1
 '@T6G_MB_LIB.T6G(SCH_1):PAGE317_I49@PURE_QUANTA.CONN112_10137002101LF(CHIPS)':
 'N1': CDS_PINID='N1';
NODE_NAME     J107 N3
 '@T6G_MB_LIB.T6G(SCH_1):PAGE317_I49@PURE_QUANTA.CONN112_10137002101LF(CHIPS)':
 'N3': CDS_PINID='N3';
NODE_NAME     J107 A6
 '@T6G_MB_LIB.T6G(SCH_1):PAGE317_I70@PURE_QUANTA.CONN112_10137002101LF(CHIPS)':
 'A6': CDS_PINID='A6';
NODE_NAME     J107 A8
 '@T6G_MB_LIB.T6G(SCH_1):PAGE317_I70@PURE_QUANTA.CONN112_10137002101LF(CHIPS)':
 'A8': CDS_PINID='A8';
NODE_NAME     J107 B5
 '@T6G_MB_LIB.T6G(SCH_1):PAGE317_I70@PURE_QUANTA.CONN112_10137002101LF(CHIPS)':
 'B5': CDS_PINID='B5';
NODE_NAME     J107 B7
 '@T6G_MB_LIB.T6G(SCH_1):PAGE317_I70@PURE_QUANTA.CONN112_10137002101LF(CHIPS)':
 'B7': CDS_PINID='B7';
NODE_NAME     J107 D6
 '@T6G_MB_LIB.T6G(SCH_1):PAGE317_I70@PURE_QUANTA.CONN112_10137002101LF(CHIPS)':
 'D6': CDS_PINID='D6';
NODE_NAME     J107 D8
 '@T6G_MB_LIB.T6G(SCH_1):PAGE317_I70@PURE_QUANTA.CONN112_10137002101LF(CHIPS)':
 'D8': CDS_PINID='D8';
NODE_NAME     J107 E5
 '@T6G_MB_LIB.T6G(SCH_1):PAGE317_I70@PURE_QUANTA.CONN112_10137002101LF(CHIPS)':
 'E5': CDS_PINID='E5';
NODE_NAME     J107 E7
 '@T6G_MB_LIB.T6G(SCH_1):PAGE317_I70@PURE_QUANTA.CONN112_10137002101LF(CHIPS)':
 'E7': CDS_PINID='E7';
NODE_NAME     J107 G6
 '@T6G_MB_LIB.T6G(SCH_1):PAGE317_I70@PURE_QUANTA.CONN112_10137002101LF(CHIPS)':
 'G6': CDS_PINID='G6';
NODE_NAME     J107 G8
 '@T6G_MB_LIB.T6G(SCH_1):PAGE317_I70@PURE_QUANTA.CONN112_10137002101LF(CHIPS)':
 'G8': CDS_PINID='G8';
NODE_NAME     J107 H5
 '@T6G_MB_LIB.T6G(SCH_1):PAGE317_I70@PURE_QUANTA.CONN112_10137002101LF(CHIPS)':
 'H5': CDS_PINID='H5';
NODE_NAME     J107 H7
 '@T6G_MB_LIB.T6G(SCH_1):PAGE317_I70@PURE_QUANTA.CONN112_10137002101LF(CHIPS)':
 'H7': CDS_PINID='H7';
NODE_NAME     J107 J6
 '@T6G_MB_LIB.T6G(SCH_1):PAGE317_I70@PURE_QUANTA.CONN112_10137002101LF(CHIPS)':
 'J6': CDS_PINID='J6';
NODE_NAME     J107 J8
 '@T6G_MB_LIB.T6G(SCH_1):PAGE317_I70@PURE_QUANTA.CONN112_10137002101LF(CHIPS)':
 'J8': CDS_PINID='J8';
NODE_NAME     J107 K5
 '@T6G_MB_LIB.T6G(SCH_1):PAGE317_I70@PURE_QUANTA.CONN112_10137002101LF(CHIPS)':
 'K5': CDS_PINID='K5';
NODE_NAME     J107 K7
 '@T6G_MB_LIB.T6G(SCH_1):PAGE317_I70@PURE_QUANTA.CONN112_10137002101LF(CHIPS)':
 'K7': CDS_PINID='K7';
NODE_NAME     J107 M6
 '@T6G_MB_LIB.T6G(SCH_1):PAGE317_I70@PURE_QUANTA.CONN112_10137002101LF(CHIPS)':
 'M6': CDS_PINID='M6';
NODE_NAME     J107 M8
 '@T6G_MB_LIB.T6G(SCH_1):PAGE317_I70@PURE_QUANTA.CONN112_10137002101LF(CHIPS)':
 'M8': CDS_PINID='M8';
NODE_NAME     J107 N5
 '@T6G_MB_LIB.T6G(SCH_1):PAGE317_I70@PURE_QUANTA.CONN112_10137002101LF(CHIPS)':
 'N5': CDS_PINID='N5';
NODE_NAME     J107 N7
 '@T6G_MB_LIB.T6G(SCH_1):PAGE317_I70@PURE_QUANTA.CONN112_10137002101LF(CHIPS)':
 'N7': CDS_PINID='N7';
NODE_NAME     J108 A6
 '@T6G_MB_LIB.T6G(SCH_1):PAGE320_I15@PURE_QUANTA.CONN112_10137002101LF(CHIPS)':
 'A6': CDS_PINID='A6';
NODE_NAME     J108 A8
 '@T6G_MB_LIB.T6G(SCH_1):PAGE320_I15@PURE_QUANTA.CONN112_10137002101LF(CHIPS)':
 'A8': CDS_PINID='A8';
NODE_NAME     J108 B5
 '@T6G_MB_LIB.T6G(SCH_1):PAGE320_I15@PURE_QUANTA.CONN112_10137002101LF(CHIPS)':
 'B5': CDS_PINID='B5';
NODE_NAME     J108 B7
 '@T6G_MB_LIB.T6G(SCH_1):PAGE320_I15@PURE_QUANTA.CONN112_10137002101LF(CHIPS)':
 'B7': CDS_PINID='B7';
NODE_NAME     J108 D6
 '@T6G_MB_LIB.T6G(SCH_1):PAGE320_I15@PURE_QUANTA.CONN112_10137002101LF(CHIPS)':
 'D6': CDS_PINID='D6';
NODE_NAME     J108 D8
 '@T6G_MB_LIB.T6G(SCH_1):PAGE320_I15@PURE_QUANTA.CONN112_10137002101LF(CHIPS)':
 'D8': CDS_PINID='D8';
NODE_NAME     J108 E5
 '@T6G_MB_LIB.T6G(SCH_1):PAGE320_I15@PURE_QUANTA.CONN112_10137002101LF(CHIPS)':
 'E5': CDS_PINID='E5';
NODE_NAME     J108 E7
 '@T6G_MB_LIB.T6G(SCH_1):PAGE320_I15@PURE_QUANTA.CONN112_10137002101LF(CHIPS)':
 'E7': CDS_PINID='E7';
NODE_NAME     J108 G6
 '@T6G_MB_LIB.T6G(SCH_1):PAGE320_I15@PURE_QUANTA.CONN112_10137002101LF(CHIPS)':
 'G6': CDS_PINID='G6';
NODE_NAME     J108 G8
 '@T6G_MB_LIB.T6G(SCH_1):PAGE320_I15@PURE_QUANTA.CONN112_10137002101LF(CHIPS)':
 'G8': CDS_PINID='G8';
NODE_NAME     J108 H5
 '@T6G_MB_LIB.T6G(SCH_1):PAGE320_I15@PURE_QUANTA.CONN112_10137002101LF(CHIPS)':
 'H5': CDS_PINID='H5';
NODE_NAME     J108 H7
 '@T6G_MB_LIB.T6G(SCH_1):PAGE320_I15@PURE_QUANTA.CONN112_10137002101LF(CHIPS)':
 'H7': CDS_PINID='H7';
NODE_NAME     J108 J6
 '@T6G_MB_LIB.T6G(SCH_1):PAGE320_I15@PURE_QUANTA.CONN112_10137002101LF(CHIPS)':
 'J6': CDS_PINID='J6';
NODE_NAME     J108 J8
 '@T6G_MB_LIB.T6G(SCH_1):PAGE320_I15@PURE_QUANTA.CONN112_10137002101LF(CHIPS)':
 'J8': CDS_PINID='J8';
NODE_NAME     J108 K5
 '@T6G_MB_LIB.T6G(SCH_1):PAGE320_I15@PURE_QUANTA.CONN112_10137002101LF(CHIPS)':
 'K5': CDS_PINID='K5';
NODE_NAME     J108 K7
 '@T6G_MB_LIB.T6G(SCH_1):PAGE320_I15@PURE_QUANTA.CONN112_10137002101LF(CHIPS)':
 'K7': CDS_PINID='K7';
NODE_NAME     J108 M6
 '@T6G_MB_LIB.T6G(SCH_1):PAGE320_I15@PURE_QUANTA.CONN112_10137002101LF(CHIPS)':
 'M6': CDS_PINID='M6';
NODE_NAME     J108 M8
 '@T6G_MB_LIB.T6G(SCH_1):PAGE320_I15@PURE_QUANTA.CONN112_10137002101LF(CHIPS)':
 'M8': CDS_PINID='M8';
NODE_NAME     J108 N5
 '@T6G_MB_LIB.T6G(SCH_1):PAGE320_I15@PURE_QUANTA.CONN112_10137002101LF(CHIPS)':
 'N5': CDS_PINID='N5';
NODE_NAME     J108 N7
 '@T6G_MB_LIB.T6G(SCH_1):PAGE320_I15@PURE_QUANTA.CONN112_10137002101LF(CHIPS)':
 'N7': CDS_PINID='N7';
NODE_NAME     J108 A2
 '@T6G_MB_LIB.T6G(SCH_1):PAGE320_I72@PURE_QUANTA.CONN112_10137002101LF(CHIPS)':
 'A2': CDS_PINID='A2';
NODE_NAME     J108 A4
 '@T6G_MB_LIB.T6G(SCH_1):PAGE320_I72@PURE_QUANTA.CONN112_10137002101LF(CHIPS)':
 'A4': CDS_PINID='A4';
NODE_NAME     J108 B1
 '@T6G_MB_LIB.T6G(SCH_1):PAGE320_I72@PURE_QUANTA.CONN112_10137002101LF(CHIPS)':
 'B1': CDS_PINID='B1';
NODE_NAME     J108 B3
 '@T6G_MB_LIB.T6G(SCH_1):PAGE320_I72@PURE_QUANTA.CONN112_10137002101LF(CHIPS)':
 'B3': CDS_PINID='B3';
NODE_NAME     J108 D2
 '@T6G_MB_LIB.T6G(SCH_1):PAGE320_I72@PURE_QUANTA.CONN112_10137002101LF(CHIPS)':
 'D2': CDS_PINID='D2';
NODE_NAME     J108 D4
 '@T6G_MB_LIB.T6G(SCH_1):PAGE320_I72@PURE_QUANTA.CONN112_10137002101LF(CHIPS)':
 'D4': CDS_PINID='D4';
NODE_NAME     J108 E1
 '@T6G_MB_LIB.T6G(SCH_1):PAGE320_I72@PURE_QUANTA.CONN112_10137002101LF(CHIPS)':
 'E1': CDS_PINID='E1';
NODE_NAME     J108 E3
 '@T6G_MB_LIB.T6G(SCH_1):PAGE320_I72@PURE_QUANTA.CONN112_10137002101LF(CHIPS)':
 'E3': CDS_PINID='E3';
NODE_NAME     J108 G2
 '@T6G_MB_LIB.T6G(SCH_1):PAGE320_I72@PURE_QUANTA.CONN112_10137002101LF(CHIPS)':
 'G2': CDS_PINID='G2';
NODE_NAME     J108 G4
 '@T6G_MB_LIB.T6G(SCH_1):PAGE320_I72@PURE_QUANTA.CONN112_10137002101LF(CHIPS)':
 'G4': CDS_PINID='G4';
NODE_NAME     J108 H1
 '@T6G_MB_LIB.T6G(SCH_1):PAGE320_I72@PURE_QUANTA.CONN112_10137002101LF(CHIPS)':
 'H1': CDS_PINID='H1';
NODE_NAME     J108 H3
 '@T6G_MB_LIB.T6G(SCH_1):PAGE320_I72@PURE_QUANTA.CONN112_10137002101LF(CHIPS)':
 'H3': CDS_PINID='H3';
NODE_NAME     J108 J2
 '@T6G_MB_LIB.T6G(SCH_1):PAGE320_I72@PURE_QUANTA.CONN112_10137002101LF(CHIPS)':
 'J2': CDS_PINID='J2';
NODE_NAME     J108 J4
 '@T6G_MB_LIB.T6G(SCH_1):PAGE320_I72@PURE_QUANTA.CONN112_10137002101LF(CHIPS)':
 'J4': CDS_PINID='J4';
NODE_NAME     J108 K1
 '@T6G_MB_LIB.T6G(SCH_1):PAGE320_I72@PURE_QUANTA.CONN112_10137002101LF(CHIPS)':
 'K1': CDS_PINID='K1';
NODE_NAME     J108 K3
 '@T6G_MB_LIB.T6G(SCH_1):PAGE320_I72@PURE_QUANTA.CONN112_10137002101LF(CHIPS)':
 'K3': CDS_PINID='K3';
NODE_NAME     J108 M2
 '@T6G_MB_LIB.T6G(SCH_1):PAGE320_I72@PURE_QUANTA.CONN112_10137002101LF(CHIPS)':
 'M2': CDS_PINID='M2';
NODE_NAME     J108 M4
 '@T6G_MB_LIB.T6G(SCH_1):PAGE320_I72@PURE_QUANTA.CONN112_10137002101LF(CHIPS)':
 'M4': CDS_PINID='M4';
NODE_NAME     J108 N1
 '@T6G_MB_LIB.T6G(SCH_1):PAGE320_I72@PURE_QUANTA.CONN112_10137002101LF(CHIPS)':
 'N1': CDS_PINID='N1';
NODE_NAME     J108 N3
 '@T6G_MB_LIB.T6G(SCH_1):PAGE320_I72@PURE_QUANTA.CONN112_10137002101LF(CHIPS)':
 'N3': CDS_PINID='N3';
NODE_NAME     J109 A6
 '@T6G_MB_LIB.T6G(SCH_1):PAGE319_I16@PURE_QUANTA.CONN112_10137002101LF(CHIPS)':
 'A6': CDS_PINID='A6';
NODE_NAME     J109 A8
 '@T6G_MB_LIB.T6G(SCH_1):PAGE319_I16@PURE_QUANTA.CONN112_10137002101LF(CHIPS)':
 'A8': CDS_PINID='A8';
NODE_NAME     J109 B5
 '@T6G_MB_LIB.T6G(SCH_1):PAGE319_I16@PURE_QUANTA.CONN112_10137002101LF(CHIPS)':
 'B5': CDS_PINID='B5';
NODE_NAME     J109 B7
 '@T6G_MB_LIB.T6G(SCH_1):PAGE319_I16@PURE_QUANTA.CONN112_10137002101LF(CHIPS)':
 'B7': CDS_PINID='B7';
NODE_NAME     J109 D6
 '@T6G_MB_LIB.T6G(SCH_1):PAGE319_I16@PURE_QUANTA.CONN112_10137002101LF(CHIPS)':
 'D6': CDS_PINID='D6';
NODE_NAME     J109 D8
 '@T6G_MB_LIB.T6G(SCH_1):PAGE319_I16@PURE_QUANTA.CONN112_10137002101LF(CHIPS)':
 'D8': CDS_PINID='D8';
NODE_NAME     J109 E5
 '@T6G_MB_LIB.T6G(SCH_1):PAGE319_I16@PURE_QUANTA.CONN112_10137002101LF(CHIPS)':
 'E5': CDS_PINID='E5';
NODE_NAME     J109 E7
 '@T6G_MB_LIB.T6G(SCH_1):PAGE319_I16@PURE_QUANTA.CONN112_10137002101LF(CHIPS)':
 'E7': CDS_PINID='E7';
NODE_NAME     J109 G6
 '@T6G_MB_LIB.T6G(SCH_1):PAGE319_I16@PURE_QUANTA.CONN112_10137002101LF(CHIPS)':
 'G6': CDS_PINID='G6';
NODE_NAME     J109 G8
 '@T6G_MB_LIB.T6G(SCH_1):PAGE319_I16@PURE_QUANTA.CONN112_10137002101LF(CHIPS)':
 'G8': CDS_PINID='G8';
NODE_NAME     J109 H5
 '@T6G_MB_LIB.T6G(SCH_1):PAGE319_I16@PURE_QUANTA.CONN112_10137002101LF(CHIPS)':
 'H5': CDS_PINID='H5';
NODE_NAME     J109 H7
 '@T6G_MB_LIB.T6G(SCH_1):PAGE319_I16@PURE_QUANTA.CONN112_10137002101LF(CHIPS)':
 'H7': CDS_PINID='H7';
NODE_NAME     J109 J6
 '@T6G_MB_LIB.T6G(SCH_1):PAGE319_I16@PURE_QUANTA.CONN112_10137002101LF(CHIPS)':
 'J6': CDS_PINID='J6';
NODE_NAME     J109 J8
 '@T6G_MB_LIB.T6G(SCH_1):PAGE319_I16@PURE_QUANTA.CONN112_10137002101LF(CHIPS)':
 'J8': CDS_PINID='J8';
NODE_NAME     J109 K5
 '@T6G_MB_LIB.T6G(SCH_1):PAGE319_I16@PURE_QUANTA.CONN112_10137002101LF(CHIPS)':
 'K5': CDS_PINID='K5';
NODE_NAME     J109 K7
 '@T6G_MB_LIB.T6G(SCH_1):PAGE319_I16@PURE_QUANTA.CONN112_10137002101LF(CHIPS)':
 'K7': CDS_PINID='K7';
NODE_NAME     J109 M6
 '@T6G_MB_LIB.T6G(SCH_1):PAGE319_I16@PURE_QUANTA.CONN112_10137002101LF(CHIPS)':
 'M6': CDS_PINID='M6';
NODE_NAME     J109 M8
 '@T6G_MB_LIB.T6G(SCH_1):PAGE319_I16@PURE_QUANTA.CONN112_10137002101LF(CHIPS)':
 'M8': CDS_PINID='M8';
NODE_NAME     J109 N5
 '@T6G_MB_LIB.T6G(SCH_1):PAGE319_I16@PURE_QUANTA.CONN112_10137002101LF(CHIPS)':
 'N5': CDS_PINID='N5';
NODE_NAME     J109 N7
 '@T6G_MB_LIB.T6G(SCH_1):PAGE319_I16@PURE_QUANTA.CONN112_10137002101LF(CHIPS)':
 'N7': CDS_PINID='N7';
NODE_NAME     J109 A2
 '@T6G_MB_LIB.T6G(SCH_1):PAGE319_I76@PURE_QUANTA.CONN112_10137002101LF(CHIPS)':
 'A2': CDS_PINID='A2';
NODE_NAME     J109 A4
 '@T6G_MB_LIB.T6G(SCH_1):PAGE319_I76@PURE_QUANTA.CONN112_10137002101LF(CHIPS)':
 'A4': CDS_PINID='A4';
NODE_NAME     J109 B1
 '@T6G_MB_LIB.T6G(SCH_1):PAGE319_I76@PURE_QUANTA.CONN112_10137002101LF(CHIPS)':
 'B1': CDS_PINID='B1';
NODE_NAME     J109 B3
 '@T6G_MB_LIB.T6G(SCH_1):PAGE319_I76@PURE_QUANTA.CONN112_10137002101LF(CHIPS)':
 'B3': CDS_PINID='B3';
NODE_NAME     J109 D2
 '@T6G_MB_LIB.T6G(SCH_1):PAGE319_I76@PURE_QUANTA.CONN112_10137002101LF(CHIPS)':
 'D2': CDS_PINID='D2';
NODE_NAME     J109 D4
 '@T6G_MB_LIB.T6G(SCH_1):PAGE319_I76@PURE_QUANTA.CONN112_10137002101LF(CHIPS)':
 'D4': CDS_PINID='D4';
NODE_NAME     J109 E1
 '@T6G_MB_LIB.T6G(SCH_1):PAGE319_I76@PURE_QUANTA.CONN112_10137002101LF(CHIPS)':
 'E1': CDS_PINID='E1';
NODE_NAME     J109 E3
 '@T6G_MB_LIB.T6G(SCH_1):PAGE319_I76@PURE_QUANTA.CONN112_10137002101LF(CHIPS)':
 'E3': CDS_PINID='E3';
NODE_NAME     J109 G2
 '@T6G_MB_LIB.T6G(SCH_1):PAGE319_I76@PURE_QUANTA.CONN112_10137002101LF(CHIPS)':
 'G2': CDS_PINID='G2';
NODE_NAME     J109 G4
 '@T6G_MB_LIB.T6G(SCH_1):PAGE319_I76@PURE_QUANTA.CONN112_10137002101LF(CHIPS)':
 'G4': CDS_PINID='G4';
NODE_NAME     J109 H1
 '@T6G_MB_LIB.T6G(SCH_1):PAGE319_I76@PURE_QUANTA.CONN112_10137002101LF(CHIPS)':
 'H1': CDS_PINID='H1';
NODE_NAME     J109 H3
 '@T6G_MB_LIB.T6G(SCH_1):PAGE319_I76@PURE_QUANTA.CONN112_10137002101LF(CHIPS)':
 'H3': CDS_PINID='H3';
NODE_NAME     J109 J2
 '@T6G_MB_LIB.T6G(SCH_1):PAGE319_I76@PURE_QUANTA.CONN112_10137002101LF(CHIPS)':
 'J2': CDS_PINID='J2';
NODE_NAME     J109 J4
 '@T6G_MB_LIB.T6G(SCH_1):PAGE319_I76@PURE_QUANTA.CONN112_10137002101LF(CHIPS)':
 'J4': CDS_PINID='J4';
NODE_NAME     J109 K1
 '@T6G_MB_LIB.T6G(SCH_1):PAGE319_I76@PURE_QUANTA.CONN112_10137002101LF(CHIPS)':
 'K1': CDS_PINID='K1';
NODE_NAME     J109 K3
 '@T6G_MB_LIB.T6G(SCH_1):PAGE319_I76@PURE_QUANTA.CONN112_10137002101LF(CHIPS)':
 'K3': CDS_PINID='K3';
NODE_NAME     J109 M2
 '@T6G_MB_LIB.T6G(SCH_1):PAGE319_I76@PURE_QUANTA.CONN112_10137002101LF(CHIPS)':
 'M2': CDS_PINID='M2';
NODE_NAME     J109 M4
 '@T6G_MB_LIB.T6G(SCH_1):PAGE319_I76@PURE_QUANTA.CONN112_10137002101LF(CHIPS)':
 'M4': CDS_PINID='M4';
NODE_NAME     J109 N1
 '@T6G_MB_LIB.T6G(SCH_1):PAGE319_I76@PURE_QUANTA.CONN112_10137002101LF(CHIPS)':
 'N1': CDS_PINID='N1';
NODE_NAME     J109 N3
 '@T6G_MB_LIB.T6G(SCH_1):PAGE319_I76@PURE_QUANTA.CONN112_10137002101LF(CHIPS)':
 'N3': CDS_PINID='N3';
NODE_NAME     J110 A6
 '@T6G_MB_LIB.T6G(SCH_1):PAGE318_I16@PURE_QUANTA.CONN112_10137002101LF(CHIPS)':
 'A6': CDS_PINID='A6';
NODE_NAME     J110 A8
 '@T6G_MB_LIB.T6G(SCH_1):PAGE318_I16@PURE_QUANTA.CONN112_10137002101LF(CHIPS)':
 'A8': CDS_PINID='A8';
NODE_NAME     J110 B5
 '@T6G_MB_LIB.T6G(SCH_1):PAGE318_I16@PURE_QUANTA.CONN112_10137002101LF(CHIPS)':
 'B5': CDS_PINID='B5';
NODE_NAME     J110 B7
 '@T6G_MB_LIB.T6G(SCH_1):PAGE318_I16@PURE_QUANTA.CONN112_10137002101LF(CHIPS)':
 'B7': CDS_PINID='B7';
NODE_NAME     J110 D6
 '@T6G_MB_LIB.T6G(SCH_1):PAGE318_I16@PURE_QUANTA.CONN112_10137002101LF(CHIPS)':
 'D6': CDS_PINID='D6';
NODE_NAME     J110 D8
 '@T6G_MB_LIB.T6G(SCH_1):PAGE318_I16@PURE_QUANTA.CONN112_10137002101LF(CHIPS)':
 'D8': CDS_PINID='D8';
NODE_NAME     J110 E5
 '@T6G_MB_LIB.T6G(SCH_1):PAGE318_I16@PURE_QUANTA.CONN112_10137002101LF(CHIPS)':
 'E5': CDS_PINID='E5';
NODE_NAME     J110 E7
 '@T6G_MB_LIB.T6G(SCH_1):PAGE318_I16@PURE_QUANTA.CONN112_10137002101LF(CHIPS)':
 'E7': CDS_PINID='E7';
NODE_NAME     J110 G6
 '@T6G_MB_LIB.T6G(SCH_1):PAGE318_I16@PURE_QUANTA.CONN112_10137002101LF(CHIPS)':
 'G6': CDS_PINID='G6';
NODE_NAME     J110 G8
 '@T6G_MB_LIB.T6G(SCH_1):PAGE318_I16@PURE_QUANTA.CONN112_10137002101LF(CHIPS)':
 'G8': CDS_PINID='G8';
NODE_NAME     J110 H5
 '@T6G_MB_LIB.T6G(SCH_1):PAGE318_I16@PURE_QUANTA.CONN112_10137002101LF(CHIPS)':
 'H5': CDS_PINID='H5';
NODE_NAME     J110 H7
 '@T6G_MB_LIB.T6G(SCH_1):PAGE318_I16@PURE_QUANTA.CONN112_10137002101LF(CHIPS)':
 'H7': CDS_PINID='H7';
NODE_NAME     J110 J6
 '@T6G_MB_LIB.T6G(SCH_1):PAGE318_I16@PURE_QUANTA.CONN112_10137002101LF(CHIPS)':
 'J6': CDS_PINID='J6';
NODE_NAME     J110 J8
 '@T6G_MB_LIB.T6G(SCH_1):PAGE318_I16@PURE_QUANTA.CONN112_10137002101LF(CHIPS)':
 'J8': CDS_PINID='J8';
NODE_NAME     J110 K5
 '@T6G_MB_LIB.T6G(SCH_1):PAGE318_I16@PURE_QUANTA.CONN112_10137002101LF(CHIPS)':
 'K5': CDS_PINID='K5';
NODE_NAME     J110 K7
 '@T6G_MB_LIB.T6G(SCH_1):PAGE318_I16@PURE_QUANTA.CONN112_10137002101LF(CHIPS)':
 'K7': CDS_PINID='K7';
NODE_NAME     J110 M6
 '@T6G_MB_LIB.T6G(SCH_1):PAGE318_I16@PURE_QUANTA.CONN112_10137002101LF(CHIPS)':
 'M6': CDS_PINID='M6';
NODE_NAME     J110 M8
 '@T6G_MB_LIB.T6G(SCH_1):PAGE318_I16@PURE_QUANTA.CONN112_10137002101LF(CHIPS)':
 'M8': CDS_PINID='M8';
NODE_NAME     J110 N5
 '@T6G_MB_LIB.T6G(SCH_1):PAGE318_I16@PURE_QUANTA.CONN112_10137002101LF(CHIPS)':
 'N5': CDS_PINID='N5';
NODE_NAME     J110 N7
 '@T6G_MB_LIB.T6G(SCH_1):PAGE318_I16@PURE_QUANTA.CONN112_10137002101LF(CHIPS)':
 'N7': CDS_PINID='N7';
NODE_NAME     J110 A2
 '@T6G_MB_LIB.T6G(SCH_1):PAGE318_I76@PURE_QUANTA.CONN112_10137002101LF(CHIPS)':
 'A2': CDS_PINID='A2';
NODE_NAME     J110 A4
 '@T6G_MB_LIB.T6G(SCH_1):PAGE318_I76@PURE_QUANTA.CONN112_10137002101LF(CHIPS)':
 'A4': CDS_PINID='A4';
NODE_NAME     J110 B1
 '@T6G_MB_LIB.T6G(SCH_1):PAGE318_I76@PURE_QUANTA.CONN112_10137002101LF(CHIPS)':
 'B1': CDS_PINID='B1';
NODE_NAME     J110 B3
 '@T6G_MB_LIB.T6G(SCH_1):PAGE318_I76@PURE_QUANTA.CONN112_10137002101LF(CHIPS)':
 'B3': CDS_PINID='B3';
NODE_NAME     J110 D2
 '@T6G_MB_LIB.T6G(SCH_1):PAGE318_I76@PURE_QUANTA.CONN112_10137002101LF(CHIPS)':
 'D2': CDS_PINID='D2';
NODE_NAME     J110 D4
 '@T6G_MB_LIB.T6G(SCH_1):PAGE318_I76@PURE_QUANTA.CONN112_10137002101LF(CHIPS)':
 'D4': CDS_PINID='D4';
NODE_NAME     J110 E1
 '@T6G_MB_LIB.T6G(SCH_1):PAGE318_I76@PURE_QUANTA.CONN112_10137002101LF(CHIPS)':
 'E1': CDS_PINID='E1';
NODE_NAME     J110 E3
 '@T6G_MB_LIB.T6G(SCH_1):PAGE318_I76@PURE_QUANTA.CONN112_10137002101LF(CHIPS)':
 'E3': CDS_PINID='E3';
NODE_NAME     J110 G2
 '@T6G_MB_LIB.T6G(SCH_1):PAGE318_I76@PURE_QUANTA.CONN112_10137002101LF(CHIPS)':
 'G2': CDS_PINID='G2';
NODE_NAME     J110 G4
 '@T6G_MB_LIB.T6G(SCH_1):PAGE318_I76@PURE_QUANTA.CONN112_10137002101LF(CHIPS)':
 'G4': CDS_PINID='G4';
NODE_NAME     J110 H1
 '@T6G_MB_LIB.T6G(SCH_1):PAGE318_I76@PURE_QUANTA.CONN112_10137002101LF(CHIPS)':
 'H1': CDS_PINID='H1';
NODE_NAME     J110 H3
 '@T6G_MB_LIB.T6G(SCH_1):PAGE318_I76@PURE_QUANTA.CONN112_10137002101LF(CHIPS)':
 'H3': CDS_PINID='H3';
NODE_NAME     J110 J2
 '@T6G_MB_LIB.T6G(SCH_1):PAGE318_I76@PURE_QUANTA.CONN112_10137002101LF(CHIPS)':
 'J2': CDS_PINID='J2';
NODE_NAME     J110 J4
 '@T6G_MB_LIB.T6G(SCH_1):PAGE318_I76@PURE_QUANTA.CONN112_10137002101LF(CHIPS)':
 'J4': CDS_PINID='J4';
NODE_NAME     J110 K1
 '@T6G_MB_LIB.T6G(SCH_1):PAGE318_I76@PURE_QUANTA.CONN112_10137002101LF(CHIPS)':
 'K1': CDS_PINID='K1';
NODE_NAME     J110 K3
 '@T6G_MB_LIB.T6G(SCH_1):PAGE318_I76@PURE_QUANTA.CONN112_10137002101LF(CHIPS)':
 'K3': CDS_PINID='K3';
NODE_NAME     J110 M2
 '@T6G_MB_LIB.T6G(SCH_1):PAGE318_I76@PURE_QUANTA.CONN112_10137002101LF(CHIPS)':
 'M2': CDS_PINID='M2';
NODE_NAME     J110 M4
 '@T6G_MB_LIB.T6G(SCH_1):PAGE318_I76@PURE_QUANTA.CONN112_10137002101LF(CHIPS)':
 'M4': CDS_PINID='M4';
NODE_NAME     J110 N1
 '@T6G_MB_LIB.T6G(SCH_1):PAGE318_I76@PURE_QUANTA.CONN112_10137002101LF(CHIPS)':
 'N1': CDS_PINID='N1';
NODE_NAME     J110 N3
 '@T6G_MB_LIB.T6G(SCH_1):PAGE318_I76@PURE_QUANTA.CONN112_10137002101LF(CHIPS)':
 'N3': CDS_PINID='N3';
NODE_NAME     J111 A6
 '@T6G_MB_LIB.T6G(SCH_1):PAGE328_I38@PURE_QUANTA.CONN112_10137002101LF(CHIPS)':
 'A6': CDS_PINID='A6';
NODE_NAME     J111 A8
 '@T6G_MB_LIB.T6G(SCH_1):PAGE328_I38@PURE_QUANTA.CONN112_10137002101LF(CHIPS)':
 'A8': CDS_PINID='A8';
NODE_NAME     J111 B5
 '@T6G_MB_LIB.T6G(SCH_1):PAGE328_I38@PURE_QUANTA.CONN112_10137002101LF(CHIPS)':
 'B5': CDS_PINID='B5';
NODE_NAME     J111 B7
 '@T6G_MB_LIB.T6G(SCH_1):PAGE328_I38@PURE_QUANTA.CONN112_10137002101LF(CHIPS)':
 'B7': CDS_PINID='B7';
NODE_NAME     J111 D6
 '@T6G_MB_LIB.T6G(SCH_1):PAGE328_I38@PURE_QUANTA.CONN112_10137002101LF(CHIPS)':
 'D6': CDS_PINID='D6';
NODE_NAME     J111 D8
 '@T6G_MB_LIB.T6G(SCH_1):PAGE328_I38@PURE_QUANTA.CONN112_10137002101LF(CHIPS)':
 'D8': CDS_PINID='D8';
NODE_NAME     J111 E5
 '@T6G_MB_LIB.T6G(SCH_1):PAGE328_I38@PURE_QUANTA.CONN112_10137002101LF(CHIPS)':
 'E5': CDS_PINID='E5';
NODE_NAME     J111 E7
 '@T6G_MB_LIB.T6G(SCH_1):PAGE328_I38@PURE_QUANTA.CONN112_10137002101LF(CHIPS)':
 'E7': CDS_PINID='E7';
NODE_NAME     J111 G6
 '@T6G_MB_LIB.T6G(SCH_1):PAGE328_I38@PURE_QUANTA.CONN112_10137002101LF(CHIPS)':
 'G6': CDS_PINID='G6';
NODE_NAME     J111 G8
 '@T6G_MB_LIB.T6G(SCH_1):PAGE328_I38@PURE_QUANTA.CONN112_10137002101LF(CHIPS)':
 'G8': CDS_PINID='G8';
NODE_NAME     J111 H5
 '@T6G_MB_LIB.T6G(SCH_1):PAGE328_I38@PURE_QUANTA.CONN112_10137002101LF(CHIPS)':
 'H5': CDS_PINID='H5';
NODE_NAME     J111 H7
 '@T6G_MB_LIB.T6G(SCH_1):PAGE328_I38@PURE_QUANTA.CONN112_10137002101LF(CHIPS)':
 'H7': CDS_PINID='H7';
NODE_NAME     J111 J6
 '@T6G_MB_LIB.T6G(SCH_1):PAGE328_I38@PURE_QUANTA.CONN112_10137002101LF(CHIPS)':
 'J6': CDS_PINID='J6';
NODE_NAME     J111 J8
 '@T6G_MB_LIB.T6G(SCH_1):PAGE328_I38@PURE_QUANTA.CONN112_10137002101LF(CHIPS)':
 'J8': CDS_PINID='J8';
NODE_NAME     J111 K5
 '@T6G_MB_LIB.T6G(SCH_1):PAGE328_I38@PURE_QUANTA.CONN112_10137002101LF(CHIPS)':
 'K5': CDS_PINID='K5';
NODE_NAME     J111 K7
 '@T6G_MB_LIB.T6G(SCH_1):PAGE328_I38@PURE_QUANTA.CONN112_10137002101LF(CHIPS)':
 'K7': CDS_PINID='K7';
NODE_NAME     J111 M6
 '@T6G_MB_LIB.T6G(SCH_1):PAGE328_I38@PURE_QUANTA.CONN112_10137002101LF(CHIPS)':
 'M6': CDS_PINID='M6';
NODE_NAME     J111 M8
 '@T6G_MB_LIB.T6G(SCH_1):PAGE328_I38@PURE_QUANTA.CONN112_10137002101LF(CHIPS)':
 'M8': CDS_PINID='M8';
NODE_NAME     J111 N5
 '@T6G_MB_LIB.T6G(SCH_1):PAGE328_I38@PURE_QUANTA.CONN112_10137002101LF(CHIPS)':
 'N5': CDS_PINID='N5';
NODE_NAME     J111 N7
 '@T6G_MB_LIB.T6G(SCH_1):PAGE328_I38@PURE_QUANTA.CONN112_10137002101LF(CHIPS)':
 'N7': CDS_PINID='N7';
NODE_NAME     J111 A2
 '@T6G_MB_LIB.T6G(SCH_1):PAGE328_I76@PURE_QUANTA.CONN112_10137002101LF(CHIPS)':
 'A2': CDS_PINID='A2';
NODE_NAME     J111 A4
 '@T6G_MB_LIB.T6G(SCH_1):PAGE328_I76@PURE_QUANTA.CONN112_10137002101LF(CHIPS)':
 'A4': CDS_PINID='A4';
NODE_NAME     J111 B1
 '@T6G_MB_LIB.T6G(SCH_1):PAGE328_I76@PURE_QUANTA.CONN112_10137002101LF(CHIPS)':
 'B1': CDS_PINID='B1';
NODE_NAME     J111 B3
 '@T6G_MB_LIB.T6G(SCH_1):PAGE328_I76@PURE_QUANTA.CONN112_10137002101LF(CHIPS)':
 'B3': CDS_PINID='B3';
NODE_NAME     J111 D2
 '@T6G_MB_LIB.T6G(SCH_1):PAGE328_I76@PURE_QUANTA.CONN112_10137002101LF(CHIPS)':
 'D2': CDS_PINID='D2';
NODE_NAME     J111 D4
 '@T6G_MB_LIB.T6G(SCH_1):PAGE328_I76@PURE_QUANTA.CONN112_10137002101LF(CHIPS)':
 'D4': CDS_PINID='D4';
NODE_NAME     J111 E1
 '@T6G_MB_LIB.T6G(SCH_1):PAGE328_I76@PURE_QUANTA.CONN112_10137002101LF(CHIPS)':
 'E1': CDS_PINID='E1';
NODE_NAME     J111 E3
 '@T6G_MB_LIB.T6G(SCH_1):PAGE328_I76@PURE_QUANTA.CONN112_10137002101LF(CHIPS)':
 'E3': CDS_PINID='E3';
NODE_NAME     J111 G2
 '@T6G_MB_LIB.T6G(SCH_1):PAGE328_I76@PURE_QUANTA.CONN112_10137002101LF(CHIPS)':
 'G2': CDS_PINID='G2';
NODE_NAME     J111 G4
 '@T6G_MB_LIB.T6G(SCH_1):PAGE328_I76@PURE_QUANTA.CONN112_10137002101LF(CHIPS)':
 'G4': CDS_PINID='G4';
NODE_NAME     J111 H1
 '@T6G_MB_LIB.T6G(SCH_1):PAGE328_I76@PURE_QUANTA.CONN112_10137002101LF(CHIPS)':
 'H1': CDS_PINID='H1';
NODE_NAME     J111 H3
 '@T6G_MB_LIB.T6G(SCH_1):PAGE328_I76@PURE_QUANTA.CONN112_10137002101LF(CHIPS)':
 'H3': CDS_PINID='H3';
NODE_NAME     J111 J2
 '@T6G_MB_LIB.T6G(SCH_1):PAGE328_I76@PURE_QUANTA.CONN112_10137002101LF(CHIPS)':
 'J2': CDS_PINID='J2';
NODE_NAME     J111 J4
 '@T6G_MB_LIB.T6G(SCH_1):PAGE328_I76@PURE_QUANTA.CONN112_10137002101LF(CHIPS)':
 'J4': CDS_PINID='J4';
NODE_NAME     J111 K1
 '@T6G_MB_LIB.T6G(SCH_1):PAGE328_I76@PURE_QUANTA.CONN112_10137002101LF(CHIPS)':
 'K1': CDS_PINID='K1';
NODE_NAME     J111 K3
 '@T6G_MB_LIB.T6G(SCH_1):PAGE328_I76@PURE_QUANTA.CONN112_10137002101LF(CHIPS)':
 'K3': CDS_PINID='K3';
NODE_NAME     J111 M2
 '@T6G_MB_LIB.T6G(SCH_1):PAGE328_I76@PURE_QUANTA.CONN112_10137002101LF(CHIPS)':
 'M2': CDS_PINID='M2';
NODE_NAME     J111 M4
 '@T6G_MB_LIB.T6G(SCH_1):PAGE328_I76@PURE_QUANTA.CONN112_10137002101LF(CHIPS)':
 'M4': CDS_PINID='M4';
NODE_NAME     J111 N1
 '@T6G_MB_LIB.T6G(SCH_1):PAGE328_I76@PURE_QUANTA.CONN112_10137002101LF(CHIPS)':
 'N1': CDS_PINID='N1';
NODE_NAME     J111 N3
 '@T6G_MB_LIB.T6G(SCH_1):PAGE328_I76@PURE_QUANTA.CONN112_10137002101LF(CHIPS)':
 'N3': CDS_PINID='N3';
NODE_NAME     J112 A6
 '@T6G_MB_LIB.T6G(SCH_1):PAGE329_I7@PURE_QUANTA.CONN160_10131762101LF(CHIPS)':
 'A6': CDS_PINID='A6';
NODE_NAME     J112 A8
 '@T6G_MB_LIB.T6G(SCH_1):PAGE329_I7@PURE_QUANTA.CONN160_10131762101LF(CHIPS)':
 'A8': CDS_PINID='A8';
NODE_NAME     J112 B5
 '@T6G_MB_LIB.T6G(SCH_1):PAGE329_I7@PURE_QUANTA.CONN160_10131762101LF(CHIPS)':
 'B5': CDS_PINID='B5';
NODE_NAME     J112 B7
 '@T6G_MB_LIB.T6G(SCH_1):PAGE329_I7@PURE_QUANTA.CONN160_10131762101LF(CHIPS)':
 'B7': CDS_PINID='B7';
NODE_NAME     J112 D6
 '@T6G_MB_LIB.T6G(SCH_1):PAGE329_I7@PURE_QUANTA.CONN160_10131762101LF(CHIPS)':
 'D6': CDS_PINID='D6';
NODE_NAME     J112 D8
 '@T6G_MB_LIB.T6G(SCH_1):PAGE329_I7@PURE_QUANTA.CONN160_10131762101LF(CHIPS)':
 'D8': CDS_PINID='D8';
NODE_NAME     J112 E5
 '@T6G_MB_LIB.T6G(SCH_1):PAGE329_I7@PURE_QUANTA.CONN160_10131762101LF(CHIPS)':
 'E5': CDS_PINID='E5';
NODE_NAME     J112 E7
 '@T6G_MB_LIB.T6G(SCH_1):PAGE329_I7@PURE_QUANTA.CONN160_10131762101LF(CHIPS)':
 'E7': CDS_PINID='E7';
NODE_NAME     J112 G6
 '@T6G_MB_LIB.T6G(SCH_1):PAGE329_I7@PURE_QUANTA.CONN160_10131762101LF(CHIPS)':
 'G6': CDS_PINID='G6';
NODE_NAME     J112 G8
 '@T6G_MB_LIB.T6G(SCH_1):PAGE329_I7@PURE_QUANTA.CONN160_10131762101LF(CHIPS)':
 'G8': CDS_PINID='G8';
NODE_NAME     J112 H5
 '@T6G_MB_LIB.T6G(SCH_1):PAGE329_I7@PURE_QUANTA.CONN160_10131762101LF(CHIPS)':
 'H5': CDS_PINID='H5';
NODE_NAME     J112 H7
 '@T6G_MB_LIB.T6G(SCH_1):PAGE329_I7@PURE_QUANTA.CONN160_10131762101LF(CHIPS)':
 'H7': CDS_PINID='H7';
NODE_NAME     J112 J6
 '@T6G_MB_LIB.T6G(SCH_1):PAGE329_I7@PURE_QUANTA.CONN160_10131762101LF(CHIPS)':
 'J6': CDS_PINID='J6';
NODE_NAME     J112 J8
 '@T6G_MB_LIB.T6G(SCH_1):PAGE329_I7@PURE_QUANTA.CONN160_10131762101LF(CHIPS)':
 'J8': CDS_PINID='J8';
NODE_NAME     J112 K5
 '@T6G_MB_LIB.T6G(SCH_1):PAGE329_I7@PURE_QUANTA.CONN160_10131762101LF(CHIPS)':
 'K5': CDS_PINID='K5';
NODE_NAME     J112 K7
 '@T6G_MB_LIB.T6G(SCH_1):PAGE329_I7@PURE_QUANTA.CONN160_10131762101LF(CHIPS)':
 'K7': CDS_PINID='K7';
NODE_NAME     J112 M6
 '@T6G_MB_LIB.T6G(SCH_1):PAGE329_I7@PURE_QUANTA.CONN160_10131762101LF(CHIPS)':
 'M6': CDS_PINID='M6';
NODE_NAME     J112 M8
 '@T6G_MB_LIB.T6G(SCH_1):PAGE329_I7@PURE_QUANTA.CONN160_10131762101LF(CHIPS)':
 'M8': CDS_PINID='M8';
NODE_NAME     J112 N5
 '@T6G_MB_LIB.T6G(SCH_1):PAGE329_I7@PURE_QUANTA.CONN160_10131762101LF(CHIPS)':
 'N5': CDS_PINID='N5';
NODE_NAME     J112 N7
 '@T6G_MB_LIB.T6G(SCH_1):PAGE329_I7@PURE_QUANTA.CONN160_10131762101LF(CHIPS)':
 'N7': CDS_PINID='N7';
NODE_NAME     J112 P6
 '@T6G_MB_LIB.T6G(SCH_1):PAGE329_I7@PURE_QUANTA.CONN160_10131762101LF(CHIPS)':
 'P6': CDS_PINID='P6';
NODE_NAME     J112 P8
 '@T6G_MB_LIB.T6G(SCH_1):PAGE329_I7@PURE_QUANTA.CONN160_10131762101LF(CHIPS)':
 'P8': CDS_PINID='P8';
NODE_NAME     J112 Q5
 '@T6G_MB_LIB.T6G(SCH_1):PAGE329_I7@PURE_QUANTA.CONN160_10131762101LF(CHIPS)':
 'Q5': CDS_PINID='Q5';
NODE_NAME     J112 Q7
 '@T6G_MB_LIB.T6G(SCH_1):PAGE329_I7@PURE_QUANTA.CONN160_10131762101LF(CHIPS)':
 'Q7': CDS_PINID='Q7';
NODE_NAME     J112 S6
 '@T6G_MB_LIB.T6G(SCH_1):PAGE329_I7@PURE_QUANTA.CONN160_10131762101LF(CHIPS)':
 'S6': CDS_PINID='S6';
NODE_NAME     J112 S8
 '@T6G_MB_LIB.T6G(SCH_1):PAGE329_I7@PURE_QUANTA.CONN160_10131762101LF(CHIPS)':
 'S8': CDS_PINID='S8';
NODE_NAME     J112 T5
 '@T6G_MB_LIB.T6G(SCH_1):PAGE329_I7@PURE_QUANTA.CONN160_10131762101LF(CHIPS)':
 'T5': CDS_PINID='T5';
NODE_NAME     J112 T7
 '@T6G_MB_LIB.T6G(SCH_1):PAGE329_I7@PURE_QUANTA.CONN160_10131762101LF(CHIPS)':
 'T7': CDS_PINID='T7';
NODE_NAME     J112 A2
 '@T6G_MB_LIB.T6G(SCH_1):PAGE329_I102@PURE_QUANTA.CONN160_10131762101LF(CHIPS)':
 'A2': CDS_PINID='A2';
NODE_NAME     J112 A4
 '@T6G_MB_LIB.T6G(SCH_1):PAGE329_I102@PURE_QUANTA.CONN160_10131762101LF(CHIPS)':
 'A4': CDS_PINID='A4';
NODE_NAME     J112 B1
 '@T6G_MB_LIB.T6G(SCH_1):PAGE329_I102@PURE_QUANTA.CONN160_10131762101LF(CHIPS)':
 'B1': CDS_PINID='B1';
NODE_NAME     J112 B3
 '@T6G_MB_LIB.T6G(SCH_1):PAGE329_I102@PURE_QUANTA.CONN160_10131762101LF(CHIPS)':
 'B3': CDS_PINID='B3';
NODE_NAME     J112 D2
 '@T6G_MB_LIB.T6G(SCH_1):PAGE329_I102@PURE_QUANTA.CONN160_10131762101LF(CHIPS)':
 'D2': CDS_PINID='D2';
NODE_NAME     J112 D4
 '@T6G_MB_LIB.T6G(SCH_1):PAGE329_I102@PURE_QUANTA.CONN160_10131762101LF(CHIPS)':
 'D4': CDS_PINID='D4';
NODE_NAME     J112 E1
 '@T6G_MB_LIB.T6G(SCH_1):PAGE329_I102@PURE_QUANTA.CONN160_10131762101LF(CHIPS)':
 'E1': CDS_PINID='E1';
NODE_NAME     J112 E3
 '@T6G_MB_LIB.T6G(SCH_1):PAGE329_I102@PURE_QUANTA.CONN160_10131762101LF(CHIPS)':
 'E3': CDS_PINID='E3';
NODE_NAME     J112 G2
 '@T6G_MB_LIB.T6G(SCH_1):PAGE329_I102@PURE_QUANTA.CONN160_10131762101LF(CHIPS)':
 'G2': CDS_PINID='G2';
NODE_NAME     J112 G4
 '@T6G_MB_LIB.T6G(SCH_1):PAGE329_I102@PURE_QUANTA.CONN160_10131762101LF(CHIPS)':
 'G4': CDS_PINID='G4';
NODE_NAME     J112 H1
 '@T6G_MB_LIB.T6G(SCH_1):PAGE329_I102@PURE_QUANTA.CONN160_10131762101LF(CHIPS)':
 'H1': CDS_PINID='H1';
NODE_NAME     J112 H3
 '@T6G_MB_LIB.T6G(SCH_1):PAGE329_I102@PURE_QUANTA.CONN160_10131762101LF(CHIPS)':
 'H3': CDS_PINID='H3';
NODE_NAME     J112 J2
 '@T6G_MB_LIB.T6G(SCH_1):PAGE329_I102@PURE_QUANTA.CONN160_10131762101LF(CHIPS)':
 'J2': CDS_PINID='J2';
NODE_NAME     J112 J4
 '@T6G_MB_LIB.T6G(SCH_1):PAGE329_I102@PURE_QUANTA.CONN160_10131762101LF(CHIPS)':
 'J4': CDS_PINID='J4';
NODE_NAME     J112 K1
 '@T6G_MB_LIB.T6G(SCH_1):PAGE329_I102@PURE_QUANTA.CONN160_10131762101LF(CHIPS)':
 'K1': CDS_PINID='K1';
NODE_NAME     J112 K3
 '@T6G_MB_LIB.T6G(SCH_1):PAGE329_I102@PURE_QUANTA.CONN160_10131762101LF(CHIPS)':
 'K3': CDS_PINID='K3';
NODE_NAME     J112 M2
 '@T6G_MB_LIB.T6G(SCH_1):PAGE329_I102@PURE_QUANTA.CONN160_10131762101LF(CHIPS)':
 'M2': CDS_PINID='M2';
NODE_NAME     J112 M4
 '@T6G_MB_LIB.T6G(SCH_1):PAGE329_I102@PURE_QUANTA.CONN160_10131762101LF(CHIPS)':
 'M4': CDS_PINID='M4';
NODE_NAME     J112 N1
 '@T6G_MB_LIB.T6G(SCH_1):PAGE329_I102@PURE_QUANTA.CONN160_10131762101LF(CHIPS)':
 'N1': CDS_PINID='N1';
NODE_NAME     J112 N3
 '@T6G_MB_LIB.T6G(SCH_1):PAGE329_I102@PURE_QUANTA.CONN160_10131762101LF(CHIPS)':
 'N3': CDS_PINID='N3';
NODE_NAME     J112 P2
 '@T6G_MB_LIB.T6G(SCH_1):PAGE329_I102@PURE_QUANTA.CONN160_10131762101LF(CHIPS)':
 'P2': CDS_PINID='P2';
NODE_NAME     J112 P4
 '@T6G_MB_LIB.T6G(SCH_1):PAGE329_I102@PURE_QUANTA.CONN160_10131762101LF(CHIPS)':
 'P4': CDS_PINID='P4';
NODE_NAME     J112 Q1
 '@T6G_MB_LIB.T6G(SCH_1):PAGE329_I102@PURE_QUANTA.CONN160_10131762101LF(CHIPS)':
 'Q1': CDS_PINID='Q1';
NODE_NAME     J112 Q3
 '@T6G_MB_LIB.T6G(SCH_1):PAGE329_I102@PURE_QUANTA.CONN160_10131762101LF(CHIPS)':
 'Q3': CDS_PINID='Q3';
NODE_NAME     J112 S2
 '@T6G_MB_LIB.T6G(SCH_1):PAGE329_I102@PURE_QUANTA.CONN160_10131762101LF(CHIPS)':
 'S2': CDS_PINID='S2';
NODE_NAME     J112 S4
 '@T6G_MB_LIB.T6G(SCH_1):PAGE329_I102@PURE_QUANTA.CONN160_10131762101LF(CHIPS)':
 'S4': CDS_PINID='S4';
NODE_NAME     J112 T1
 '@T6G_MB_LIB.T6G(SCH_1):PAGE329_I102@PURE_QUANTA.CONN160_10131762101LF(CHIPS)':
 'T1': CDS_PINID='T1';
NODE_NAME     J112 T3
 '@T6G_MB_LIB.T6G(SCH_1):PAGE329_I102@PURE_QUANTA.CONN160_10131762101LF(CHIPS)':
 'T3': CDS_PINID='T3';
NODE_NAME     U11 4
 '@T6G_MB_LIB.T6G(SCH_1):PAGE387_I3@PURE_QUANTA.M24M02DRMN6TP(CHIPS)':
 'VSS': CDS_PINID='VSS';
NODE_NAME     U11 7
 '@T6G_MB_LIB.T6G(SCH_1):PAGE387_I3@PURE_QUANTA.M24M02DRMN6TP(CHIPS)':
 'WC_N': CDS_PINID='WC_N';
NODE_NAME     U15 4
 '@T6G_MB_LIB.T6G(SCH_1):PAGE410_I5@PURE_QUANTA.M24M02DRMN6TP(CHIPS)':
 'VSS': CDS_PINID='VSS';
NODE_NAME     U15 7
 '@T6G_MB_LIB.T6G(SCH_1):PAGE410_I5@PURE_QUANTA.M24M02DRMN6TP(CHIPS)':
 'WC_N': CDS_PINID='WC_N';
NODE_NAME     U16 4
 '@T6G_MB_LIB.T6G(SCH_1):PAGE421_I5@PURE_QUANTA.M24M02DRMN6TP(CHIPS)':
 'VSS': CDS_PINID='VSS';
NODE_NAME     U16 7
 '@T6G_MB_LIB.T6G(SCH_1):PAGE421_I5@PURE_QUANTA.M24M02DRMN6TP(CHIPS)':
 'WC_N': CDS_PINID='WC_N';
NODE_NAME     U17 4
 '@T6G_MB_LIB.T6G(SCH_1):PAGE432_I5@PURE_QUANTA.M24M02DRMN6TP(CHIPS)':
 'VSS': CDS_PINID='VSS';
NODE_NAME     U17 7
 '@T6G_MB_LIB.T6G(SCH_1):PAGE432_I5@PURE_QUANTA.M24M02DRMN6TP(CHIPS)':
 'WC_N': CDS_PINID='WC_N';
NODE_NAME     U12 4
 '@T6G_MB_LIB.T6G(SCH_1):PAGE399_I5@PURE_QUANTA.M24M02DRMN6TP(CHIPS)':
 'VSS': CDS_PINID='VSS';
NODE_NAME     U12 7
 '@T6G_MB_LIB.T6G(SCH_1):PAGE399_I5@PURE_QUANTA.M24M02DRMN6TP(CHIPS)':
 'WC_N': CDS_PINID='WC_N';
NODE_NAME     U19 4
 '@T6G_MB_LIB.T6G(SCH_1):PAGE442_I5@PURE_QUANTA.M24M02DRMN6TP(CHIPS)':
 'VSS': CDS_PINID='VSS';
NODE_NAME     U19 7
 '@T6G_MB_LIB.T6G(SCH_1):PAGE442_I5@PURE_QUANTA.M24M02DRMN6TP(CHIPS)':
 'WC_N': CDS_PINID='WC_N';
NODE_NAME     U20 4
 '@T6G_MB_LIB.T6G(SCH_1):PAGE453_I5@PURE_QUANTA.M24M02DRMN6TP(CHIPS)':
 'VSS': CDS_PINID='VSS';
NODE_NAME     U20 7
 '@T6G_MB_LIB.T6G(SCH_1):PAGE453_I5@PURE_QUANTA.M24M02DRMN6TP(CHIPS)':
 'WC_N': CDS_PINID='WC_N';
NODE_NAME     U21 4
 '@T6G_MB_LIB.T6G(SCH_1):PAGE464_I5@PURE_QUANTA.M24M02DRMN6TP(CHIPS)':
 'VSS': CDS_PINID='VSS';
NODE_NAME     U21 7
 '@T6G_MB_LIB.T6G(SCH_1):PAGE464_I5@PURE_QUANTA.M24M02DRMN6TP(CHIPS)':
 'WC_N': CDS_PINID='WC_N';
NODE_NAME     C114 2
 '@T6G_MB_LIB.T6G(SCH_1):PAGE398_I4@PURE_QUANTA.Q_CAP(CHIPS)':
 'B': CDS_PINID='B';
NODE_NAME     C117 2
 '@T6G_MB_LIB.T6G(SCH_1):PAGE398_I5@PURE_QUANTA.Q_CAP(CHIPS)':
 'B': CDS_PINID='B';
NODE_NAME     C121 2
 '@T6G_MB_LIB.T6G(SCH_1):PAGE398_I7@PURE_QUANTA.Q_CAP(CHIPS)':
 'B': CDS_PINID='B';
NODE_NAME     C126 2
 '@T6G_MB_LIB.T6G(SCH_1):PAGE398_I9@PURE_QUANTA.Q_CAP(CHIPS)':
 'B': CDS_PINID='B';
NODE_NAME     C113 2
 '@T6G_MB_LIB.T6G(SCH_1):PAGE398_I12@PURE_QUANTA.Q_CAP(CHIPS)':
 'B': CDS_PINID='B';
NODE_NAME     C118 2
 '@T6G_MB_LIB.T6G(SCH_1):PAGE398_I14@PURE_QUANTA.Q_CAP(CHIPS)':
 'B': CDS_PINID='B';
NODE_NAME     C122 2
 '@T6G_MB_LIB.T6G(SCH_1):PAGE398_I15@PURE_QUANTA.Q_CAP(CHIPS)':
 'B': CDS_PINID='B';
NODE_NAME     PC6500 2
 '@T6G_MB_LIB.T6G(SCH_1):PAGE469_I4@PURE_QUANTA.Q_CAP(CHIPS)':
 'B': CDS_PINID='B';
NODE_NAME     C6757 2
 '@T6G_MB_LIB.T6G(SCH_1):PAGE469_I5@PURE_QUANTA.Q_CAP(CHIPS)':
 'B': CDS_PINID='B';
NODE_NAME     PC6800 2
 '@T6G_MB_LIB.T6G(SCH_1):PAGE469_I6@PURE_QUANTA.Q_CAPP(CHIPS)':
 'B': CDS_PINID='B';
NODE_NAME     PC6802 2
 '@T6G_MB_LIB.T6G(SCH_1):PAGE469_I7@PURE_QUANTA.Q_CAP(CHIPS)':
 'B': CDS_PINID='B';
NODE_NAME     PC6506 2
 '@T6G_MB_LIB.T6G(SCH_1):PAGE469_I12@PURE_QUANTA.Q_CAP(CHIPS)':
 'B': CDS_PINID='B';
NODE_NAME     PC6501 2
 '@T6G_MB_LIB.T6G(SCH_1):PAGE469_I16@PURE_QUANTA.Q_CAP(CHIPS)':
 'B': CDS_PINID='B';
NODE_NAME     PC6502 2
 '@T6G_MB_LIB.T6G(SCH_1):PAGE469_I17@PURE_QUANTA.Q_CAP(CHIPS)':
 'B': CDS_PINID='B';
NODE_NAME     PC6503 2
 '@T6G_MB_LIB.T6G(SCH_1):PAGE469_I18@PURE_QUANTA.Q_CAP(CHIPS)':
 'B': CDS_PINID='B';
NODE_NAME     PR6502 2
 '@T6G_MB_LIB.T6G(SCH_1):PAGE469_I20@PURE_QUANTA.Q_RES(CHIPS)':
 'B': CDS_PINID='B';
NODE_NAME     PR6500 1
 '@T6G_MB_LIB.T6G(SCH_1):PAGE469_I21@PURE_QUANTA.Q_RES(CHIPS)':
 'A': CDS_PINID='A';
NODE_NAME     PC6504 2
 '@T6G_MB_LIB.T6G(SCH_1):PAGE469_I22@PURE_QUANTA.Q_CAP(CHIPS)':
 'B': CDS_PINID='B';
NODE_NAME     PC6505 2
 '@T6G_MB_LIB.T6G(SCH_1):PAGE469_I23@PURE_QUANTA.Q_CAP(CHIPS)':
 'B': CDS_PINID='B';
NODE_NAME     PC6518 2
 '@T6G_MB_LIB.T6G(SCH_1):PAGE469_I26@PURE_QUANTA.Q_CAP(CHIPS)':
 'B': CDS_PINID='B';
NODE_NAME     PR6507 2
 '@T6G_MB_LIB.T6G(SCH_1):PAGE469_I33@PURE_QUANTA.Q_RES(CHIPS)':
 'B': CDS_PINID='B';
NODE_NAME     PC6508 2
 '@T6G_MB_LIB.T6G(SCH_1):PAGE469_I38@PURE_QUANTA.Q_CAP(CHIPS)':
 'B': CDS_PINID='B';
NODE_NAME     PC6509 2
 '@T6G_MB_LIB.T6G(SCH_1):PAGE469_I39@PURE_QUANTA.Q_CAP(CHIPS)':
 'B': CDS_PINID='B';
NODE_NAME     PC6510 2
 '@T6G_MB_LIB.T6G(SCH_1):PAGE469_I40@PURE_QUANTA.Q_CAP(CHIPS)':
 'B': CDS_PINID='B';
NODE_NAME     C6758 2
 '@T6G_MB_LIB.T6G(SCH_1):PAGE469_I42@PURE_QUANTA.Q_CAP(CHIPS)':
 'B': CDS_PINID='B';
NODE_NAME     PC6511 2
 '@T6G_MB_LIB.T6G(SCH_1):PAGE469_I44@PURE_QUANTA.Q_CAP(CHIPS)':
 'B': CDS_PINID='B';
NODE_NAME     PC6513 2
 '@T6G_MB_LIB.T6G(SCH_1):PAGE469_I46@PURE_QUANTA.Q_CAPP(CHIPS)':
 'B': CDS_PINID='B';
NODE_NAME     PC6805 2
 '@T6G_MB_LIB.T6G(SCH_1):PAGE469_I48@PURE_QUANTA.Q_CAPP(CHIPS)':
 'B': CDS_PINID='B';
NODE_NAME     PC6514 2
 '@T6G_MB_LIB.T6G(SCH_1):PAGE469_I49@PURE_QUANTA.Q_CAP(CHIPS)':
 'B': CDS_PINID='B';
NODE_NAME     PU6500 2
 '@T6G_MB_LIB.T6G(SCH_1):PAGE469_I51@PURE_QUANTA.MPQ8633BGLEC838Z(CHIPS)':
 'AGND': CDS_PINID='AGND';
NODE_NAME     PU6500 11_18
 '@T6G_MB_LIB.T6G(SCH_1):PAGE469_I51@PURE_QUANTA.MPQ8633BGLEC838Z(CHIPS)':
 'PGND': CDS_PINID='PGND';
NODE_NAME     PU6500 6
 '@T6G_MB_LIB.T6G(SCH_1):PAGE469_I51@PURE_QUANTA.MPQ8633BGLEC838Z(CHIPS)':
 'RGND': CDS_PINID='RGND';
NODE_NAME     PC6519 2
 '@T6G_MB_LIB.T6G(SCH_1):PAGE470_I3@PURE_QUANTA.Q_CAP(CHIPS)':
 'B': CDS_PINID='B';
NODE_NAME     C105 2
 '@T6G_MB_LIB.T6G(SCH_1):PAGE470_I5@PURE_QUANTA.Q_CAP(CHIPS)':
 'B': CDS_PINID='B';
NODE_NAME     PC6801 2
 '@T6G_MB_LIB.T6G(SCH_1):PAGE470_I6@PURE_QUANTA.Q_CAPP(CHIPS)':
 'B': CDS_PINID='B';
NODE_NAME     PC6803 2
 '@T6G_MB_LIB.T6G(SCH_1):PAGE470_I7@PURE_QUANTA.Q_CAP(CHIPS)':
 'B': CDS_PINID='B';
NODE_NAME     PC6525 2
 '@T6G_MB_LIB.T6G(SCH_1):PAGE470_I12@PURE_QUANTA.Q_CAP(CHIPS)':
 'B': CDS_PINID='B';
NODE_NAME     PC6520 2
 '@T6G_MB_LIB.T6G(SCH_1):PAGE470_I16@PURE_QUANTA.Q_CAP(CHIPS)':
 'B': CDS_PINID='B';
NODE_NAME     PC6521 2
 '@T6G_MB_LIB.T6G(SCH_1):PAGE470_I17@PURE_QUANTA.Q_CAP(CHIPS)':
 'B': CDS_PINID='B';
NODE_NAME     PC6522 2
 '@T6G_MB_LIB.T6G(SCH_1):PAGE470_I18@PURE_QUANTA.Q_CAP(CHIPS)':
 'B': CDS_PINID='B';
NODE_NAME     PR6522 2
 '@T6G_MB_LIB.T6G(SCH_1):PAGE470_I20@PURE_QUANTA.Q_RES(CHIPS)':
 'B': CDS_PINID='B';
NODE_NAME     PR6520 1
 '@T6G_MB_LIB.T6G(SCH_1):PAGE470_I21@PURE_QUANTA.Q_RES(CHIPS)':
 'A': CDS_PINID='A';
NODE_NAME     PC6523 2
 '@T6G_MB_LIB.T6G(SCH_1):PAGE470_I22@PURE_QUANTA.Q_CAP(CHIPS)':
 'B': CDS_PINID='B';
NODE_NAME     PC6524 2
 '@T6G_MB_LIB.T6G(SCH_1):PAGE470_I23@PURE_QUANTA.Q_CAP(CHIPS)':
 'B': CDS_PINID='B';
NODE_NAME     PC6537 2
 '@T6G_MB_LIB.T6G(SCH_1):PAGE470_I25@PURE_QUANTA.Q_CAP(CHIPS)':
 'B': CDS_PINID='B';
NODE_NAME     PR6526 2
 '@T6G_MB_LIB.T6G(SCH_1):PAGE470_I32@PURE_QUANTA.Q_RES(CHIPS)':
 'B': CDS_PINID='B';
NODE_NAME     PC6527 2
 '@T6G_MB_LIB.T6G(SCH_1):PAGE470_I38@PURE_QUANTA.Q_CAP(CHIPS)':
 'B': CDS_PINID='B';
NODE_NAME     C109 2
 '@T6G_MB_LIB.T6G(SCH_1):PAGE470_I39@PURE_QUANTA.Q_CAP(CHIPS)':
 'B': CDS_PINID='B';
NODE_NAME     PC6528 2
 '@T6G_MB_LIB.T6G(SCH_1):PAGE470_I41@PURE_QUANTA.Q_CAP(CHIPS)':
 'B': CDS_PINID='B';
NODE_NAME     PC6529 2
 '@T6G_MB_LIB.T6G(SCH_1):PAGE470_I42@PURE_QUANTA.Q_CAP(CHIPS)':
 'B': CDS_PINID='B';
NODE_NAME     PC6530 2
 '@T6G_MB_LIB.T6G(SCH_1):PAGE470_I44@PURE_QUANTA.Q_CAP(CHIPS)':
 'B': CDS_PINID='B';
NODE_NAME     PC6531 2
 '@T6G_MB_LIB.T6G(SCH_1):PAGE470_I45@PURE_QUANTA.Q_CAP(CHIPS)':
 'B': CDS_PINID='B';
NODE_NAME     PC6532 2
 '@T6G_MB_LIB.T6G(SCH_1):PAGE470_I46@PURE_QUANTA.Q_CAPP(CHIPS)':
 'B': CDS_PINID='B';
NODE_NAME     PC6804 2
 '@T6G_MB_LIB.T6G(SCH_1):PAGE470_I47@PURE_QUANTA.Q_CAPP(CHIPS)':
 'B': CDS_PINID='B';
NODE_NAME     PC6533 2
 '@T6G_MB_LIB.T6G(SCH_1):PAGE470_I49@PURE_QUANTA.Q_CAP(CHIPS)':
 'B': CDS_PINID='B';
NODE_NAME     PU6501 2
 '@T6G_MB_LIB.T6G(SCH_1):PAGE470_I51@PURE_QUANTA.MPQ8633BGLEC838Z(CHIPS)':
 'AGND': CDS_PINID='AGND';
NODE_NAME     PU6501 11_18
 '@T6G_MB_LIB.T6G(SCH_1):PAGE470_I51@PURE_QUANTA.MPQ8633BGLEC838Z(CHIPS)':
 'PGND': CDS_PINID='PGND';
NODE_NAME     PU6501 6
 '@T6G_MB_LIB.T6G(SCH_1):PAGE470_I51@PURE_QUANTA.MPQ8633BGLEC838Z(CHIPS)':
 'RGND': CDS_PINID='RGND';
NODE_NAME     PC6512 2
 '@T6G_MB_LIB.T6G(SCH_1):PAGE469_I52@PURE_QUANTA.Q_CAP(CHIPS)':
 'B': CDS_PINID='B';
NODE_NAME     PR6532 2
 '@T6G_MB_LIB.T6G(SCH_1):PAGE475_I32@PURE_QUANTA.Q_RES(CHIPS)':
 'B': CDS_PINID='B';
NODE_NAME     PU6502 31
 '@T6G_MB_LIB.T6G(SCH_1):PAGE475_I42@PURE_QUANTA.ISL69260IRAZT(CHIPS)':
 'RGND1': CDS_PINID='RGND1';
NODE_NAME     PU6502 TH
 '@T6G_MB_LIB.T6G(SCH_1):PAGE475_I42@PURE_QUANTA.ISL69260IRAZT(CHIPS)':
 'TH_GND': CDS_PINID='TH_GND';
NODE_NAME     PU6502 32
 '@T6G_MB_LIB.T6G(SCH_1):PAGE475_I42@PURE_QUANTA.ISL69260IRAZT(CHIPS)':
 'VSEN1': CDS_PINID='VSEN1';
NODE_NAME     C101 2
 '@T6G_MB_LIB.T6G(SCH_1):PAGE475_I118@PURE_QUANTA.Q_CAP(CHIPS)':
 'B': CDS_PINID='B';
NODE_NAME     PC6602 2
 '@T6G_MB_LIB.T6G(SCH_1):PAGE475_I123@PURE_QUANTA.Q_CAP(CHIPS)':
 'B': CDS_PINID='B';
NODE_NAME     PR6607 2
 '@T6G_MB_LIB.T6G(SCH_1):PAGE475_I125@PURE_QUANTA.Q_RES(CHIPS)':
 'B': CDS_PINID='B';
NODE_NAME     PC6604 2
 '@T6G_MB_LIB.T6G(SCH_1):PAGE475_I132@PURE_QUANTA.Q_CAP(CHIPS)':
 'B': CDS_PINID='B';
NODE_NAME     PR6814 2
 '@T6G_MB_LIB.T6G(SCH_1):PAGE475_I138@PURE_QUANTA.Q_RES(CHIPS)':
 'B': CDS_PINID='B';
NODE_NAME     PC6603 2
 '@T6G_MB_LIB.T6G(SCH_1):PAGE475_I144@PURE_QUANTA.Q_CAP(CHIPS)':
 'B': CDS_PINID='B';
NODE_NAME     PC6606 2
 '@T6G_MB_LIB.T6G(SCH_1):PAGE475_I145@PURE_QUANTA.Q_CAP(CHIPS)':
 'B': CDS_PINID='B';
NODE_NAME     PC6605 2
 '@T6G_MB_LIB.T6G(SCH_1):PAGE475_I146@PURE_QUANTA.Q_CAP(CHIPS)':
 'B': CDS_PINID='B';
NODE_NAME     PC6607 2
 '@T6G_MB_LIB.T6G(SCH_1):PAGE475_I148@PURE_QUANTA.Q_CAP(CHIPS)':
 'B': CDS_PINID='B';
NODE_NAME     PR6605 2
 '@T6G_MB_LIB.T6G(SCH_1):PAGE475_I150@PURE_QUANTA.Q_RES(CHIPS)':
 'B': CDS_PINID='B';
NODE_NAME     PC6601 2
 '@T6G_MB_LIB.T6G(SCH_1):PAGE475_I151@PURE_QUANTA.Q_CAP(CHIPS)':
 'B': CDS_PINID='B';
NODE_NAME     R6801 1
 '@T6G_MB_LIB.T6G(SCH_1):PAGE475_I161@PURE_QUANTA.Q_RES(CHIPS)':
 'A': CDS_PINID='A';
NODE_NAME     PR6810 2
 '@T6G_MB_LIB.T6G(SCH_1):PAGE475_I165@PURE_QUANTA.Q_RES(CHIPS)':
 'B': CDS_PINID='B';
NODE_NAME     PR6819 2
 '@T6G_MB_LIB.T6G(SCH_1):PAGE475_I168@PURE_QUANTA.Q_RES(CHIPS)':
 'B': CDS_PINID='B';
NODE_NAME     PR6603 1
 '@T6G_MB_LIB.T6G(SCH_1):PAGE475_I183@PURE_QUANTA.Q_RES(CHIPS)':
 'A': CDS_PINID='A';
NODE_NAME     PR6609 2
 '@T6G_MB_LIB.T6G(SCH_1):PAGE475_I188@PURE_QUANTA.Q_RES(CHIPS)':
 'B': CDS_PINID='B';
NODE_NAME     PR6610 2
 '@T6G_MB_LIB.T6G(SCH_1):PAGE475_I190@PURE_QUANTA.Q_RES(CHIPS)':
 'B': CDS_PINID='B';
NODE_NAME     PR6611 2
 '@T6G_MB_LIB.T6G(SCH_1):PAGE475_I191@PURE_QUANTA.Q_RES(CHIPS)':
 'B': CDS_PINID='B';
NODE_NAME     PR6612 2
 '@T6G_MB_LIB.T6G(SCH_1):PAGE475_I192@PURE_QUANTA.Q_RES(CHIPS)':
 'B': CDS_PINID='B';
NODE_NAME     PR6613 2
 '@T6G_MB_LIB.T6G(SCH_1):PAGE475_I193@PURE_QUANTA.Q_RES(CHIPS)':
 'B': CDS_PINID='B';
NODE_NAME     PR6614 2
 '@T6G_MB_LIB.T6G(SCH_1):PAGE475_I198@PURE_QUANTA.Q_RES(CHIPS)':
 'B': CDS_PINID='B';
NODE_NAME     PR6618 2
 '@T6G_MB_LIB.T6G(SCH_1):PAGE475_I204@PURE_QUANTA.Q_RES(CHIPS)':
 'B': CDS_PINID='B';
NODE_NAME     PC6555_1 2
 '@T6G_MB_LIB.T6G(SCH_1):PAGE476_I6@PURE_QUANTA.Q_CAP(CHIPS)':
 'B': CDS_PINID='B';
NODE_NAME     PC6558_1 2
 '@T6G_MB_LIB.T6G(SCH_1):PAGE476_I21@PURE_QUANTA.Q_CAP(CHIPS)':
 'B': CDS_PINID='B';
NODE_NAME     PC6557_1 2
 '@T6G_MB_LIB.T6G(SCH_1):PAGE476_I24@PURE_QUANTA.Q_CAP(CHIPS)':
 'B': CDS_PINID='B';
NODE_NAME     PC6556_1 2
 '@T6G_MB_LIB.T6G(SCH_1):PAGE476_I27@PURE_QUANTA.Q_CAP(CHIPS)':
 'B': CDS_PINID='B';
NODE_NAME     PC6554_1 2
 '@T6G_MB_LIB.T6G(SCH_1):PAGE476_I29@PURE_QUANTA.Q_CAP(CHIPS)':
 'B': CDS_PINID='B';
NODE_NAME     PC6565 2
 '@T6G_MB_LIB.T6G(SCH_1):PAGE476_I33@PURE_QUANTA.Q_CAP(CHIPS)':
 'B': CDS_PINID='B';
NODE_NAME     PC6550_09P0_1 2
 '@T6G_MB_LIB.T6G(SCH_1):PAGE476_I47@PURE_QUANTA.Q_CAP(CHIPS)':
 'B': CDS_PINID='B';
NODE_NAME     PC6552 2
 '@T6G_MB_LIB.T6G(SCH_1):PAGE476_I48@PURE_QUANTA.Q_CAP(CHIPS)':
 'B': CDS_PINID='B';
NODE_NAME     PU6503 2
 '@T6G_MB_LIB.T6G(SCH_1):PAGE476_I53@PURE_QUANTA.ISL99390FRZTR5935(CHIPS)':
 'AGND': CDS_PINID='AGND';
NODE_NAME     PU6503 5
 '@T6G_MB_LIB.T6G(SCH_1):PAGE476_I53@PURE_QUANTA.ISL99390FRZTR5935(CHIPS)':
 'PGND1': CDS_PINID='PGND1';
NODE_NAME     PU6503 7_9-20_24
 '@T6G_MB_LIB.T6G(SCH_1):PAGE476_I53@PURE_QUANTA.ISL99390FRZTR5935(CHIPS)':
 'PGND2': CDS_PINID='PGND2';
NODE_NAME     PU6503 40
 '@T6G_MB_LIB.T6G(SCH_1):PAGE476_I53@PURE_QUANTA.ISL99390FRZTR5935(CHIPS)':
 'PGND3': CDS_PINID='PGND3';
NODE_NAME     PC6553_1 2
 '@T6G_MB_LIB.T6G(SCH_1):PAGE476_I68@PURE_QUANTA.Q_CAP(CHIPS)':
 'B': CDS_PINID='B';
NODE_NAME     PR6557 2
 '@T6G_MB_LIB.T6G(SCH_1):PAGE476_I187@PURE_QUANTA.Q_RES(CHIPS)':
 'B': CDS_PINID='B';
NODE_NAME     PC6566_1 2
 '@T6G_MB_LIB.T6G(SCH_1):PAGE476_I202@PURE_QUANTA.Q_CAP(CHIPS)':
 'B': CDS_PINID='B';
NODE_NAME     PC6561 2
 '@T6G_MB_LIB.T6G(SCH_1):PAGE476_I209@PURE_QUANTA.Q_CAPP(CHIPS)':
 'B': CDS_PINID='B';
NODE_NAME     PC6559_1 2
 '@T6G_MB_LIB.T6G(SCH_1):PAGE476_I210@PURE_QUANTA.Q_CAP(CHIPS)':
 'B': CDS_PINID='B';
NODE_NAME     PC6816 2
 '@T6G_MB_LIB.T6G(SCH_1):PAGE476_I216@PURE_QUANTA.Q_CAP(CHIPS)':
 'B': CDS_PINID='B';
NODE_NAME     PC6560 2
 '@T6G_MB_LIB.T6G(SCH_1):PAGE476_I217@PURE_QUANTA.Q_CAP(CHIPS)':
 'B': CDS_PINID='B';
NODE_NAME     PR6553 2
 '@T6G_MB_LIB.T6G(SCH_1):PAGE476_I220@PURE_QUANTA.Q_RES(CHIPS)':
 'B': CDS_PINID='B';
NODE_NAME     PC6572 2
 '@T6G_MB_LIB.T6G(SCH_1):PAGE476_I222@PURE_QUANTA.Q_CAPP(CHIPS)':
 'B': CDS_PINID='B';
NODE_NAME     PC6567_1 2
 '@T6G_MB_LIB.T6G(SCH_1):PAGE476_I223@PURE_QUANTA.Q_CAP(CHIPS)':
 'B': CDS_PINID='B';
NODE_NAME     PC6568 2
 '@T6G_MB_LIB.T6G(SCH_1):PAGE476_I224@PURE_QUANTA.Q_CAPP(CHIPS)':
 'B': CDS_PINID='B';
NODE_NAME     PC6569 2
 '@T6G_MB_LIB.T6G(SCH_1):PAGE476_I225@PURE_QUANTA.Q_CAPP(CHIPS)':
 'B': CDS_PINID='B';
NODE_NAME     PC6570 2
 '@T6G_MB_LIB.T6G(SCH_1):PAGE476_I226@PURE_QUANTA.Q_CAPP(CHIPS)':
 'B': CDS_PINID='B';
NODE_NAME     PC6571 2
 '@T6G_MB_LIB.T6G(SCH_1):PAGE476_I227@PURE_QUANTA.Q_CAPP(CHIPS)':
 'B': CDS_PINID='B';
NODE_NAME     PC6810 2
 '@T6G_MB_LIB.T6G(SCH_1):PAGE476_I231@PURE_QUANTA.Q_CAPP(CHIPS)':
 'B': CDS_PINID='B';
NODE_NAME     PC6817 2
 '@T6G_MB_LIB.T6G(SCH_1):PAGE476_I232@PURE_QUANTA.Q_CAP(CHIPS)':
 'B': CDS_PINID='B';
NODE_NAME     PC6574 2
 '@T6G_MB_LIB.T6G(SCH_1):PAGE476_I236@PURE_QUANTA.Q_CAPP(CHIPS)':
 'B': CDS_PINID='B';
NODE_NAME     PC6573 2
 '@T6G_MB_LIB.T6G(SCH_1):PAGE476_I238@PURE_QUANTA.Q_CAPP(CHIPS)':
 'B': CDS_PINID='B';
NODE_NAME     PC534 2
 '@T6G_MB_LIB.T6G(SCH_1):PAGE476_I239@PURE_QUANTA.Q_CAPP(CHIPS)':
 'B': CDS_PINID='B';
NODE_NAME     PC6583 2
 '@T6G_MB_LIB.T6G(SCH_1):PAGE476_I241@PURE_QUANTA.Q_CAP(CHIPS)':
 'B': CDS_PINID='B';
NODE_NAME     PC6582_2 2
 '@T6G_MB_LIB.T6G(SCH_1):PAGE476_I242@PURE_QUANTA.Q_CAP(CHIPS)':
 'B': CDS_PINID='B';
NODE_NAME     PC6581_2 2
 '@T6G_MB_LIB.T6G(SCH_1):PAGE476_I243@PURE_QUANTA.Q_CAP(CHIPS)':
 'B': CDS_PINID='B';
NODE_NAME     PC6580_2 2
 '@T6G_MB_LIB.T6G(SCH_1):PAGE476_I244@PURE_QUANTA.Q_CAP(CHIPS)':
 'B': CDS_PINID='B';
NODE_NAME     PC6579_2 2
 '@T6G_MB_LIB.T6G(SCH_1):PAGE476_I245@PURE_QUANTA.Q_CAP(CHIPS)':
 'B': CDS_PINID='B';
NODE_NAME     PC6811 2
 '@T6G_MB_LIB.T6G(SCH_1):PAGE476_I247@PURE_QUANTA.Q_CAPP(CHIPS)':
 'B': CDS_PINID='B';
NODE_NAME     PC6812 2
 '@T6G_MB_LIB.T6G(SCH_1):PAGE476_I248@PURE_QUANTA.Q_CAPP(CHIPS)':
 'B': CDS_PINID='B';
NODE_NAME     PC6587_2 2
 '@T6G_MB_LIB.T6G(SCH_1):PAGE476_I250@PURE_QUANTA.Q_CAP(CHIPS)':
 'B': CDS_PINID='B';
NODE_NAME     PC6586_2 2
 '@T6G_MB_LIB.T6G(SCH_1):PAGE476_I251@PURE_QUANTA.Q_CAP(CHIPS)':
 'B': CDS_PINID='B';
NODE_NAME     PC6806 2
 '@T6G_MB_LIB.T6G(SCH_1):PAGE476_I255@PURE_QUANTA.Q_CAP(CHIPS)':
 'B': CDS_PINID='B';
NODE_NAME     PC6577_2 2
 '@T6G_MB_LIB.T6G(SCH_1):PAGE476_I258@PURE_QUANTA.Q_CAP(CHIPS)':
 'B': CDS_PINID='B';
NODE_NAME     PC6578_2 2
 '@T6G_MB_LIB.T6G(SCH_1):PAGE476_I259@PURE_QUANTA.Q_CAP(CHIPS)':
 'B': CDS_PINID='B';
NODE_NAME     PC6551_09P0_2 2
 '@T6G_MB_LIB.T6G(SCH_1):PAGE476_I267@PURE_QUANTA.Q_CAP(CHIPS)':
 'B': CDS_PINID='B';
NODE_NAME     PU6504 2
 '@T6G_MB_LIB.T6G(SCH_1):PAGE476_I270@PURE_QUANTA.ISL99390FRZTR5935(CHIPS)':
 'AGND': CDS_PINID='AGND';
NODE_NAME     PU6504 5
 '@T6G_MB_LIB.T6G(SCH_1):PAGE476_I270@PURE_QUANTA.ISL99390FRZTR5935(CHIPS)':
 'PGND1': CDS_PINID='PGND1';
NODE_NAME     PU6504 7_9-20_24
 '@T6G_MB_LIB.T6G(SCH_1):PAGE476_I270@PURE_QUANTA.ISL99390FRZTR5935(CHIPS)':
 'PGND2': CDS_PINID='PGND2';
NODE_NAME     PU6504 40
 '@T6G_MB_LIB.T6G(SCH_1):PAGE476_I270@PURE_QUANTA.ISL99390FRZTR5935(CHIPS)':
 'PGND3': CDS_PINID='PGND3';
NODE_NAME     PC6575 2
 '@T6G_MB_LIB.T6G(SCH_1):PAGE476_I271@PURE_QUANTA.Q_CAP(CHIPS)':
 'B': CDS_PINID='B';
NODE_NAME     PR6561 2
 '@T6G_MB_LIB.T6G(SCH_1):PAGE476_I276@PURE_QUANTA.Q_RES(CHIPS)':
 'B': CDS_PINID='B';
NODE_NAME     PC6576 2
 '@T6G_MB_LIB.T6G(SCH_1):PAGE476_I281@PURE_QUANTA.Q_CAP(CHIPS)':
 'B': CDS_PINID='B';
NODE_NAME     PR6555 2
 '@T6G_MB_LIB.T6G(SCH_1):PAGE476_I283@PURE_QUANTA.Q_RES(CHIPS)':
 'B': CDS_PINID='B';
NODE_NAME     PR6563 2
 '@T6G_MB_LIB.T6G(SCH_1):PAGE476_I286@PURE_QUANTA.Q_RES(CHIPS)':
 'B': CDS_PINID='B';
NODE_NAME     PC6562 2
 '@T6G_MB_LIB.T6G(SCH_1):PAGE476_I291@PURE_QUANTA.Q_CAP(CHIPS)':
 'B': CDS_PINID='B';
NODE_NAME     R6800 1
 '@T6G_MB_LIB.T6G(SCH_1):PAGE477_I2@PURE_QUANTA.Q_RES(CHIPS)':
 'A': CDS_PINID='A';
NODE_NAME     PR6821 2
 '@T6G_MB_LIB.T6G(SCH_1):PAGE477_I3@PURE_QUANTA.Q_RES(CHIPS)':
 'B': CDS_PINID='B';
NODE_NAME     PC514 2
 '@T6G_MB_LIB.T6G(SCH_1):PAGE477_I5@PURE_QUANTA.Q_CAP(CHIPS)':
 'B': CDS_PINID='B';
NODE_NAME     PR6533 1
 '@T6G_MB_LIB.T6G(SCH_1):PAGE477_I13@PURE_QUANTA.Q_RES(CHIPS)':
 'A': CDS_PINID='A';
NODE_NAME     PR6602 2
 '@T6G_MB_LIB.T6G(SCH_1):PAGE477_I22@PURE_QUANTA.Q_RES(CHIPS)':
 'B': CDS_PINID='B';
NODE_NAME     PR6811 2
 '@T6G_MB_LIB.T6G(SCH_1):PAGE477_I42@PURE_QUANTA.Q_RES(CHIPS)':
 'B': CDS_PINID='B';
NODE_NAME     PR6820 2
 '@T6G_MB_LIB.T6G(SCH_1):PAGE477_I43@PURE_QUANTA.Q_RES(CHIPS)':
 'B': CDS_PINID='B';
NODE_NAME     PR6802 2
 '@T6G_MB_LIB.T6G(SCH_1):PAGE477_I44@PURE_QUANTA.Q_RES(CHIPS)':
 'B': CDS_PINID='B';
NODE_NAME     C107 2
 '@T6G_MB_LIB.T6G(SCH_1):PAGE477_I45@PURE_QUANTA.Q_CAP(CHIPS)':
 'B': CDS_PINID='B';
NODE_NAME     PR6813 2
 '@T6G_MB_LIB.T6G(SCH_1):PAGE477_I46@PURE_QUANTA.Q_RES(CHIPS)':
 'B': CDS_PINID='B';
NODE_NAME     PC819 2
 '@T6G_MB_LIB.T6G(SCH_1):PAGE477_I48@PURE_QUANTA.Q_CAP(CHIPS)':
 'B': CDS_PINID='B';
NODE_NAME     PC523 2
 '@T6G_MB_LIB.T6G(SCH_1):PAGE477_I51@PURE_QUANTA.Q_CAP(CHIPS)':
 'B': CDS_PINID='B';
NODE_NAME     PR6548 2
 '@T6G_MB_LIB.T6G(SCH_1):PAGE477_I52@PURE_QUANTA.Q_RES(CHIPS)':
 'B': CDS_PINID='B';
NODE_NAME     PR6815 2
 '@T6G_MB_LIB.T6G(SCH_1):PAGE477_I54@PURE_QUANTA.Q_RES(CHIPS)':
 'B': CDS_PINID='B';
NODE_NAME     PR6544 2
 '@T6G_MB_LIB.T6G(SCH_1):PAGE477_I57@PURE_QUANTA.Q_RES(CHIPS)':
 'B': CDS_PINID='B';
NODE_NAME     PR6543 2
 '@T6G_MB_LIB.T6G(SCH_1):PAGE477_I58@PURE_QUANTA.Q_RES(CHIPS)':
 'B': CDS_PINID='B';
NODE_NAME     PR6542 2
 '@T6G_MB_LIB.T6G(SCH_1):PAGE477_I64@PURE_QUANTA.Q_RES(CHIPS)':
 'B': CDS_PINID='B';
NODE_NAME     PR6541 2
 '@T6G_MB_LIB.T6G(SCH_1):PAGE477_I65@PURE_QUANTA.Q_RES(CHIPS)':
 'B': CDS_PINID='B';
NODE_NAME     PR6540 2
 '@T6G_MB_LIB.T6G(SCH_1):PAGE477_I68@PURE_QUANTA.Q_RES(CHIPS)':
 'B': CDS_PINID='B';
NODE_NAME     PR6539 2
 '@T6G_MB_LIB.T6G(SCH_1):PAGE477_I69@PURE_QUANTA.Q_RES(CHIPS)':
 'B': CDS_PINID='B';
NODE_NAME     PC6546 2
 '@T6G_MB_LIB.T6G(SCH_1):PAGE477_I72@PURE_QUANTA.Q_CAP(CHIPS)':
 'B': CDS_PINID='B';
NODE_NAME     PC6545 2
 '@T6G_MB_LIB.T6G(SCH_1):PAGE477_I73@PURE_QUANTA.Q_CAP(CHIPS)':
 'B': CDS_PINID='B';
NODE_NAME     PC6543 2
 '@T6G_MB_LIB.T6G(SCH_1):PAGE477_I74@PURE_QUANTA.Q_CAP(CHIPS)':
 'B': CDS_PINID='B';
NODE_NAME     PC6544 2
 '@T6G_MB_LIB.T6G(SCH_1):PAGE477_I75@PURE_QUANTA.Q_CAP(CHIPS)':
 'B': CDS_PINID='B';
NODE_NAME     PU6510 31
 '@T6G_MB_LIB.T6G(SCH_1):PAGE477_I88@PURE_QUANTA.ISL69260IRAZT(CHIPS)':
 'RGND1': CDS_PINID='RGND1';
NODE_NAME     PU6510 TH
 '@T6G_MB_LIB.T6G(SCH_1):PAGE477_I88@PURE_QUANTA.ISL69260IRAZT(CHIPS)':
 'TH_GND': CDS_PINID='TH_GND';
NODE_NAME     PU6510 32
 '@T6G_MB_LIB.T6G(SCH_1):PAGE477_I88@PURE_QUANTA.ISL69260IRAZT(CHIPS)':
 'VSEN1': CDS_PINID='VSEN1';
NODE_NAME     PC6646 2
 '@T6G_MB_LIB.T6G(SCH_1):PAGE478_I2@PURE_QUANTA.Q_CAP(CHIPS)':
 'B': CDS_PINID='B';
NODE_NAME     PR6628 2
 '@T6G_MB_LIB.T6G(SCH_1):PAGE478_I5@PURE_QUANTA.Q_RES(CHIPS)':
 'B': CDS_PINID='B';
NODE_NAME     PC6645 2
 '@T6G_MB_LIB.T6G(SCH_1):PAGE478_I10@PURE_QUANTA.Q_CAP(CHIPS)':
 'B': CDS_PINID='B';
NODE_NAME     PU6512 2
 '@T6G_MB_LIB.T6G(SCH_1):PAGE478_I12@PURE_QUANTA.ISL99390FRZTR5935(CHIPS)':
 'AGND': CDS_PINID='AGND';
NODE_NAME     PU6512 5
 '@T6G_MB_LIB.T6G(SCH_1):PAGE478_I12@PURE_QUANTA.ISL99390FRZTR5935(CHIPS)':
 'PGND1': CDS_PINID='PGND1';
NODE_NAME     PU6512 7_9-20_24
 '@T6G_MB_LIB.T6G(SCH_1):PAGE478_I12@PURE_QUANTA.ISL99390FRZTR5935(CHIPS)':
 'PGND2': CDS_PINID='PGND2';
NODE_NAME     PU6512 40
 '@T6G_MB_LIB.T6G(SCH_1):PAGE478_I12@PURE_QUANTA.ISL99390FRZTR5935(CHIPS)':
 'PGND3': CDS_PINID='PGND3';
NODE_NAME     PC6644_09P1_2 2
 '@T6G_MB_LIB.T6G(SCH_1):PAGE478_I14@PURE_QUANTA.Q_CAP(CHIPS)':
 'B': CDS_PINID='B';
NODE_NAME     PC6634_2 2
 '@T6G_MB_LIB.T6G(SCH_1):PAGE478_I18@PURE_QUANTA.Q_CAP(CHIPS)':
 'B': CDS_PINID='B';
NODE_NAME     PC6633_2 2
 '@T6G_MB_LIB.T6G(SCH_1):PAGE478_I21@PURE_QUANTA.Q_CAP(CHIPS)':
 'B': CDS_PINID='B';
NODE_NAME     PC6807 2
 '@T6G_MB_LIB.T6G(SCH_1):PAGE478_I23@PURE_QUANTA.Q_CAP(CHIPS)':
 'B': CDS_PINID='B';
NODE_NAME     PC6635_2 2
 '@T6G_MB_LIB.T6G(SCH_1):PAGE478_I25@PURE_QUANTA.Q_CAP(CHIPS)':
 'B': CDS_PINID='B';
NODE_NAME     PC6636_2 2
 '@T6G_MB_LIB.T6G(SCH_1):PAGE478_I28@PURE_QUANTA.Q_CAP(CHIPS)':
 'B': CDS_PINID='B';
NODE_NAME     PC6642_2 2
 '@T6G_MB_LIB.T6G(SCH_1):PAGE478_I29@PURE_QUANTA.Q_CAP(CHIPS)':
 'B': CDS_PINID='B';
NODE_NAME     PC6643_2 2
 '@T6G_MB_LIB.T6G(SCH_1):PAGE478_I30@PURE_QUANTA.Q_CAP(CHIPS)':
 'B': CDS_PINID='B';
NODE_NAME     PC6813 2
 '@T6G_MB_LIB.T6G(SCH_1):PAGE478_I31@PURE_QUANTA.Q_CAPP(CHIPS)':
 'B': CDS_PINID='B';
NODE_NAME     PC6814 2
 '@T6G_MB_LIB.T6G(SCH_1):PAGE478_I32@PURE_QUANTA.Q_CAPP(CHIPS)':
 'B': CDS_PINID='B';
NODE_NAME     PC6637_2 2
 '@T6G_MB_LIB.T6G(SCH_1):PAGE478_I35@PURE_QUANTA.Q_CAP(CHIPS)':
 'B': CDS_PINID='B';
NODE_NAME     PC6638_2 2
 '@T6G_MB_LIB.T6G(SCH_1):PAGE478_I36@PURE_QUANTA.Q_CAP(CHIPS)':
 'B': CDS_PINID='B';
NODE_NAME     PC6639 2
 '@T6G_MB_LIB.T6G(SCH_1):PAGE478_I38@PURE_QUANTA.Q_CAP(CHIPS)':
 'B': CDS_PINID='B';
NODE_NAME     PC6611_1 2
 '@T6G_MB_LIB.T6G(SCH_1):PAGE478_I39@PURE_QUANTA.Q_CAP(CHIPS)':
 'B': CDS_PINID='B';
NODE_NAME     PR6622 2
 '@T6G_MB_LIB.T6G(SCH_1):PAGE478_I46@PURE_QUANTA.Q_RES(CHIPS)':
 'B': CDS_PINID='B';
NODE_NAME     PU6511 2
 '@T6G_MB_LIB.T6G(SCH_1):PAGE478_I51@PURE_QUANTA.ISL99390FRZTR5935(CHIPS)':
 'AGND': CDS_PINID='AGND';
NODE_NAME     PU6511 5
 '@T6G_MB_LIB.T6G(SCH_1):PAGE478_I51@PURE_QUANTA.ISL99390FRZTR5935(CHIPS)':
 'PGND1': CDS_PINID='PGND1';
NODE_NAME     PU6511 7_9-20_24
 '@T6G_MB_LIB.T6G(SCH_1):PAGE478_I51@PURE_QUANTA.ISL99390FRZTR5935(CHIPS)':
 'PGND2': CDS_PINID='PGND2';
NODE_NAME     PU6511 40
 '@T6G_MB_LIB.T6G(SCH_1):PAGE478_I51@PURE_QUANTA.ISL99390FRZTR5935(CHIPS)':
 'PGND3': CDS_PINID='PGND3';
NODE_NAME     PC6610 2
 '@T6G_MB_LIB.T6G(SCH_1):PAGE478_I52@PURE_QUANTA.Q_CAP(CHIPS)':
 'B': CDS_PINID='B';
NODE_NAME     PC6609_09P1_1 2
 '@T6G_MB_LIB.T6G(SCH_1):PAGE478_I55@PURE_QUANTA.Q_CAP(CHIPS)':
 'B': CDS_PINID='B';
NODE_NAME     PC6613_1 2
 '@T6G_MB_LIB.T6G(SCH_1):PAGE478_I61@PURE_QUANTA.Q_CAP(CHIPS)':
 'B': CDS_PINID='B';
NODE_NAME     PC6612_1 2
 '@T6G_MB_LIB.T6G(SCH_1):PAGE478_I64@PURE_QUANTA.Q_CAP(CHIPS)':
 'B': CDS_PINID='B';
NODE_NAME     PC6623 2
 '@T6G_MB_LIB.T6G(SCH_1):PAGE478_I66@PURE_QUANTA.Q_CAP(CHIPS)':
 'B': CDS_PINID='B';
NODE_NAME     PC6624_1 2
 '@T6G_MB_LIB.T6G(SCH_1):PAGE478_I67@PURE_QUANTA.Q_CAP(CHIPS)':
 'B': CDS_PINID='B';
NODE_NAME     PC6625_1 2
 '@T6G_MB_LIB.T6G(SCH_1):PAGE478_I68@PURE_QUANTA.Q_CAP(CHIPS)':
 'B': CDS_PINID='B';
NODE_NAME     PC6626 2
 '@T6G_MB_LIB.T6G(SCH_1):PAGE478_I69@PURE_QUANTA.Q_CAPP(CHIPS)':
 'B': CDS_PINID='B';
NODE_NAME     PC6627 2
 '@T6G_MB_LIB.T6G(SCH_1):PAGE478_I70@PURE_QUANTA.Q_CAPP(CHIPS)':
 'B': CDS_PINID='B';
NODE_NAME     PC6614_1 2
 '@T6G_MB_LIB.T6G(SCH_1):PAGE478_I72@PURE_QUANTA.Q_CAP(CHIPS)':
 'B': CDS_PINID='B';
NODE_NAME     PC6615_1 2
 '@T6G_MB_LIB.T6G(SCH_1):PAGE478_I74@PURE_QUANTA.Q_CAP(CHIPS)':
 'B': CDS_PINID='B';
NODE_NAME     PC6616_1 2
 '@T6G_MB_LIB.T6G(SCH_1):PAGE478_I77@PURE_QUANTA.Q_CAP(CHIPS)':
 'B': CDS_PINID='B';
NODE_NAME     PC6617_1 2
 '@T6G_MB_LIB.T6G(SCH_1):PAGE478_I79@PURE_QUANTA.Q_CAP(CHIPS)':
 'B': CDS_PINID='B';
NODE_NAME     PC6618 2
 '@T6G_MB_LIB.T6G(SCH_1):PAGE478_I80@PURE_QUANTA.Q_CAP(CHIPS)':
 'B': CDS_PINID='B';
NODE_NAME     PC6815 2
 '@T6G_MB_LIB.T6G(SCH_1):PAGE478_I82@PURE_QUANTA.Q_CAPP(CHIPS)':
 'B': CDS_PINID='B';
NODE_NAME     PC6631 2
 '@T6G_MB_LIB.T6G(SCH_1):PAGE478_I83@PURE_QUANTA.Q_CAPP(CHIPS)':
 'B': CDS_PINID='B';
NODE_NAME     PC6632 2
 '@T6G_MB_LIB.T6G(SCH_1):PAGE478_I84@PURE_QUANTA.Q_CAPP(CHIPS)':
 'B': CDS_PINID='B';
NODE_NAME     PC6818 2
 '@T6G_MB_LIB.T6G(SCH_1):PAGE478_I86@PURE_QUANTA.Q_CAP(CHIPS)':
 'B': CDS_PINID='B';
NODE_NAME     PC473 2
 '@T6G_MB_LIB.T6G(SCH_1):PAGE478_I88@PURE_QUANTA.Q_CAPP(CHIPS)':
 'B': CDS_PINID='B';
NODE_NAME     PC6628 2
 '@T6G_MB_LIB.T6G(SCH_1):PAGE478_I93@PURE_QUANTA.Q_CAPP(CHIPS)':
 'B': CDS_PINID='B';
NODE_NAME     PC6629 2
 '@T6G_MB_LIB.T6G(SCH_1):PAGE478_I94@PURE_QUANTA.Q_CAPP(CHIPS)':
 'B': CDS_PINID='B';
NODE_NAME     PC6630 2
 '@T6G_MB_LIB.T6G(SCH_1):PAGE478_I95@PURE_QUANTA.Q_CAPP(CHIPS)':
 'B': CDS_PINID='B';
NODE_NAME     PR6625 2
 '@T6G_MB_LIB.T6G(SCH_1):PAGE478_I97@PURE_QUANTA.Q_RES(CHIPS)':
 'B': CDS_PINID='B';
NODE_NAME     PC6819 2
 '@T6G_MB_LIB.T6G(SCH_1):PAGE478_I100@PURE_QUANTA.Q_CAP(CHIPS)':
 'B': CDS_PINID='B';
NODE_NAME     PC6619 2
 '@T6G_MB_LIB.T6G(SCH_1):PAGE478_I102@PURE_QUANTA.Q_CAPP(CHIPS)':
 'B': CDS_PINID='B';
NODE_NAME     PR6624 2
 '@T6G_MB_LIB.T6G(SCH_1):PAGE478_I106@PURE_QUANTA.Q_RES(CHIPS)':
 'B': CDS_PINID='B';
NODE_NAME     PR6630 2
 '@T6G_MB_LIB.T6G(SCH_1):PAGE478_I110@PURE_QUANTA.Q_RES(CHIPS)':
 'B': CDS_PINID='B';
NODE_NAME     PC6620 2
 '@T6G_MB_LIB.T6G(SCH_1):PAGE478_I114@PURE_QUANTA.Q_CAP(CHIPS)':
 'B': CDS_PINID='B';
NODE_NAME     H2 1
 '@T6G_MB_LIB.T6G(SCH_1):PAGE212_I170@PURE_QUANTA.HOLE(CHIPS)':
 '1': CDS_PINID='\1\';
NODE_NAME     H8 1
 '@T6G_MB_LIB.T6G(SCH_1):PAGE212_I176@PURE_QUANTA.HOLE(CHIPS)':
 '1': CDS_PINID='\1\';
NODE_NAME     H10 1
 '@T6G_MB_LIB.T6G(SCH_1):PAGE212_I178@PURE_QUANTA.HOLE(CHIPS)':
 '1': CDS_PINID='\1\';
NODE_NAME     H12 1
 '@T6G_MB_LIB.T6G(SCH_1):PAGE212_I187@PURE_QUANTA.HOLE(CHIPS)':
 '1': CDS_PINID='\1\';
NODE_NAME     H5 1
 '@T6G_MB_LIB.T6G(SCH_1):PAGE212_I193@PURE_QUANTA.HOLE(CHIPS)':
 '1': CDS_PINID='\1\';
NODE_NAME     H3 1
 '@T6G_MB_LIB.T6G(SCH_1):PAGE212_I195@PURE_QUANTA.HOLE(CHIPS)':
 '1': CDS_PINID='\1\';
NODE_NAME     C123 2
 '@T6G_MB_LIB.T6G(SCH_1):PAGE398_I18@PURE_QUANTA.Q_CAP(CHIPS)':
 'B': CDS_PINID='B';
NODE_NAME     C125 2
 '@T6G_MB_LIB.T6G(SCH_1):PAGE398_I19@PURE_QUANTA.Q_CAP(CHIPS)':
 'B': CDS_PINID='B';
NODE_NAME     C119 2
 '@T6G_MB_LIB.T6G(SCH_1):PAGE398_I20@PURE_QUANTA.Q_CAP(CHIPS)':
 'B': CDS_PINID='B';
NODE_NAME     C115 2
 '@T6G_MB_LIB.T6G(SCH_1):PAGE398_I21@PURE_QUANTA.Q_CAP(CHIPS)':
 'B': CDS_PINID='B';
NODE_NAME     R6802 2
 '@T6G_MB_LIB.T6G(SCH_1):PAGE160_I68@PURE_QUANTA.Q_RES(CHIPS)':
 'B': CDS_PINID='B';
NODE_NAME     R6803 2
 '@T6G_MB_LIB.T6G(SCH_1):PAGE379_I76@PURE_QUANTA.Q_RES(CHIPS)':
 'B': CDS_PINID='B';
NODE_NAME     U6020 12
 '@T6G_MB_LIB.T6G(SCH_1):PAGE378_I1@PURE_QUANTA.TCA9548APWR(CHIPS)':
 'GND': CDS_PINID='GND';
NODE_NAME     C76 2
 '@T6G_MB_LIB.T6G(SCH_1):PAGE160_I69@PURE_QUANTA.Q_CAP(CHIPS)':
 'B': CDS_PINID='B';
NODE_NAME     C77 2
 '@T6G_MB_LIB.T6G(SCH_1):PAGE160_I70@PURE_QUANTA.Q_CAP(CHIPS)':
 'B': CDS_PINID='B';
NODE_NAME     C2328 2
 '@T6G_MB_LIB.T6G(SCH_1):PAGE160_I71@PURE_QUANTA.Q_CAP(CHIPS)':
 'B': CDS_PINID='B';
NODE_NAME     C82 2
 '@T6G_MB_LIB.T6G(SCH_1):PAGE379_I77@PURE_QUANTA.Q_CAP(CHIPS)':
 'B': CDS_PINID='B';
NODE_NAME     C83 2
 '@T6G_MB_LIB.T6G(SCH_1):PAGE379_I78@PURE_QUANTA.Q_CAP(CHIPS)':
 'B': CDS_PINID='B';
NODE_NAME     C28 2
 '@T6G_MB_LIB.T6G(SCH_1):PAGE379_I79@PURE_QUANTA.Q_CAP(CHIPS)':
 'B': CDS_PINID='B';
NODE_NAME     R629 2
 '@T6G_MB_LIB.T6G(SCH_1):PAGE408_I18@PURE_QUANTA.Q_RES(CHIPS)':
 'B': CDS_PINID='B';
NODE_NAME     R630 2
 '@T6G_MB_LIB.T6G(SCH_1):PAGE408_I19@PURE_QUANTA.Q_RES(CHIPS)':
 'B': CDS_PINID='B';
NODE_NAME     R627 2
 '@T6G_MB_LIB.T6G(SCH_1):PAGE401_I23@PURE_QUANTA.Q_RES(CHIPS)':
 'B': CDS_PINID='B';
NODE_NAME     R628 2
 '@T6G_MB_LIB.T6G(SCH_1):PAGE401_I24@PURE_QUANTA.Q_RES(CHIPS)':
 'B': CDS_PINID='B';
NODE_NAME     R711 2
 '@T6G_MB_LIB.T6G(SCH_1):PAGE400_I102@PURE_QUANTA.Q_RES(CHIPS)':
 'B': CDS_PINID='B';
NODE_NAME     R709 2
 '@T6G_MB_LIB.T6G(SCH_1):PAGE400_I103@PURE_QUANTA.Q_RES(CHIPS)':
 'B': CDS_PINID='B';
NODE_NAME     R725 2
 '@T6G_MB_LIB.T6G(SCH_1):PAGE401_I32@PURE_QUANTA.Q_RES(CHIPS)':
 'B': CDS_PINID='B';
NODE_NAME     R723 2
 '@T6G_MB_LIB.T6G(SCH_1):PAGE401_I33@PURE_QUANTA.Q_RES(CHIPS)':
 'B': CDS_PINID='B';
NODE_NAME     R719 2
 '@T6G_MB_LIB.T6G(SCH_1):PAGE401_I34@PURE_QUANTA.Q_RES(CHIPS)':
 'B': CDS_PINID='B';
NODE_NAME     R715 2
 '@T6G_MB_LIB.T6G(SCH_1):PAGE401_I35@PURE_QUANTA.Q_RES(CHIPS)':
 'B': CDS_PINID='B';
NODE_NAME     R707 2
 '@T6G_MB_LIB.T6G(SCH_1):PAGE401_I36@PURE_QUANTA.Q_RES(CHIPS)':
 'B': CDS_PINID='B';
NODE_NAME     R728 2
 '@T6G_MB_LIB.T6G(SCH_1):PAGE401_I55@PURE_QUANTA.Q_RES(CHIPS)':
 'B': CDS_PINID='B';
NODE_NAME     BT2 2
 '@T6G_MB_LIB.T6G(SCH_1):PAGE156_I86@PURE_QUANTA.CONN2_AAABAT029Y19(CHIPS)':
 '2': CDS_PINID='\2\';
NODE_NAME     U9 2
 '@T6G_MB_LIB.T6G(SCH_1):PAGE156_I91@PURE_QUANTA.TPS71715DCKR(CHIPS)':
 'GND': CDS_PINID='GND';
NODE_NAME     R1776 2
 '@T6G_MB_LIB.T6G(SCH_1):PAGE156_I94@PURE_QUANTA.Q_RES(CHIPS)':
 'B': CDS_PINID='B';
NODE_NAME     C1563 2
 '@T6G_MB_LIB.T6G(SCH_1):PAGE156_I95@PURE_QUANTA.Q_CAP(CHIPS)':
 'B': CDS_PINID='B';
NODE_NAME     Q8 1
 '@T6G_MB_LIB.T6G(SCH_1):PAGE156_I104@PURE_QUANTA.MOSFET_DUAL_6P(CHIPS)':
 'S1': CDS_PINID='S1';
NODE_NAME     Q8 4
 '@T6G_MB_LIB.T6G(SCH_1):PAGE156_I104@PURE_QUANTA.MOSFET_DUAL_6P(CHIPS)':
 'S2': CDS_PINID='S2';
NODE_NAME     C45 2
 '@T6G_MB_LIB.T6G(SCH_1):PAGE156_I107@PURE_QUANTA.Q_CAP(CHIPS)':
 'B': CDS_PINID='B';
NODE_NAME     C193 2
 '@T6G_MB_LIB.T6G(SCH_1):PAGE156_I108@PURE_QUANTA.Q_CAP(CHIPS)':
 'B': CDS_PINID='B';
NODE_NAME     C22 2
 '@T6G_MB_LIB.T6G(SCH_1):PAGE156_I113@PURE_QUANTA.Q_CAP(CHIPS)':
 'B': CDS_PINID='B';
NODE_NAME     C1564 2
 '@T6G_MB_LIB.T6G(SCH_1):PAGE156_I118@PURE_QUANTA.Q_CAP(CHIPS)':
 'B': CDS_PINID='B';
NODE_NAME     C1567 2
 '@T6G_MB_LIB.T6G(SCH_1):PAGE156_I125@PURE_QUANTA.Q_CAP(CHIPS)':
 'B': CDS_PINID='B';
NODE_NAME     C5032 2
 '@T6G_MB_LIB.T6G(SCH_1):PAGE156_I126@PURE_QUANTA.Q_CAP(CHIPS)':
 'B': CDS_PINID='B';
NODE_NAME     JP12 3
 '@T6G_MB_LIB.T6G(SCH_1):PAGE156_I128@PURE_QUANTA.CONN3_210HP1030BR1(CHIPS)':
 '3': CDS_PINID='\3\';
NODE_NAME     R5056 2
 '@T6G_MB_LIB.T6G(SCH_1):PAGE27_I428@PURE_QUANTA.Q_RES(CHIPS)':
 'B': CDS_PINID='B';
NODE_NAME     C129 2
 '@T6G_MB_LIB.T6G(SCH_1):PAGE398_I23@PURE_QUANTA.Q_CAP(CHIPS)':
 'B': CDS_PINID='B';
NODE_NAME     C131 2
 '@T6G_MB_LIB.T6G(SCH_1):PAGE398_I24@PURE_QUANTA.Q_CAP(CHIPS)':
 'B': CDS_PINID='B';
NODE_NAME     C133 2
 '@T6G_MB_LIB.T6G(SCH_1):PAGE398_I25@PURE_QUANTA.Q_CAP(CHIPS)':
 'B': CDS_PINID='B';
NODE_NAME     C134 2
 '@T6G_MB_LIB.T6G(SCH_1):PAGE398_I26@PURE_QUANTA.Q_CAP(CHIPS)':
 'B': CDS_PINID='B';
NODE_NAME     C130 2
 '@T6G_MB_LIB.T6G(SCH_1):PAGE398_I27@PURE_QUANTA.Q_CAP(CHIPS)':
 'B': CDS_PINID='B';
NODE_NAME     C229 2
 '@T6G_MB_LIB.T6G(SCH_1):PAGE398_I34@PURE_QUANTA.Q_CAP(CHIPS)':
 'B': CDS_PINID='B';
NODE_NAME     C244 2
 '@T6G_MB_LIB.T6G(SCH_1):PAGE398_I35@PURE_QUANTA.Q_CAP(CHIPS)':
 'B': CDS_PINID='B';
NODE_NAME     C261 2
 '@T6G_MB_LIB.T6G(SCH_1):PAGE398_I36@PURE_QUANTA.Q_CAP(CHIPS)':
 'B': CDS_PINID='B';
NODE_NAME     C256 2
 '@T6G_MB_LIB.T6G(SCH_1):PAGE398_I39@PURE_QUANTA.Q_CAP(CHIPS)':
 'B': CDS_PINID='B';
NODE_NAME     C185 2
 '@T6G_MB_LIB.T6G(SCH_1):PAGE398_I40@PURE_QUANTA.Q_CAP(CHIPS)':
 'B': CDS_PINID='B';
NODE_NAME     C222 2
 '@T6G_MB_LIB.T6G(SCH_1):PAGE398_I42@PURE_QUANTA.Q_CAP(CHIPS)':
 'B': CDS_PINID='B';
NODE_NAME     C220 2
 '@T6G_MB_LIB.T6G(SCH_1):PAGE398_I44@PURE_QUANTA.Q_CAP(CHIPS)':
 'B': CDS_PINID='B';
NODE_NAME     C135 2
 '@T6G_MB_LIB.T6G(SCH_1):PAGE398_I46@PURE_QUANTA.Q_CAP(CHIPS)':
 'B': CDS_PINID='B';
NODE_NAME     C243 2
 '@T6G_MB_LIB.T6G(SCH_1):PAGE398_I47@PURE_QUANTA.Q_CAP(CHIPS)':
 'B': CDS_PINID='B';
NODE_NAME     C138 2
 '@T6G_MB_LIB.T6G(SCH_1):PAGE398_I48@PURE_QUANTA.Q_CAP(CHIPS)':
 'B': CDS_PINID='B';
NODE_NAME     C257 2
 '@T6G_MB_LIB.T6G(SCH_1):PAGE398_I49@PURE_QUANTA.Q_CAP(CHIPS)':
 'B': CDS_PINID='B';
NODE_NAME     C221 2
 '@T6G_MB_LIB.T6G(SCH_1):PAGE398_I50@PURE_QUANTA.Q_CAP(CHIPS)':
 'B': CDS_PINID='B';
NODE_NAME     C258 2
 '@T6G_MB_LIB.T6G(SCH_1):PAGE398_I51@PURE_QUANTA.Q_CAP(CHIPS)':
 'B': CDS_PINID='B';
NODE_NAME     C225 2
 '@T6G_MB_LIB.T6G(SCH_1):PAGE398_I52@PURE_QUANTA.Q_CAP(CHIPS)':
 'B': CDS_PINID='B';
NODE_NAME     C240 2
 '@T6G_MB_LIB.T6G(SCH_1):PAGE398_I53@PURE_QUANTA.Q_CAP(CHIPS)':
 'B': CDS_PINID='B';
NODE_NAME     C284 2
 '@T6G_MB_LIB.T6G(SCH_1):PAGE398_I54@PURE_QUANTA.Q_CAP(CHIPS)':
 'B': CDS_PINID='B';
NODE_NAME     C188 2
 '@T6G_MB_LIB.T6G(SCH_1):PAGE398_I55@PURE_QUANTA.Q_CAP(CHIPS)':
 'B': CDS_PINID='B';
NODE_NAME     C265 2
 '@T6G_MB_LIB.T6G(SCH_1):PAGE398_I56@PURE_QUANTA.Q_CAP(CHIPS)':
 'B': CDS_PINID='B';
NODE_NAME     C227 2
 '@T6G_MB_LIB.T6G(SCH_1):PAGE398_I57@PURE_QUANTA.Q_CAP(CHIPS)':
 'B': CDS_PINID='B';
NODE_NAME     C186 2
 '@T6G_MB_LIB.T6G(SCH_1):PAGE398_I58@PURE_QUANTA.Q_CAP(CHIPS)':
 'B': CDS_PINID='B';
NODE_NAME     C280 2
 '@T6G_MB_LIB.T6G(SCH_1):PAGE398_I59@PURE_QUANTA.Q_CAP(CHIPS)':
 'B': CDS_PINID='B';
NODE_NAME     C190 2
 '@T6G_MB_LIB.T6G(SCH_1):PAGE398_I62@PURE_QUANTA.Q_CAP(CHIPS)':
 'B': CDS_PINID='B';
NODE_NAME     C285 2
 '@T6G_MB_LIB.T6G(SCH_1):PAGE398_I63@PURE_QUANTA.Q_CAP(CHIPS)':
 'B': CDS_PINID='B';
NODE_NAME     C255 2
 '@T6G_MB_LIB.T6G(SCH_1):PAGE398_I64@PURE_QUANTA.Q_CAP(CHIPS)':
 'B': CDS_PINID='B';
NODE_NAME     C262 2
 '@T6G_MB_LIB.T6G(SCH_1):PAGE398_I65@PURE_QUANTA.Q_CAP(CHIPS)':
 'B': CDS_PINID='B';
NODE_NAME     C259 2
 '@T6G_MB_LIB.T6G(SCH_1):PAGE398_I66@PURE_QUANTA.Q_CAP(CHIPS)':
 'B': CDS_PINID='B';
NODE_NAME     C254 2
 '@T6G_MB_LIB.T6G(SCH_1):PAGE398_I67@PURE_QUANTA.Q_CAP(CHIPS)':
 'B': CDS_PINID='B';
NODE_NAME     C286 2
 '@T6G_MB_LIB.T6G(SCH_1):PAGE398_I68@PURE_QUANTA.Q_CAP(CHIPS)':
 'B': CDS_PINID='B';
NODE_NAME     C250 2
 '@T6G_MB_LIB.T6G(SCH_1):PAGE398_I70@PURE_QUANTA.Q_CAP(CHIPS)':
 'B': CDS_PINID='B';
NODE_NAME     C269 2
 '@T6G_MB_LIB.T6G(SCH_1):PAGE398_I71@PURE_QUANTA.Q_CAP(CHIPS)':
 'B': CDS_PINID='B';
NODE_NAME     C241 2
 '@T6G_MB_LIB.T6G(SCH_1):PAGE398_I72@PURE_QUANTA.Q_CAP(CHIPS)':
 'B': CDS_PINID='B';
NODE_NAME     C247 2
 '@T6G_MB_LIB.T6G(SCH_1):PAGE398_I73@PURE_QUANTA.Q_CAP(CHIPS)':
 'B': CDS_PINID='B';
NODE_NAME     C189 2
 '@T6G_MB_LIB.T6G(SCH_1):PAGE398_I75@PURE_QUANTA.Q_CAP(CHIPS)':
 'B': CDS_PINID='B';
NODE_NAME     C266 2
 '@T6G_MB_LIB.T6G(SCH_1):PAGE398_I76@PURE_QUANTA.Q_CAP(CHIPS)':
 'B': CDS_PINID='B';
NODE_NAME     C139 2
 '@T6G_MB_LIB.T6G(SCH_1):PAGE398_I77@PURE_QUANTA.Q_CAP(CHIPS)':
 'B': CDS_PINID='B';
NODE_NAME     C137 2
 '@T6G_MB_LIB.T6G(SCH_1):PAGE398_I78@PURE_QUANTA.Q_CAP(CHIPS)':
 'B': CDS_PINID='B';
NODE_NAME     C282 2
 '@T6G_MB_LIB.T6G(SCH_1):PAGE398_I80@PURE_QUANTA.Q_CAP(CHIPS)':
 'B': CDS_PINID='B';
NODE_NAME     C264 2
 '@T6G_MB_LIB.T6G(SCH_1):PAGE398_I81@PURE_QUANTA.Q_CAP(CHIPS)':
 'B': CDS_PINID='B';
NODE_NAME     C141 2
 '@T6G_MB_LIB.T6G(SCH_1):PAGE398_I82@PURE_QUANTA.Q_CAP(CHIPS)':
 'B': CDS_PINID='B';
NODE_NAME     C192 2
 '@T6G_MB_LIB.T6G(SCH_1):PAGE398_I83@PURE_QUANTA.Q_CAP(CHIPS)':
 'B': CDS_PINID='B';
NODE_NAME     C260 2
 '@T6G_MB_LIB.T6G(SCH_1):PAGE398_I84@PURE_QUANTA.Q_CAP(CHIPS)':
 'B': CDS_PINID='B';
NODE_NAME     C184 2
 '@T6G_MB_LIB.T6G(SCH_1):PAGE398_I85@PURE_QUANTA.Q_CAP(CHIPS)':
 'B': CDS_PINID='B';
NODE_NAME     C253 2
 '@T6G_MB_LIB.T6G(SCH_1):PAGE398_I86@PURE_QUANTA.Q_CAP(CHIPS)':
 'B': CDS_PINID='B';
NODE_NAME     C228 2
 '@T6G_MB_LIB.T6G(SCH_1):PAGE398_I87@PURE_QUANTA.Q_CAP(CHIPS)':
 'B': CDS_PINID='B';
NODE_NAME     C198 2
 '@T6G_MB_LIB.T6G(SCH_1):PAGE398_I92@PURE_QUANTA.Q_CAP(CHIPS)':
 'B': CDS_PINID='B';
NODE_NAME     C191 2
 '@T6G_MB_LIB.T6G(SCH_1):PAGE398_I93@PURE_QUANTA.Q_CAP(CHIPS)':
 'B': CDS_PINID='B';
NODE_NAME     R726 2
 '@T6G_MB_LIB.T6G(SCH_1):PAGE401_I90@PURE_QUANTA.Q_RES(CHIPS)':
 'B': CDS_PINID='B';
NODE_NAME     R6721 2
 '@T6G_MB_LIB.T6G(SCH_1):PAGE401_I96@PURE_QUANTA.Q_RES(CHIPS)':
 'B': CDS_PINID='B';
NODE_NAME     R6720 2
 '@T6G_MB_LIB.T6G(SCH_1):PAGE401_I97@PURE_QUANTA.Q_RES(CHIPS)':
 'B': CDS_PINID='B';
NODE_NAME     R6733 2
 '@T6G_MB_LIB.T6G(SCH_1):PAGE391_I15@PURE_QUANTA.Q_RES(CHIPS)':
 'B': CDS_PINID='B';
NODE_NAME     R6732 2
 '@T6G_MB_LIB.T6G(SCH_1):PAGE391_I16@PURE_QUANTA.Q_RES(CHIPS)':
 'B': CDS_PINID='B';
NODE_NAME     U6015 AC13
 '@T6G_MB_LIB.T6G(SCH_1):PAGE391_I19@PURE_QUANTA.PT5161LRS(CHIPS)':
 'GND1': CDS_PINID='GND1';
NODE_NAME     U6015 AC22
 '@T6G_MB_LIB.T6G(SCH_1):PAGE391_I19@PURE_QUANTA.PT5161LRS(CHIPS)':
 'GND2': CDS_PINID='GND2';
NODE_NAME     U6015 AC32
 '@T6G_MB_LIB.T6G(SCH_1):PAGE391_I19@PURE_QUANTA.PT5161LRS(CHIPS)':
 'GND3': CDS_PINID='GND3';
NODE_NAME     U6015 AC4
 '@T6G_MB_LIB.T6G(SCH_1):PAGE391_I19@PURE_QUANTA.PT5161LRS(CHIPS)':
 'GND4': CDS_PINID='GND4';
NODE_NAME     U6015 AD2
 '@T6G_MB_LIB.T6G(SCH_1):PAGE391_I19@PURE_QUANTA.PT5161LRS(CHIPS)':
 'GND5': CDS_PINID='GND5';
NODE_NAME     U6015 AD34
 '@T6G_MB_LIB.T6G(SCH_1):PAGE391_I19@PURE_QUANTA.PT5161LRS(CHIPS)':
 'GND6': CDS_PINID='GND6';
NODE_NAME     U6015 AE1
 '@T6G_MB_LIB.T6G(SCH_1):PAGE391_I19@PURE_QUANTA.PT5161LRS(CHIPS)':
 'GND7': CDS_PINID='GND7';
NODE_NAME     U6015 AE35
 '@T6G_MB_LIB.T6G(SCH_1):PAGE391_I19@PURE_QUANTA.PT5161LRS(CHIPS)':
 'GND8': CDS_PINID='GND8';
NODE_NAME     U6015 AK13
 '@T6G_MB_LIB.T6G(SCH_1):PAGE391_I19@PURE_QUANTA.PT5161LRS(CHIPS)':
 'GND9': CDS_PINID='GND9';
NODE_NAME     U6015 AK22
 '@T6G_MB_LIB.T6G(SCH_1):PAGE391_I19@PURE_QUANTA.PT5161LRS(CHIPS)':
 'GND10': CDS_PINID='GND10';
NODE_NAME     U6015 AK32
 '@T6G_MB_LIB.T6G(SCH_1):PAGE391_I19@PURE_QUANTA.PT5161LRS(CHIPS)':
 'GND11': CDS_PINID='GND11';
NODE_NAME     U6015 AK4
 '@T6G_MB_LIB.T6G(SCH_1):PAGE391_I19@PURE_QUANTA.PT5161LRS(CHIPS)':
 'GND12': CDS_PINID='GND12';
NODE_NAME     U6015 AL2
 '@T6G_MB_LIB.T6G(SCH_1):PAGE391_I19@PURE_QUANTA.PT5161LRS(CHIPS)':
 'GND13': CDS_PINID='GND13';
NODE_NAME     U6015 AL34
 '@T6G_MB_LIB.T6G(SCH_1):PAGE391_I19@PURE_QUANTA.PT5161LRS(CHIPS)':
 'GND14': CDS_PINID='GND14';
NODE_NAME     U6015 AM1
 '@T6G_MB_LIB.T6G(SCH_1):PAGE391_I19@PURE_QUANTA.PT5161LRS(CHIPS)':
 'GND15': CDS_PINID='GND15';
NODE_NAME     U6015 AM35
 '@T6G_MB_LIB.T6G(SCH_1):PAGE391_I19@PURE_QUANTA.PT5161LRS(CHIPS)':
 'GND16': CDS_PINID='GND16';
NODE_NAME     U6015 AU13
 '@T6G_MB_LIB.T6G(SCH_1):PAGE391_I19@PURE_QUANTA.PT5161LRS(CHIPS)':
 'GND17': CDS_PINID='GND17';
NODE_NAME     U6015 AU22
 '@T6G_MB_LIB.T6G(SCH_1):PAGE391_I19@PURE_QUANTA.PT5161LRS(CHIPS)':
 'GND18': CDS_PINID='GND18';
NODE_NAME     U6015 AU32
 '@T6G_MB_LIB.T6G(SCH_1):PAGE391_I19@PURE_QUANTA.PT5161LRS(CHIPS)':
 'GND19': CDS_PINID='GND19';
NODE_NAME     U6015 AU4
 '@T6G_MB_LIB.T6G(SCH_1):PAGE391_I19@PURE_QUANTA.PT5161LRS(CHIPS)':
 'GND20': CDS_PINID='GND20';
NODE_NAME     U6015 AV2
 '@T6G_MB_LIB.T6G(SCH_1):PAGE391_I19@PURE_QUANTA.PT5161LRS(CHIPS)':
 'GND21': CDS_PINID='GND21';
NODE_NAME     U6015 AV34
 '@T6G_MB_LIB.T6G(SCH_1):PAGE391_I19@PURE_QUANTA.PT5161LRS(CHIPS)':
 'GND22': CDS_PINID='GND22';
NODE_NAME     U6015 AW1
 '@T6G_MB_LIB.T6G(SCH_1):PAGE391_I19@PURE_QUANTA.PT5161LRS(CHIPS)':
 'GND23': CDS_PINID='GND23';
NODE_NAME     U6015 AW35
 '@T6G_MB_LIB.T6G(SCH_1):PAGE391_I19@PURE_QUANTA.PT5161LRS(CHIPS)':
 'GND24': CDS_PINID='GND24';
NODE_NAME     U6015 B19
 '@T6G_MB_LIB.T6G(SCH_1):PAGE391_I19@PURE_QUANTA.PT5161LRS(CHIPS)':
 'GND25': CDS_PINID='GND25';
NODE_NAME     U6015 BD13
 '@T6G_MB_LIB.T6G(SCH_1):PAGE391_I19@PURE_QUANTA.PT5161LRS(CHIPS)':
 'GND26': CDS_PINID='GND26';
NODE_NAME     U6015 BD22
 '@T6G_MB_LIB.T6G(SCH_1):PAGE391_I19@PURE_QUANTA.PT5161LRS(CHIPS)':
 'GND27': CDS_PINID='GND27';
NODE_NAME     U6015 BD32
 '@T6G_MB_LIB.T6G(SCH_1):PAGE391_I19@PURE_QUANTA.PT5161LRS(CHIPS)':
 'GND28': CDS_PINID='GND28';
NODE_NAME     U6015 BD4
 '@T6G_MB_LIB.T6G(SCH_1):PAGE391_I19@PURE_QUANTA.PT5161LRS(CHIPS)':
 'GND29': CDS_PINID='GND29';
NODE_NAME     U6015 BE2
 '@T6G_MB_LIB.T6G(SCH_1):PAGE391_I19@PURE_QUANTA.PT5161LRS(CHIPS)':
 'GND30': CDS_PINID='GND30';
NODE_NAME     U6015 BE34
 '@T6G_MB_LIB.T6G(SCH_1):PAGE391_I19@PURE_QUANTA.PT5161LRS(CHIPS)':
 'GND31': CDS_PINID='GND31';
NODE_NAME     U6015 BF1
 '@T6G_MB_LIB.T6G(SCH_1):PAGE391_I19@PURE_QUANTA.PT5161LRS(CHIPS)':
 'GND32': CDS_PINID='GND32';
NODE_NAME     U6015 BF35
 '@T6G_MB_LIB.T6G(SCH_1):PAGE391_I19@PURE_QUANTA.PT5161LRS(CHIPS)':
 'GND33': CDS_PINID='GND33';
NODE_NAME     U6015 BL13
 '@T6G_MB_LIB.T6G(SCH_1):PAGE391_I19@PURE_QUANTA.PT5161LRS(CHIPS)':
 'GND34': CDS_PINID='GND34';
NODE_NAME     U6015 BL22
 '@T6G_MB_LIB.T6G(SCH_1):PAGE391_I19@PURE_QUANTA.PT5161LRS(CHIPS)':
 'GND35': CDS_PINID='GND35';
NODE_NAME     U6015 BL32
 '@T6G_MB_LIB.T6G(SCH_1):PAGE391_I19@PURE_QUANTA.PT5161LRS(CHIPS)':
 'GND36': CDS_PINID='GND36';
NODE_NAME     U6015 BL4
 '@T6G_MB_LIB.T6G(SCH_1):PAGE391_I19@PURE_QUANTA.PT5161LRS(CHIPS)':
 'GND37': CDS_PINID='GND37';
NODE_NAME     U6015 BM2
 '@T6G_MB_LIB.T6G(SCH_1):PAGE391_I19@PURE_QUANTA.PT5161LRS(CHIPS)':
 'GND38': CDS_PINID='GND38';
NODE_NAME     U6015 BM34
 '@T6G_MB_LIB.T6G(SCH_1):PAGE391_I19@PURE_QUANTA.PT5161LRS(CHIPS)':
 'GND39': CDS_PINID='GND39';
NODE_NAME     U6015 BN1
 '@T6G_MB_LIB.T6G(SCH_1):PAGE391_I19@PURE_QUANTA.PT5161LRS(CHIPS)':
 'GND40': CDS_PINID='GND40';
NODE_NAME     U6015 BN35
 '@T6G_MB_LIB.T6G(SCH_1):PAGE391_I19@PURE_QUANTA.PT5161LRS(CHIPS)':
 'GND41': CDS_PINID='GND41';
NODE_NAME     U6015 BV13
 '@T6G_MB_LIB.T6G(SCH_1):PAGE391_I19@PURE_QUANTA.PT5161LRS(CHIPS)':
 'GND42': CDS_PINID='GND42';
NODE_NAME     U6015 BV22
 '@T6G_MB_LIB.T6G(SCH_1):PAGE391_I19@PURE_QUANTA.PT5161LRS(CHIPS)':
 'GND43': CDS_PINID='GND43';
NODE_NAME     U6015 BV32
 '@T6G_MB_LIB.T6G(SCH_1):PAGE391_I19@PURE_QUANTA.PT5161LRS(CHIPS)':
 'GND44': CDS_PINID='GND44';
NODE_NAME     U6015 BV4
 '@T6G_MB_LIB.T6G(SCH_1):PAGE391_I19@PURE_QUANTA.PT5161LRS(CHIPS)':
 'GND45': CDS_PINID='GND45';
NODE_NAME     U6015 BW2
 '@T6G_MB_LIB.T6G(SCH_1):PAGE391_I19@PURE_QUANTA.PT5161LRS(CHIPS)':
 'GND46': CDS_PINID='GND46';
NODE_NAME     U6015 BW34
 '@T6G_MB_LIB.T6G(SCH_1):PAGE391_I19@PURE_QUANTA.PT5161LRS(CHIPS)':
 'GND47': CDS_PINID='GND47';
NODE_NAME     U6015 BY1
 '@T6G_MB_LIB.T6G(SCH_1):PAGE391_I19@PURE_QUANTA.PT5161LRS(CHIPS)':
 'GND48': CDS_PINID='GND48';
NODE_NAME     U6015 BY35
 '@T6G_MB_LIB.T6G(SCH_1):PAGE391_I19@PURE_QUANTA.PT5161LRS(CHIPS)':
 'GND49': CDS_PINID='GND49';
NODE_NAME     U6015 CE13
 '@T6G_MB_LIB.T6G(SCH_1):PAGE391_I19@PURE_QUANTA.PT5161LRS(CHIPS)':
 'GND50': CDS_PINID='GND50';
NODE_NAME     U6015 CE22
 '@T6G_MB_LIB.T6G(SCH_1):PAGE391_I19@PURE_QUANTA.PT5161LRS(CHIPS)':
 'GND51': CDS_PINID='GND51';
NODE_NAME     U6015 CE32
 '@T6G_MB_LIB.T6G(SCH_1):PAGE391_I19@PURE_QUANTA.PT5161LRS(CHIPS)':
 'GND52': CDS_PINID='GND52';
NODE_NAME     U6015 CE4
 '@T6G_MB_LIB.T6G(SCH_1):PAGE391_I19@PURE_QUANTA.PT5161LRS(CHIPS)':
 'GND53': CDS_PINID='GND53';
NODE_NAME     U6015 CF2
 '@T6G_MB_LIB.T6G(SCH_1):PAGE391_I19@PURE_QUANTA.PT5161LRS(CHIPS)':
 'GND54': CDS_PINID='GND54';
NODE_NAME     U6015 CF34
 '@T6G_MB_LIB.T6G(SCH_1):PAGE391_I19@PURE_QUANTA.PT5161LRS(CHIPS)':
 'GND55': CDS_PINID='GND55';
NODE_NAME     U6015 CG1
 '@T6G_MB_LIB.T6G(SCH_1):PAGE391_I19@PURE_QUANTA.PT5161LRS(CHIPS)':
 'GND56': CDS_PINID='GND56';
NODE_NAME     U6015 CG35
 '@T6G_MB_LIB.T6G(SCH_1):PAGE391_I19@PURE_QUANTA.PT5161LRS(CHIPS)':
 'GND57': CDS_PINID='GND57';
NODE_NAME     U6015 CM13
 '@T6G_MB_LIB.T6G(SCH_1):PAGE391_I19@PURE_QUANTA.PT5161LRS(CHIPS)':
 'GND58': CDS_PINID='GND58';
NODE_NAME     U6015 CM22
 '@T6G_MB_LIB.T6G(SCH_1):PAGE391_I19@PURE_QUANTA.PT5161LRS(CHIPS)':
 'GND59': CDS_PINID='GND59';
NODE_NAME     U6015 CM32
 '@T6G_MB_LIB.T6G(SCH_1):PAGE391_I19@PURE_QUANTA.PT5161LRS(CHIPS)':
 'GND60': CDS_PINID='GND60';
NODE_NAME     U6015 CM4
 '@T6G_MB_LIB.T6G(SCH_1):PAGE391_I19@PURE_QUANTA.PT5161LRS(CHIPS)':
 'GND61': CDS_PINID='GND61';
NODE_NAME     U6015 CN2
 '@T6G_MB_LIB.T6G(SCH_1):PAGE391_I19@PURE_QUANTA.PT5161LRS(CHIPS)':
 'GND62': CDS_PINID='GND62';
NODE_NAME     U6015 CN34
 '@T6G_MB_LIB.T6G(SCH_1):PAGE391_I19@PURE_QUANTA.PT5161LRS(CHIPS)':
 'GND63': CDS_PINID='GND63';
NODE_NAME     U6015 CP1
 '@T6G_MB_LIB.T6G(SCH_1):PAGE391_I19@PURE_QUANTA.PT5161LRS(CHIPS)':
 'GND64': CDS_PINID='GND64';
NODE_NAME     U6015 CP35
 '@T6G_MB_LIB.T6G(SCH_1):PAGE391_I19@PURE_QUANTA.PT5161LRS(CHIPS)':
 'GND65': CDS_PINID='GND65';
NODE_NAME     U6015 CW13
 '@T6G_MB_LIB.T6G(SCH_1):PAGE391_I19@PURE_QUANTA.PT5161LRS(CHIPS)':
 'GND66': CDS_PINID='GND66';
NODE_NAME     U6015 CW22
 '@T6G_MB_LIB.T6G(SCH_1):PAGE391_I19@PURE_QUANTA.PT5161LRS(CHIPS)':
 'GND67': CDS_PINID='GND67';
NODE_NAME     U6015 CW32
 '@T6G_MB_LIB.T6G(SCH_1):PAGE391_I19@PURE_QUANTA.PT5161LRS(CHIPS)':
 'GND68': CDS_PINID='GND68';
NODE_NAME     U6015 CW4
 '@T6G_MB_LIB.T6G(SCH_1):PAGE391_I19@PURE_QUANTA.PT5161LRS(CHIPS)':
 'GND69': CDS_PINID='GND69';
NODE_NAME     U6015 CY2
 '@T6G_MB_LIB.T6G(SCH_1):PAGE391_I19@PURE_QUANTA.PT5161LRS(CHIPS)':
 'GND70': CDS_PINID='GND70';
NODE_NAME     U6015 CY34
 '@T6G_MB_LIB.T6G(SCH_1):PAGE391_I19@PURE_QUANTA.PT5161LRS(CHIPS)':
 'GND71': CDS_PINID='GND71';
NODE_NAME     U6015 DA1
 '@T6G_MB_LIB.T6G(SCH_1):PAGE391_I19@PURE_QUANTA.PT5161LRS(CHIPS)':
 'GND72': CDS_PINID='GND72';
NODE_NAME     U6015 DA35
 '@T6G_MB_LIB.T6G(SCH_1):PAGE391_I19@PURE_QUANTA.PT5161LRS(CHIPS)':
 'GND73': CDS_PINID='GND73';
NODE_NAME     U6015 DF13
 '@T6G_MB_LIB.T6G(SCH_1):PAGE391_I19@PURE_QUANTA.PT5161LRS(CHIPS)':
 'GND74': CDS_PINID='GND74';
NODE_NAME     U6015 DF22
 '@T6G_MB_LIB.T6G(SCH_1):PAGE391_I19@PURE_QUANTA.PT5161LRS(CHIPS)':
 'GND75': CDS_PINID='GND75';
NODE_NAME     U6015 DF32
 '@T6G_MB_LIB.T6G(SCH_1):PAGE391_I19@PURE_QUANTA.PT5161LRS(CHIPS)':
 'GND76': CDS_PINID='GND76';
NODE_NAME     U6015 DF4
 '@T6G_MB_LIB.T6G(SCH_1):PAGE391_I19@PURE_QUANTA.PT5161LRS(CHIPS)':
 'GND77': CDS_PINID='GND77';
NODE_NAME     U6015 DG2
 '@T6G_MB_LIB.T6G(SCH_1):PAGE391_I19@PURE_QUANTA.PT5161LRS(CHIPS)':
 'GND78': CDS_PINID='GND78';
NODE_NAME     U6015 DG34
 '@T6G_MB_LIB.T6G(SCH_1):PAGE391_I19@PURE_QUANTA.PT5161LRS(CHIPS)':
 'GND79': CDS_PINID='GND79';
NODE_NAME     U6015 DH1
 '@T6G_MB_LIB.T6G(SCH_1):PAGE391_I19@PURE_QUANTA.PT5161LRS(CHIPS)':
 'GND80': CDS_PINID='GND80';
NODE_NAME     U6015 DH35
 '@T6G_MB_LIB.T6G(SCH_1):PAGE391_I19@PURE_QUANTA.PT5161LRS(CHIPS)':
 'GND81': CDS_PINID='GND81';
NODE_NAME     U6015 DN13
 '@T6G_MB_LIB.T6G(SCH_1):PAGE391_I19@PURE_QUANTA.PT5161LRS(CHIPS)':
 'GND82': CDS_PINID='GND82';
NODE_NAME     U6015 DN22
 '@T6G_MB_LIB.T6G(SCH_1):PAGE391_I19@PURE_QUANTA.PT5161LRS(CHIPS)':
 'GND83': CDS_PINID='GND83';
NODE_NAME     U6015 DN32
 '@T6G_MB_LIB.T6G(SCH_1):PAGE391_I19@PURE_QUANTA.PT5161LRS(CHIPS)':
 'GND84': CDS_PINID='GND84';
NODE_NAME     U6015 DN4
 '@T6G_MB_LIB.T6G(SCH_1):PAGE391_I19@PURE_QUANTA.PT5161LRS(CHIPS)':
 'GND85': CDS_PINID='GND85';
NODE_NAME     U6015 DP2
 '@T6G_MB_LIB.T6G(SCH_1):PAGE391_I19@PURE_QUANTA.PT5161LRS(CHIPS)':
 'GND86': CDS_PINID='GND86';
NODE_NAME     U6015 DP34
 '@T6G_MB_LIB.T6G(SCH_1):PAGE391_I19@PURE_QUANTA.PT5161LRS(CHIPS)':
 'GND87': CDS_PINID='GND87';
NODE_NAME     U6015 DR1
 '@T6G_MB_LIB.T6G(SCH_1):PAGE391_I19@PURE_QUANTA.PT5161LRS(CHIPS)':
 'GND88': CDS_PINID='GND88';
NODE_NAME     U6015 DR35
 '@T6G_MB_LIB.T6G(SCH_1):PAGE391_I19@PURE_QUANTA.PT5161LRS(CHIPS)':
 'GND89': CDS_PINID='GND89';
NODE_NAME     U6015 DY13
 '@T6G_MB_LIB.T6G(SCH_1):PAGE391_I19@PURE_QUANTA.PT5161LRS(CHIPS)':
 'GND90': CDS_PINID='GND90';
NODE_NAME     U6015 DY22
 '@T6G_MB_LIB.T6G(SCH_1):PAGE391_I19@PURE_QUANTA.PT5161LRS(CHIPS)':
 'GND91': CDS_PINID='GND91';
NODE_NAME     U6015 DY32
 '@T6G_MB_LIB.T6G(SCH_1):PAGE391_I19@PURE_QUANTA.PT5161LRS(CHIPS)':
 'GND92': CDS_PINID='GND92';
NODE_NAME     U6015 DY4
 '@T6G_MB_LIB.T6G(SCH_1):PAGE391_I19@PURE_QUANTA.PT5161LRS(CHIPS)':
 'GND93': CDS_PINID='GND93';
NODE_NAME     U6015 E14
 '@T6G_MB_LIB.T6G(SCH_1):PAGE391_I19@PURE_QUANTA.PT5161LRS(CHIPS)':
 'GND94': CDS_PINID='GND94';
NODE_NAME     U6015 E27
 '@T6G_MB_LIB.T6G(SCH_1):PAGE391_I19@PURE_QUANTA.PT5161LRS(CHIPS)':
 'GND95': CDS_PINID='GND95';
NODE_NAME     U6015 E33
 '@T6G_MB_LIB.T6G(SCH_1):PAGE391_I19@PURE_QUANTA.PT5161LRS(CHIPS)':
 'GND96': CDS_PINID='GND96';
NODE_NAME     U6015 EA2
 '@T6G_MB_LIB.T6G(SCH_1):PAGE391_I19@PURE_QUANTA.PT5161LRS(CHIPS)':
 'GND97': CDS_PINID='GND97';
NODE_NAME     U6015 EA34
 '@T6G_MB_LIB.T6G(SCH_1):PAGE391_I19@PURE_QUANTA.PT5161LRS(CHIPS)':
 'GND98': CDS_PINID='GND98';
NODE_NAME     U6015 EB1
 '@T6G_MB_LIB.T6G(SCH_1):PAGE391_I19@PURE_QUANTA.PT5161LRS(CHIPS)':
 'GND99': CDS_PINID='GND99';
NODE_NAME     U6015 EB35
 '@T6G_MB_LIB.T6G(SCH_1):PAGE391_I19@PURE_QUANTA.PT5161LRS(CHIPS)':
 'GND100': CDS_PINID='GND100';
NODE_NAME     U6015 EG13
 '@T6G_MB_LIB.T6G(SCH_1):PAGE391_I19@PURE_QUANTA.PT5161LRS(CHIPS)':
 'GND101': CDS_PINID='GND101';
NODE_NAME     U6015 EG22
 '@T6G_MB_LIB.T6G(SCH_1):PAGE391_I19@PURE_QUANTA.PT5161LRS(CHIPS)':
 'GND102': CDS_PINID='GND102';
NODE_NAME     U6015 EG32
 '@T6G_MB_LIB.T6G(SCH_1):PAGE391_I19@PURE_QUANTA.PT5161LRS(CHIPS)':
 'GND103': CDS_PINID='GND103';
NODE_NAME     U6015 EG4
 '@T6G_MB_LIB.T6G(SCH_1):PAGE391_I19@PURE_QUANTA.PT5161LRS(CHIPS)':
 'GND104': CDS_PINID='GND104';
NODE_NAME     U6015 EH2
 '@T6G_MB_LIB.T6G(SCH_1):PAGE391_I19@PURE_QUANTA.PT5161LRS(CHIPS)':
 'GND105': CDS_PINID='GND105';
NODE_NAME     U6015 EH34
 '@T6G_MB_LIB.T6G(SCH_1):PAGE391_I19@PURE_QUANTA.PT5161LRS(CHIPS)':
 'GND106': CDS_PINID='GND106';
NODE_NAME     U6015 EJ1
 '@T6G_MB_LIB.T6G(SCH_1):PAGE391_I19@PURE_QUANTA.PT5161LRS(CHIPS)':
 'GND107': CDS_PINID='GND107';
NODE_NAME     U6015 EJ35
 '@T6G_MB_LIB.T6G(SCH_1):PAGE391_I19@PURE_QUANTA.PT5161LRS(CHIPS)':
 'GND108': CDS_PINID='GND108';
NODE_NAME     U6015 EP13
 '@T6G_MB_LIB.T6G(SCH_1):PAGE391_I19@PURE_QUANTA.PT5161LRS(CHIPS)':
 'GND109': CDS_PINID='GND109';
NODE_NAME     U6015 EP22
 '@T6G_MB_LIB.T6G(SCH_1):PAGE391_I19@PURE_QUANTA.PT5161LRS(CHIPS)':
 'GND110': CDS_PINID='GND110';
NODE_NAME     U6015 EP32
 '@T6G_MB_LIB.T6G(SCH_1):PAGE391_I19@PURE_QUANTA.PT5161LRS(CHIPS)':
 'GND111': CDS_PINID='GND111';
NODE_NAME     U6015 EP4
 '@T6G_MB_LIB.T6G(SCH_1):PAGE391_I19@PURE_QUANTA.PT5161LRS(CHIPS)':
 'GND112': CDS_PINID='GND112';
NODE_NAME     U6015 ER2
 '@T6G_MB_LIB.T6G(SCH_1):PAGE391_I19@PURE_QUANTA.PT5161LRS(CHIPS)':
 'GND113': CDS_PINID='GND113';
NODE_NAME     U6015 ER34
 '@T6G_MB_LIB.T6G(SCH_1):PAGE391_I19@PURE_QUANTA.PT5161LRS(CHIPS)':
 'GND114': CDS_PINID='GND114';
NODE_NAME     U6015 ET1
 '@T6G_MB_LIB.T6G(SCH_1):PAGE391_I19@PURE_QUANTA.PT5161LRS(CHIPS)':
 'GND115': CDS_PINID='GND115';
NODE_NAME     U6015 ET35
 '@T6G_MB_LIB.T6G(SCH_1):PAGE391_I19@PURE_QUANTA.PT5161LRS(CHIPS)':
 'GND116': CDS_PINID='GND116';
NODE_NAME     U6015 FA15
 '@T6G_MB_LIB.T6G(SCH_1):PAGE391_I19@PURE_QUANTA.PT5161LRS(CHIPS)':
 'GND117': CDS_PINID='GND117';
NODE_NAME     U6015 FA32
 '@T6G_MB_LIB.T6G(SCH_1):PAGE391_I19@PURE_QUANTA.PT5161LRS(CHIPS)':
 'GND118': CDS_PINID='GND118';
NODE_NAME     U6015 FB2
 '@T6G_MB_LIB.T6G(SCH_1):PAGE391_I19@PURE_QUANTA.PT5161LRS(CHIPS)':
 'GND119': CDS_PINID='GND119';
NODE_NAME     U6015 FB34
 '@T6G_MB_LIB.T6G(SCH_1):PAGE391_I19@PURE_QUANTA.PT5161LRS(CHIPS)':
 'GND120': CDS_PINID='GND120';
NODE_NAME     U6015 FC19
 '@T6G_MB_LIB.T6G(SCH_1):PAGE391_I19@PURE_QUANTA.PT5161LRS(CHIPS)':
 'GND121': CDS_PINID='GND121';
NODE_NAME     U6015 FC23
 '@T6G_MB_LIB.T6G(SCH_1):PAGE391_I19@PURE_QUANTA.PT5161LRS(CHIPS)':
 'GND122': CDS_PINID='GND122';
NODE_NAME     U6015 FC25
 '@T6G_MB_LIB.T6G(SCH_1):PAGE391_I19@PURE_QUANTA.PT5161LRS(CHIPS)':
 'GND123': CDS_PINID='GND123';
NODE_NAME     U6015 FC28
 '@T6G_MB_LIB.T6G(SCH_1):PAGE391_I19@PURE_QUANTA.PT5161LRS(CHIPS)':
 'GND124': CDS_PINID='GND124';
NODE_NAME     U6015 FC3
 '@T6G_MB_LIB.T6G(SCH_1):PAGE391_I19@PURE_QUANTA.PT5161LRS(CHIPS)':
 'GND125': CDS_PINID='GND125';
NODE_NAME     U6015 FC6
 '@T6G_MB_LIB.T6G(SCH_1):PAGE391_I19@PURE_QUANTA.PT5161LRS(CHIPS)':
 'GND126': CDS_PINID='GND126';
NODE_NAME     U6015 FC9
 '@T6G_MB_LIB.T6G(SCH_1):PAGE391_I19@PURE_QUANTA.PT5161LRS(CHIPS)':
 'GND127': CDS_PINID='GND127';
NODE_NAME     U6015 FD1
 '@T6G_MB_LIB.T6G(SCH_1):PAGE391_I19@PURE_QUANTA.PT5161LRS(CHIPS)':
 'GND128': CDS_PINID='GND128';
NODE_NAME     U6015 FD35
 '@T6G_MB_LIB.T6G(SCH_1):PAGE391_I19@PURE_QUANTA.PT5161LRS(CHIPS)':
 'GND129': CDS_PINID='GND129';
NODE_NAME     U6015 FF14
 '@T6G_MB_LIB.T6G(SCH_1):PAGE391_I19@PURE_QUANTA.PT5161LRS(CHIPS)':
 'GND130': CDS_PINID='GND130';
NODE_NAME     U6015 FF21
 '@T6G_MB_LIB.T6G(SCH_1):PAGE391_I19@PURE_QUANTA.PT5161LRS(CHIPS)':
 'GND131': CDS_PINID='GND131';
NODE_NAME     U6015 FJ12
 '@T6G_MB_LIB.T6G(SCH_1):PAGE391_I19@PURE_QUANTA.PT5161LRS(CHIPS)':
 'GND132': CDS_PINID='GND132';
NODE_NAME     U6015 FJ19
 '@T6G_MB_LIB.T6G(SCH_1):PAGE391_I19@PURE_QUANTA.PT5161LRS(CHIPS)':
 'GND133': CDS_PINID='GND133';
NODE_NAME     U6015 H12
 '@T6G_MB_LIB.T6G(SCH_1):PAGE391_I19@PURE_QUANTA.PT5161LRS(CHIPS)':
 'GND134': CDS_PINID='GND134';
NODE_NAME     U6015 H16
 '@T6G_MB_LIB.T6G(SCH_1):PAGE391_I19@PURE_QUANTA.PT5161LRS(CHIPS)':
 'GND135': CDS_PINID='GND135';
NODE_NAME     U6015 H19
 '@T6G_MB_LIB.T6G(SCH_1):PAGE391_I19@PURE_QUANTA.PT5161LRS(CHIPS)':
 'GND136': CDS_PINID='GND136';
NODE_NAME     U6015 H31
 '@T6G_MB_LIB.T6G(SCH_1):PAGE391_I19@PURE_QUANTA.PT5161LRS(CHIPS)':
 'GND137': CDS_PINID='GND137';
NODE_NAME     U6015 J22
 '@T6G_MB_LIB.T6G(SCH_1):PAGE391_I19@PURE_QUANTA.PT5161LRS(CHIPS)':
 'GND138': CDS_PINID='GND138';
NODE_NAME     U6015 J4
 '@T6G_MB_LIB.T6G(SCH_1):PAGE391_I19@PURE_QUANTA.PT5161LRS(CHIPS)':
 'GND139': CDS_PINID='GND139';
NODE_NAME     U6015 K2
 '@T6G_MB_LIB.T6G(SCH_1):PAGE391_I19@PURE_QUANTA.PT5161LRS(CHIPS)':
 'GND140': CDS_PINID='GND140';
NODE_NAME     U6015 K34
 '@T6G_MB_LIB.T6G(SCH_1):PAGE391_I19@PURE_QUANTA.PT5161LRS(CHIPS)':
 'GND141': CDS_PINID='GND141';
NODE_NAME     U6015 L1
 '@T6G_MB_LIB.T6G(SCH_1):PAGE391_I19@PURE_QUANTA.PT5161LRS(CHIPS)':
 'GND142': CDS_PINID='GND142';
NODE_NAME     U6015 L35
 '@T6G_MB_LIB.T6G(SCH_1):PAGE391_I19@PURE_QUANTA.PT5161LRS(CHIPS)':
 'GND143': CDS_PINID='GND143';
NODE_NAME     U6015 T13
 '@T6G_MB_LIB.T6G(SCH_1):PAGE391_I19@PURE_QUANTA.PT5161LRS(CHIPS)':
 'GND144': CDS_PINID='GND144';
NODE_NAME     U6015 T22
 '@T6G_MB_LIB.T6G(SCH_1):PAGE391_I19@PURE_QUANTA.PT5161LRS(CHIPS)':
 'GND145': CDS_PINID='GND145';
NODE_NAME     U6015 T32
 '@T6G_MB_LIB.T6G(SCH_1):PAGE391_I19@PURE_QUANTA.PT5161LRS(CHIPS)':
 'GND146': CDS_PINID='GND146';
NODE_NAME     U6015 T4
 '@T6G_MB_LIB.T6G(SCH_1):PAGE391_I19@PURE_QUANTA.PT5161LRS(CHIPS)':
 'GND147': CDS_PINID='GND147';
NODE_NAME     U6015 U2
 '@T6G_MB_LIB.T6G(SCH_1):PAGE391_I19@PURE_QUANTA.PT5161LRS(CHIPS)':
 'GND148': CDS_PINID='GND148';
NODE_NAME     U6015 U34
 '@T6G_MB_LIB.T6G(SCH_1):PAGE391_I19@PURE_QUANTA.PT5161LRS(CHIPS)':
 'GND149': CDS_PINID='GND149';
NODE_NAME     U6015 V1
 '@T6G_MB_LIB.T6G(SCH_1):PAGE391_I19@PURE_QUANTA.PT5161LRS(CHIPS)':
 'GND150': CDS_PINID='GND150';
NODE_NAME     U6015 V35
 '@T6G_MB_LIB.T6G(SCH_1):PAGE391_I19@PURE_QUANTA.PT5161LRS(CHIPS)':
 'GND151': CDS_PINID='GND151';
NODE_NAME     C203 2
 '@T6G_MB_LIB.T6G(SCH_1):PAGE443_I8@PURE_QUANTA.Q_CAP(CHIPS)':
 'B': CDS_PINID='B';
NODE_NAME     C206 2
 '@T6G_MB_LIB.T6G(SCH_1):PAGE443_I9@PURE_QUANTA.Q_CAP(CHIPS)':
 'B': CDS_PINID='B';
NODE_NAME     C103 2
 '@T6G_MB_LIB.T6G(SCH_1):PAGE443_I13@PURE_QUANTA.Q_CAP(CHIPS)':
 'B': CDS_PINID='B';
NODE_NAME     C111 2
 '@T6G_MB_LIB.T6G(SCH_1):PAGE443_I14@PURE_QUANTA.Q_CAP(CHIPS)':
 'B': CDS_PINID='B';
NODE_NAME     C102 2
 '@T6G_MB_LIB.T6G(SCH_1):PAGE443_I16@PURE_QUANTA.Q_CAP(CHIPS)':
 'B': CDS_PINID='B';
NODE_NAME     C199 2
 '@T6G_MB_LIB.T6G(SCH_1):PAGE443_I17@PURE_QUANTA.Q_CAP(CHIPS)':
 'B': CDS_PINID='B';
NODE_NAME     C195 2
 '@T6G_MB_LIB.T6G(SCH_1):PAGE443_I18@PURE_QUANTA.Q_CAP(CHIPS)':
 'B': CDS_PINID='B';
NODE_NAME     C202 2
 '@T6G_MB_LIB.T6G(SCH_1):PAGE443_I20@PURE_QUANTA.Q_CAP(CHIPS)':
 'B': CDS_PINID='B';
NODE_NAME     C204 2
 '@T6G_MB_LIB.T6G(SCH_1):PAGE443_I22@PURE_QUANTA.Q_CAP(CHIPS)':
 'B': CDS_PINID='B';
NODE_NAME     C205 2
 '@T6G_MB_LIB.T6G(SCH_1):PAGE443_I23@PURE_QUANTA.Q_CAP(CHIPS)':
 'B': CDS_PINID='B';
NODE_NAME     C110 2
 '@T6G_MB_LIB.T6G(SCH_1):PAGE443_I24@PURE_QUANTA.Q_CAP(CHIPS)':
 'B': CDS_PINID='B';
NODE_NAME     C127 2
 '@T6G_MB_LIB.T6G(SCH_1):PAGE443_I25@PURE_QUANTA.Q_CAP(CHIPS)':
 'B': CDS_PINID='B';
NODE_NAME     C200 2
 '@T6G_MB_LIB.T6G(SCH_1):PAGE443_I26@PURE_QUANTA.Q_CAP(CHIPS)':
 'B': CDS_PINID='B';
NODE_NAME     C217 2
 '@T6G_MB_LIB.T6G(SCH_1):PAGE443_I27@PURE_QUANTA.Q_CAP(CHIPS)':
 'B': CDS_PINID='B';
NODE_NAME     C287 2
 '@T6G_MB_LIB.T6G(SCH_1):PAGE443_I28@PURE_QUANTA.Q_CAP(CHIPS)':
 'B': CDS_PINID='B';
NODE_NAME     C288 2
 '@T6G_MB_LIB.T6G(SCH_1):PAGE443_I29@PURE_QUANTA.Q_CAP(CHIPS)':
 'B': CDS_PINID='B';
NODE_NAME     C313 2
 '@T6G_MB_LIB.T6G(SCH_1):PAGE443_I34@PURE_QUANTA.Q_CAP(CHIPS)':
 'B': CDS_PINID='B';
NODE_NAME     C316 2
 '@T6G_MB_LIB.T6G(SCH_1):PAGE443_I37@PURE_QUANTA.Q_CAP(CHIPS)':
 'B': CDS_PINID='B';
NODE_NAME     C340 2
 '@T6G_MB_LIB.T6G(SCH_1):PAGE443_I38@PURE_QUANTA.Q_CAP(CHIPS)':
 'B': CDS_PINID='B';
NODE_NAME     C344 2
 '@T6G_MB_LIB.T6G(SCH_1):PAGE443_I39@PURE_QUANTA.Q_CAP(CHIPS)':
 'B': CDS_PINID='B';
NODE_NAME     C294 2
 '@T6G_MB_LIB.T6G(SCH_1):PAGE443_I40@PURE_QUANTA.Q_CAP(CHIPS)':
 'B': CDS_PINID='B';
NODE_NAME     C332 2
 '@T6G_MB_LIB.T6G(SCH_1):PAGE443_I41@PURE_QUANTA.Q_CAP(CHIPS)':
 'B': CDS_PINID='B';
NODE_NAME     C307 2
 '@T6G_MB_LIB.T6G(SCH_1):PAGE443_I42@PURE_QUANTA.Q_CAP(CHIPS)':
 'B': CDS_PINID='B';
NODE_NAME     C326 2
 '@T6G_MB_LIB.T6G(SCH_1):PAGE443_I43@PURE_QUANTA.Q_CAP(CHIPS)':
 'B': CDS_PINID='B';
NODE_NAME     C321 2
 '@T6G_MB_LIB.T6G(SCH_1):PAGE443_I44@PURE_QUANTA.Q_CAP(CHIPS)':
 'B': CDS_PINID='B';
NODE_NAME     C325 2
 '@T6G_MB_LIB.T6G(SCH_1):PAGE443_I45@PURE_QUANTA.Q_CAP(CHIPS)':
 'B': CDS_PINID='B';
NODE_NAME     C331 2
 '@T6G_MB_LIB.T6G(SCH_1):PAGE443_I46@PURE_QUANTA.Q_CAP(CHIPS)':
 'B': CDS_PINID='B';
NODE_NAME     C330 2
 '@T6G_MB_LIB.T6G(SCH_1):PAGE443_I47@PURE_QUANTA.Q_CAP(CHIPS)':
 'B': CDS_PINID='B';
NODE_NAME     C312 2
 '@T6G_MB_LIB.T6G(SCH_1):PAGE443_I48@PURE_QUANTA.Q_CAP(CHIPS)':
 'B': CDS_PINID='B';
NODE_NAME     C349 2
 '@T6G_MB_LIB.T6G(SCH_1):PAGE443_I49@PURE_QUANTA.Q_CAP(CHIPS)':
 'B': CDS_PINID='B';
NODE_NAME     C291 2
 '@T6G_MB_LIB.T6G(SCH_1):PAGE443_I50@PURE_QUANTA.Q_CAP(CHIPS)':
 'B': CDS_PINID='B';
NODE_NAME     C319 2
 '@T6G_MB_LIB.T6G(SCH_1):PAGE443_I51@PURE_QUANTA.Q_CAP(CHIPS)':
 'B': CDS_PINID='B';
NODE_NAME     C314 2
 '@T6G_MB_LIB.T6G(SCH_1):PAGE443_I52@PURE_QUANTA.Q_CAP(CHIPS)':
 'B': CDS_PINID='B';
NODE_NAME     C337 2
 '@T6G_MB_LIB.T6G(SCH_1):PAGE443_I53@PURE_QUANTA.Q_CAP(CHIPS)':
 'B': CDS_PINID='B';
NODE_NAME     C343 2
 '@T6G_MB_LIB.T6G(SCH_1):PAGE443_I54@PURE_QUANTA.Q_CAP(CHIPS)':
 'B': CDS_PINID='B';
NODE_NAME     C336 2
 '@T6G_MB_LIB.T6G(SCH_1):PAGE443_I55@PURE_QUANTA.Q_CAP(CHIPS)':
 'B': CDS_PINID='B';
NODE_NAME     C346 2
 '@T6G_MB_LIB.T6G(SCH_1):PAGE443_I57@PURE_QUANTA.Q_CAP(CHIPS)':
 'B': CDS_PINID='B';
NODE_NAME     C293 2
 '@T6G_MB_LIB.T6G(SCH_1):PAGE443_I58@PURE_QUANTA.Q_CAP(CHIPS)':
 'B': CDS_PINID='B';
NODE_NAME     C301 2
 '@T6G_MB_LIB.T6G(SCH_1):PAGE443_I59@PURE_QUANTA.Q_CAP(CHIPS)':
 'B': CDS_PINID='B';
NODE_NAME     C322 2
 '@T6G_MB_LIB.T6G(SCH_1):PAGE443_I60@PURE_QUANTA.Q_CAP(CHIPS)':
 'B': CDS_PINID='B';
NODE_NAME     C334 2
 '@T6G_MB_LIB.T6G(SCH_1):PAGE443_I62@PURE_QUANTA.Q_CAP(CHIPS)':
 'B': CDS_PINID='B';
NODE_NAME     C289 2
 '@T6G_MB_LIB.T6G(SCH_1):PAGE443_I65@PURE_QUANTA.Q_CAP(CHIPS)':
 'B': CDS_PINID='B';
NODE_NAME     C353 2
 '@T6G_MB_LIB.T6G(SCH_1):PAGE443_I66@PURE_QUANTA.Q_CAP(CHIPS)':
 'B': CDS_PINID='B';
NODE_NAME     C317 2
 '@T6G_MB_LIB.T6G(SCH_1):PAGE443_I67@PURE_QUANTA.Q_CAP(CHIPS)':
 'B': CDS_PINID='B';
NODE_NAME     C320 2
 '@T6G_MB_LIB.T6G(SCH_1):PAGE443_I69@PURE_QUANTA.Q_CAP(CHIPS)':
 'B': CDS_PINID='B';
NODE_NAME     C324 2
 '@T6G_MB_LIB.T6G(SCH_1):PAGE443_I70@PURE_QUANTA.Q_CAP(CHIPS)':
 'B': CDS_PINID='B';
NODE_NAME     C328 2
 '@T6G_MB_LIB.T6G(SCH_1):PAGE443_I71@PURE_QUANTA.Q_CAP(CHIPS)':
 'B': CDS_PINID='B';
NODE_NAME     C323 2
 '@T6G_MB_LIB.T6G(SCH_1):PAGE443_I72@PURE_QUANTA.Q_CAP(CHIPS)':
 'B': CDS_PINID='B';
NODE_NAME     C327 2
 '@T6G_MB_LIB.T6G(SCH_1):PAGE443_I73@PURE_QUANTA.Q_CAP(CHIPS)':
 'B': CDS_PINID='B';
NODE_NAME     C329 2
 '@T6G_MB_LIB.T6G(SCH_1):PAGE443_I74@PURE_QUANTA.Q_CAP(CHIPS)':
 'B': CDS_PINID='B';
NODE_NAME     C335 2
 '@T6G_MB_LIB.T6G(SCH_1):PAGE443_I75@PURE_QUANTA.Q_CAP(CHIPS)':
 'B': CDS_PINID='B';
NODE_NAME     C351 2
 '@T6G_MB_LIB.T6G(SCH_1):PAGE443_I76@PURE_QUANTA.Q_CAP(CHIPS)':
 'B': CDS_PINID='B';
NODE_NAME     C318 2
 '@T6G_MB_LIB.T6G(SCH_1):PAGE443_I77@PURE_QUANTA.Q_CAP(CHIPS)':
 'B': CDS_PINID='B';
NODE_NAME     C338 2
 '@T6G_MB_LIB.T6G(SCH_1):PAGE443_I78@PURE_QUANTA.Q_CAP(CHIPS)':
 'B': CDS_PINID='B';
NODE_NAME     C342 2
 '@T6G_MB_LIB.T6G(SCH_1):PAGE443_I79@PURE_QUANTA.Q_CAP(CHIPS)':
 'B': CDS_PINID='B';
NODE_NAME     C339 2
 '@T6G_MB_LIB.T6G(SCH_1):PAGE443_I80@PURE_QUANTA.Q_CAP(CHIPS)':
 'B': CDS_PINID='B';
NODE_NAME     C354 2
 '@T6G_MB_LIB.T6G(SCH_1):PAGE443_I81@PURE_QUANTA.Q_CAP(CHIPS)':
 'B': CDS_PINID='B';
NODE_NAME     C300 2
 '@T6G_MB_LIB.T6G(SCH_1):PAGE443_I82@PURE_QUANTA.Q_CAP(CHIPS)':
 'B': CDS_PINID='B';
NODE_NAME     C311 2
 '@T6G_MB_LIB.T6G(SCH_1):PAGE443_I84@PURE_QUANTA.Q_CAP(CHIPS)':
 'B': CDS_PINID='B';
NODE_NAME     C292 2
 '@T6G_MB_LIB.T6G(SCH_1):PAGE443_I85@PURE_QUANTA.Q_CAP(CHIPS)':
 'B': CDS_PINID='B';
NODE_NAME     C290 2
 '@T6G_MB_LIB.T6G(SCH_1):PAGE443_I86@PURE_QUANTA.Q_CAP(CHIPS)':
 'B': CDS_PINID='B';
NODE_NAME     C333 2
 '@T6G_MB_LIB.T6G(SCH_1):PAGE443_I87@PURE_QUANTA.Q_CAP(CHIPS)':
 'B': CDS_PINID='B';
NODE_NAME     R782 2
 '@T6G_MB_LIB.T6G(SCH_1):PAGE392_I21@PURE_QUANTA.Q_RES(CHIPS)':
 'B': CDS_PINID='B';
NODE_NAME     R783 2
 '@T6G_MB_LIB.T6G(SCH_1):PAGE392_I22@PURE_QUANTA.Q_RES(CHIPS)':
 'B': CDS_PINID='B';
NODE_NAME     R785 2
 '@T6G_MB_LIB.T6G(SCH_1):PAGE392_I23@PURE_QUANTA.Q_RES(CHIPS)':
 'B': CDS_PINID='B';
NODE_NAME     R625 2
 '@T6G_MB_LIB.T6G(SCH_1):PAGE392_I31@PURE_QUANTA.Q_RES(CHIPS)':
 'B': CDS_PINID='B';
NODE_NAME     R626 2
 '@T6G_MB_LIB.T6G(SCH_1):PAGE392_I32@PURE_QUANTA.Q_RES(CHIPS)':
 'B': CDS_PINID='B';
NODE_NAME     U6015 E30
 '@T6G_MB_LIB.T6G(SCH_1):PAGE392_I47@PURE_QUANTA.PT5161LRS(CHIPS)':
 'T_SENSE': CDS_PINID='T_SENSE';
NODE_NAME     R787 2
 '@T6G_MB_LIB.T6G(SCH_1):PAGE392_I51@PURE_QUANTA.Q_RES(CHIPS)':
 'B': CDS_PINID='B';
NODE_NAME     R791 2
 '@T6G_MB_LIB.T6G(SCH_1):PAGE392_I52@PURE_QUANTA.Q_RES(CHIPS)':
 'B': CDS_PINID='B';
NODE_NAME     R792 2
 '@T6G_MB_LIB.T6G(SCH_1):PAGE392_I54@PURE_QUANTA.Q_RES(CHIPS)':
 'B': CDS_PINID='B';
NODE_NAME     R794 2
 '@T6G_MB_LIB.T6G(SCH_1):PAGE392_I65@PURE_QUANTA.Q_RES(CHIPS)':
 'B': CDS_PINID='B';
NODE_NAME     R752 2
 '@T6G_MB_LIB.T6G(SCH_1):PAGE392_I92@PURE_QUANTA.Q_RES(CHIPS)':
 'B': CDS_PINID='B';
NODE_NAME     R749 2
 '@T6G_MB_LIB.T6G(SCH_1):PAGE392_I93@PURE_QUANTA.Q_RES(CHIPS)':
 'B': CDS_PINID='B';
NODE_NAME     R6744 2
 '@T6G_MB_LIB.T6G(SCH_1):PAGE467_I2@PURE_QUANTA.Q_RES(CHIPS)':
 'B': CDS_PINID='B';
NODE_NAME     R6745 2
 '@T6G_MB_LIB.T6G(SCH_1):PAGE467_I4@PURE_QUANTA.Q_RES(CHIPS)':
 'B': CDS_PINID='B';
NODE_NAME     C7500 2
 '@T6G_MB_LIB.T6G(SCH_1):PAGE378_I88@PURE_QUANTA.Q_CAP(CHIPS)':
 'B': CDS_PINID='B';
NODE_NAME     R6773 2
 '@T6G_MB_LIB.T6G(SCH_1):PAGE378_I94@PURE_QUANTA.Q_RES(CHIPS)':
 'B': CDS_PINID='B';
NODE_NAME     R6774 2
 '@T6G_MB_LIB.T6G(SCH_1):PAGE378_I95@PURE_QUANTA.Q_RES(CHIPS)':
 'B': CDS_PINID='B';
NODE_NAME     R6775 2
 '@T6G_MB_LIB.T6G(SCH_1):PAGE378_I97@PURE_QUANTA.Q_RES(CHIPS)':
 'B': CDS_PINID='B';
NODE_NAME     R6778 2
 '@T6G_MB_LIB.T6G(SCH_1):PAGE378_I107@PURE_QUANTA.Q_RES(CHIPS)':
 'B': CDS_PINID='B';
NODE_NAME     R845 2
 '@T6G_MB_LIB.T6G(SCH_1):PAGE377_I2@PURE_QUANTA.Q_RES(CHIPS)':
 'B': CDS_PINID='B';
NODE_NAME     R846 2
 '@T6G_MB_LIB.T6G(SCH_1):PAGE377_I3@PURE_QUANTA.Q_RES(CHIPS)':
 'B': CDS_PINID='B';
NODE_NAME     R847 2
 '@T6G_MB_LIB.T6G(SCH_1):PAGE377_I8@PURE_QUANTA.Q_RES(CHIPS)':
 'B': CDS_PINID='B';
NODE_NAME     R849 2
 '@T6G_MB_LIB.T6G(SCH_1):PAGE377_I16@PURE_QUANTA.Q_RES(CHIPS)':
 'B': CDS_PINID='B';
NODE_NAME     C365 2
 '@T6G_MB_LIB.T6G(SCH_1):PAGE377_I55@PURE_QUANTA.Q_CAP(CHIPS)':
 'B': CDS_PINID='B';
NODE_NAME     U22 12
 '@T6G_MB_LIB.T6G(SCH_1):PAGE377_I94@PURE_QUANTA.TCA9548APWR(CHIPS)':
 'GND': CDS_PINID='GND';
NODE_NAME     R6786 2
 '@T6G_MB_LIB.T6G(SCH_1):PAGE475_I208@PURE_QUANTA.Q_RES(CHIPS)':
 'B': CDS_PINID='B';
NODE_NAME     R6787 2
 '@T6G_MB_LIB.T6G(SCH_1):PAGE477_I90@PURE_QUANTA.Q_RES(CHIPS)':
 'B': CDS_PINID='B';
NODE_NAME     R6713 2
 '@T6G_MB_LIB.T6G(SCH_1):PAGE401_I103@PURE_QUANTA.Q_RES(CHIPS)':
 'B': CDS_PINID='B';
NODE_NAME     R6715 2
 '@T6G_MB_LIB.T6G(SCH_1):PAGE401_I105@PURE_QUANTA.Q_RES(CHIPS)':
 'B': CDS_PINID='B';
NODE_NAME     R6717 2
 '@T6G_MB_LIB.T6G(SCH_1):PAGE401_I106@PURE_QUANTA.Q_RES(CHIPS)':
 'B': CDS_PINID='B';
NODE_NAME     R741 2
 '@T6G_MB_LIB.T6G(SCH_1):PAGE392_I101@PURE_QUANTA.Q_RES(CHIPS)':
 'B': CDS_PINID='B';
NODE_NAME     R746 2
 '@T6G_MB_LIB.T6G(SCH_1):PAGE392_I102@PURE_QUANTA.Q_RES(CHIPS)':
 'B': CDS_PINID='B';
NODE_NAME     R796 2
 '@T6G_MB_LIB.T6G(SCH_1):PAGE392_I105@PURE_QUANTA.Q_RES(CHIPS)':
 'B': CDS_PINID='B';
NODE_NAME     C7501 2
 '@T6G_MB_LIB.T6G(SCH_1):PAGE399_I11@PURE_QUANTA.Q_CAP(CHIPS)':
 'B': CDS_PINID='B';
NODE_NAME     R6788 2
 '@T6G_MB_LIB.T6G(SCH_1):PAGE399_I13@PURE_QUANTA.Q_RES(CHIPS)':
 'B': CDS_PINID='B';
NODE_NAME     R6789 2
 '@T6G_MB_LIB.T6G(SCH_1):PAGE442_I19@PURE_QUANTA.Q_RES(CHIPS)':
 'B': CDS_PINID='B';
NODE_NAME     C7502 2
 '@T6G_MB_LIB.T6G(SCH_1):PAGE442_I22@PURE_QUANTA.Q_CAP(CHIPS)':
 'B': CDS_PINID='B';
NODE_NAME     R6790 2
 '@T6G_MB_LIB.T6G(SCH_1):PAGE453_I19@PURE_QUANTA.Q_RES(CHIPS)':
 'B': CDS_PINID='B';
NODE_NAME     C7503 2
 '@T6G_MB_LIB.T6G(SCH_1):PAGE453_I23@PURE_QUANTA.Q_CAP(CHIPS)':
 'B': CDS_PINID='B';
NODE_NAME     C7504 2
 '@T6G_MB_LIB.T6G(SCH_1):PAGE464_I19@PURE_QUANTA.Q_CAP(CHIPS)':
 'B': CDS_PINID='B';
NODE_NAME     R6791 2
 '@T6G_MB_LIB.T6G(SCH_1):PAGE464_I22@PURE_QUANTA.Q_RES(CHIPS)':
 'B': CDS_PINID='B';
NODE_NAME     R875 2
 '@T6G_MB_LIB.T6G(SCH_1):PAGE451_I19@PURE_QUANTA.Q_RES(CHIPS)':
 'B': CDS_PINID='B';
NODE_NAME     R876 2
 '@T6G_MB_LIB.T6G(SCH_1):PAGE451_I20@PURE_QUANTA.Q_RES(CHIPS)':
 'B': CDS_PINID='B';
NODE_NAME     R640 2
 '@T6G_MB_LIB.T6G(SCH_1):PAGE451_I36@PURE_QUANTA.Q_RES(CHIPS)':
 'B': CDS_PINID='B';
NODE_NAME     R879 2
 '@T6G_MB_LIB.T6G(SCH_1):PAGE451_I42@PURE_QUANTA.Q_RES(CHIPS)':
 'B': CDS_PINID='B';
NODE_NAME     R881 2
 '@T6G_MB_LIB.T6G(SCH_1):PAGE451_I43@PURE_QUANTA.Q_RES(CHIPS)':
 'B': CDS_PINID='B';
NODE_NAME     R883 2
 '@T6G_MB_LIB.T6G(SCH_1):PAGE451_I45@PURE_QUANTA.Q_RES(CHIPS)':
 'B': CDS_PINID='B';
NODE_NAME     R884 2
 '@T6G_MB_LIB.T6G(SCH_1):PAGE451_I46@PURE_QUANTA.Q_RES(CHIPS)':
 'B': CDS_PINID='B';
NODE_NAME     R886 2
 '@T6G_MB_LIB.T6G(SCH_1):PAGE451_I58@PURE_QUANTA.Q_RES(CHIPS)':
 'B': CDS_PINID='B';
NODE_NAME     R863 2
 '@T6G_MB_LIB.T6G(SCH_1):PAGE451_I71@PURE_QUANTA.Q_RES(CHIPS)':
 'B': CDS_PINID='B';
NODE_NAME     R865 2
 '@T6G_MB_LIB.T6G(SCH_1):PAGE451_I72@PURE_QUANTA.Q_RES(CHIPS)':
 'B': CDS_PINID='B';
NODE_NAME     R892 2
 '@T6G_MB_LIB.T6G(SCH_1):PAGE451_I76@PURE_QUANTA.Q_RES(CHIPS)':
 'B': CDS_PINID='B';
NODE_NAME     R867 2
 '@T6G_MB_LIB.T6G(SCH_1):PAGE451_I80@PURE_QUANTA.Q_RES(CHIPS)':
 'B': CDS_PINID='B';
NODE_NAME     R866 2
 '@T6G_MB_LIB.T6G(SCH_1):PAGE451_I82@PURE_QUANTA.Q_RES(CHIPS)':
 'B': CDS_PINID='B';
NODE_NAME     R637 2
 '@T6G_MB_LIB.T6G(SCH_1):PAGE451_I92@PURE_QUANTA.Q_RES(CHIPS)':
 'B': CDS_PINID='B';
NODE_NAME     U6016 E30
 '@T6G_MB_LIB.T6G(SCH_1):PAGE451_I97@PURE_QUANTA.PT5161LRS(CHIPS)':
 'T_SENSE': CDS_PINID='T_SENSE';
NODE_NAME     R6797 2
 '@T6G_MB_LIB.T6G(SCH_1):PAGE452_I15@PURE_QUANTA.Q_RES(CHIPS)':
 'B': CDS_PINID='B';
NODE_NAME     R6796 2
 '@T6G_MB_LIB.T6G(SCH_1):PAGE452_I18@PURE_QUANTA.Q_RES(CHIPS)':
 'B': CDS_PINID='B';
NODE_NAME     U6016 AC13
 '@T6G_MB_LIB.T6G(SCH_1):PAGE452_I19@PURE_QUANTA.PT5161LRS(CHIPS)':
 'GND1': CDS_PINID='GND1';
NODE_NAME     U6016 AC22
 '@T6G_MB_LIB.T6G(SCH_1):PAGE452_I19@PURE_QUANTA.PT5161LRS(CHIPS)':
 'GND2': CDS_PINID='GND2';
NODE_NAME     U6016 AC32
 '@T6G_MB_LIB.T6G(SCH_1):PAGE452_I19@PURE_QUANTA.PT5161LRS(CHIPS)':
 'GND3': CDS_PINID='GND3';
NODE_NAME     U6016 AC4
 '@T6G_MB_LIB.T6G(SCH_1):PAGE452_I19@PURE_QUANTA.PT5161LRS(CHIPS)':
 'GND4': CDS_PINID='GND4';
NODE_NAME     U6016 AD2
 '@T6G_MB_LIB.T6G(SCH_1):PAGE452_I19@PURE_QUANTA.PT5161LRS(CHIPS)':
 'GND5': CDS_PINID='GND5';
NODE_NAME     U6016 AD34
 '@T6G_MB_LIB.T6G(SCH_1):PAGE452_I19@PURE_QUANTA.PT5161LRS(CHIPS)':
 'GND6': CDS_PINID='GND6';
NODE_NAME     U6016 AE1
 '@T6G_MB_LIB.T6G(SCH_1):PAGE452_I19@PURE_QUANTA.PT5161LRS(CHIPS)':
 'GND7': CDS_PINID='GND7';
NODE_NAME     U6016 AE35
 '@T6G_MB_LIB.T6G(SCH_1):PAGE452_I19@PURE_QUANTA.PT5161LRS(CHIPS)':
 'GND8': CDS_PINID='GND8';
NODE_NAME     U6016 AK13
 '@T6G_MB_LIB.T6G(SCH_1):PAGE452_I19@PURE_QUANTA.PT5161LRS(CHIPS)':
 'GND9': CDS_PINID='GND9';
NODE_NAME     U6016 AK22
 '@T6G_MB_LIB.T6G(SCH_1):PAGE452_I19@PURE_QUANTA.PT5161LRS(CHIPS)':
 'GND10': CDS_PINID='GND10';
NODE_NAME     U6016 AK32
 '@T6G_MB_LIB.T6G(SCH_1):PAGE452_I19@PURE_QUANTA.PT5161LRS(CHIPS)':
 'GND11': CDS_PINID='GND11';
NODE_NAME     U6016 AK4
 '@T6G_MB_LIB.T6G(SCH_1):PAGE452_I19@PURE_QUANTA.PT5161LRS(CHIPS)':
 'GND12': CDS_PINID='GND12';
NODE_NAME     U6016 AL2
 '@T6G_MB_LIB.T6G(SCH_1):PAGE452_I19@PURE_QUANTA.PT5161LRS(CHIPS)':
 'GND13': CDS_PINID='GND13';
NODE_NAME     U6016 AL34
 '@T6G_MB_LIB.T6G(SCH_1):PAGE452_I19@PURE_QUANTA.PT5161LRS(CHIPS)':
 'GND14': CDS_PINID='GND14';
NODE_NAME     U6016 AM1
 '@T6G_MB_LIB.T6G(SCH_1):PAGE452_I19@PURE_QUANTA.PT5161LRS(CHIPS)':
 'GND15': CDS_PINID='GND15';
NODE_NAME     U6016 AM35
 '@T6G_MB_LIB.T6G(SCH_1):PAGE452_I19@PURE_QUANTA.PT5161LRS(CHIPS)':
 'GND16': CDS_PINID='GND16';
NODE_NAME     U6016 AU13
 '@T6G_MB_LIB.T6G(SCH_1):PAGE452_I19@PURE_QUANTA.PT5161LRS(CHIPS)':
 'GND17': CDS_PINID='GND17';
NODE_NAME     U6016 AU22
 '@T6G_MB_LIB.T6G(SCH_1):PAGE452_I19@PURE_QUANTA.PT5161LRS(CHIPS)':
 'GND18': CDS_PINID='GND18';
NODE_NAME     U6016 AU32
 '@T6G_MB_LIB.T6G(SCH_1):PAGE452_I19@PURE_QUANTA.PT5161LRS(CHIPS)':
 'GND19': CDS_PINID='GND19';
NODE_NAME     U6016 AU4
 '@T6G_MB_LIB.T6G(SCH_1):PAGE452_I19@PURE_QUANTA.PT5161LRS(CHIPS)':
 'GND20': CDS_PINID='GND20';
NODE_NAME     U6016 AV2
 '@T6G_MB_LIB.T6G(SCH_1):PAGE452_I19@PURE_QUANTA.PT5161LRS(CHIPS)':
 'GND21': CDS_PINID='GND21';
NODE_NAME     U6016 AV34
 '@T6G_MB_LIB.T6G(SCH_1):PAGE452_I19@PURE_QUANTA.PT5161LRS(CHIPS)':
 'GND22': CDS_PINID='GND22';
NODE_NAME     U6016 AW1
 '@T6G_MB_LIB.T6G(SCH_1):PAGE452_I19@PURE_QUANTA.PT5161LRS(CHIPS)':
 'GND23': CDS_PINID='GND23';
NODE_NAME     U6016 AW35
 '@T6G_MB_LIB.T6G(SCH_1):PAGE452_I19@PURE_QUANTA.PT5161LRS(CHIPS)':
 'GND24': CDS_PINID='GND24';
NODE_NAME     U6016 B19
 '@T6G_MB_LIB.T6G(SCH_1):PAGE452_I19@PURE_QUANTA.PT5161LRS(CHIPS)':
 'GND25': CDS_PINID='GND25';
NODE_NAME     U6016 BD13
 '@T6G_MB_LIB.T6G(SCH_1):PAGE452_I19@PURE_QUANTA.PT5161LRS(CHIPS)':
 'GND26': CDS_PINID='GND26';
NODE_NAME     U6016 BD22
 '@T6G_MB_LIB.T6G(SCH_1):PAGE452_I19@PURE_QUANTA.PT5161LRS(CHIPS)':
 'GND27': CDS_PINID='GND27';
NODE_NAME     U6016 BD32
 '@T6G_MB_LIB.T6G(SCH_1):PAGE452_I19@PURE_QUANTA.PT5161LRS(CHIPS)':
 'GND28': CDS_PINID='GND28';
NODE_NAME     U6016 BD4
 '@T6G_MB_LIB.T6G(SCH_1):PAGE452_I19@PURE_QUANTA.PT5161LRS(CHIPS)':
 'GND29': CDS_PINID='GND29';
NODE_NAME     U6016 BE2
 '@T6G_MB_LIB.T6G(SCH_1):PAGE452_I19@PURE_QUANTA.PT5161LRS(CHIPS)':
 'GND30': CDS_PINID='GND30';
NODE_NAME     U6016 BE34
 '@T6G_MB_LIB.T6G(SCH_1):PAGE452_I19@PURE_QUANTA.PT5161LRS(CHIPS)':
 'GND31': CDS_PINID='GND31';
NODE_NAME     U6016 BF1
 '@T6G_MB_LIB.T6G(SCH_1):PAGE452_I19@PURE_QUANTA.PT5161LRS(CHIPS)':
 'GND32': CDS_PINID='GND32';
NODE_NAME     U6016 BF35
 '@T6G_MB_LIB.T6G(SCH_1):PAGE452_I19@PURE_QUANTA.PT5161LRS(CHIPS)':
 'GND33': CDS_PINID='GND33';
NODE_NAME     U6016 BL13
 '@T6G_MB_LIB.T6G(SCH_1):PAGE452_I19@PURE_QUANTA.PT5161LRS(CHIPS)':
 'GND34': CDS_PINID='GND34';
NODE_NAME     U6016 BL22
 '@T6G_MB_LIB.T6G(SCH_1):PAGE452_I19@PURE_QUANTA.PT5161LRS(CHIPS)':
 'GND35': CDS_PINID='GND35';
NODE_NAME     U6016 BL32
 '@T6G_MB_LIB.T6G(SCH_1):PAGE452_I19@PURE_QUANTA.PT5161LRS(CHIPS)':
 'GND36': CDS_PINID='GND36';
NODE_NAME     U6016 BL4
 '@T6G_MB_LIB.T6G(SCH_1):PAGE452_I19@PURE_QUANTA.PT5161LRS(CHIPS)':
 'GND37': CDS_PINID='GND37';
NODE_NAME     U6016 BM2
 '@T6G_MB_LIB.T6G(SCH_1):PAGE452_I19@PURE_QUANTA.PT5161LRS(CHIPS)':
 'GND38': CDS_PINID='GND38';
NODE_NAME     U6016 BM34
 '@T6G_MB_LIB.T6G(SCH_1):PAGE452_I19@PURE_QUANTA.PT5161LRS(CHIPS)':
 'GND39': CDS_PINID='GND39';
NODE_NAME     U6016 BN1
 '@T6G_MB_LIB.T6G(SCH_1):PAGE452_I19@PURE_QUANTA.PT5161LRS(CHIPS)':
 'GND40': CDS_PINID='GND40';
NODE_NAME     U6016 BN35
 '@T6G_MB_LIB.T6G(SCH_1):PAGE452_I19@PURE_QUANTA.PT5161LRS(CHIPS)':
 'GND41': CDS_PINID='GND41';
NODE_NAME     U6016 BV13
 '@T6G_MB_LIB.T6G(SCH_1):PAGE452_I19@PURE_QUANTA.PT5161LRS(CHIPS)':
 'GND42': CDS_PINID='GND42';
NODE_NAME     U6016 BV22
 '@T6G_MB_LIB.T6G(SCH_1):PAGE452_I19@PURE_QUANTA.PT5161LRS(CHIPS)':
 'GND43': CDS_PINID='GND43';
NODE_NAME     U6016 BV32
 '@T6G_MB_LIB.T6G(SCH_1):PAGE452_I19@PURE_QUANTA.PT5161LRS(CHIPS)':
 'GND44': CDS_PINID='GND44';
NODE_NAME     U6016 BV4
 '@T6G_MB_LIB.T6G(SCH_1):PAGE452_I19@PURE_QUANTA.PT5161LRS(CHIPS)':
 'GND45': CDS_PINID='GND45';
NODE_NAME     U6016 BW2
 '@T6G_MB_LIB.T6G(SCH_1):PAGE452_I19@PURE_QUANTA.PT5161LRS(CHIPS)':
 'GND46': CDS_PINID='GND46';
NODE_NAME     U6016 BW34
 '@T6G_MB_LIB.T6G(SCH_1):PAGE452_I19@PURE_QUANTA.PT5161LRS(CHIPS)':
 'GND47': CDS_PINID='GND47';
NODE_NAME     U6016 BY1
 '@T6G_MB_LIB.T6G(SCH_1):PAGE452_I19@PURE_QUANTA.PT5161LRS(CHIPS)':
 'GND48': CDS_PINID='GND48';
NODE_NAME     U6016 BY35
 '@T6G_MB_LIB.T6G(SCH_1):PAGE452_I19@PURE_QUANTA.PT5161LRS(CHIPS)':
 'GND49': CDS_PINID='GND49';
NODE_NAME     U6016 CE13
 '@T6G_MB_LIB.T6G(SCH_1):PAGE452_I19@PURE_QUANTA.PT5161LRS(CHIPS)':
 'GND50': CDS_PINID='GND50';
NODE_NAME     U6016 CE22
 '@T6G_MB_LIB.T6G(SCH_1):PAGE452_I19@PURE_QUANTA.PT5161LRS(CHIPS)':
 'GND51': CDS_PINID='GND51';
NODE_NAME     U6016 CE32
 '@T6G_MB_LIB.T6G(SCH_1):PAGE452_I19@PURE_QUANTA.PT5161LRS(CHIPS)':
 'GND52': CDS_PINID='GND52';
NODE_NAME     U6016 CE4
 '@T6G_MB_LIB.T6G(SCH_1):PAGE452_I19@PURE_QUANTA.PT5161LRS(CHIPS)':
 'GND53': CDS_PINID='GND53';
NODE_NAME     U6016 CF2
 '@T6G_MB_LIB.T6G(SCH_1):PAGE452_I19@PURE_QUANTA.PT5161LRS(CHIPS)':
 'GND54': CDS_PINID='GND54';
NODE_NAME     U6016 CF34
 '@T6G_MB_LIB.T6G(SCH_1):PAGE452_I19@PURE_QUANTA.PT5161LRS(CHIPS)':
 'GND55': CDS_PINID='GND55';
NODE_NAME     U6016 CG1
 '@T6G_MB_LIB.T6G(SCH_1):PAGE452_I19@PURE_QUANTA.PT5161LRS(CHIPS)':
 'GND56': CDS_PINID='GND56';
NODE_NAME     U6016 CG35
 '@T6G_MB_LIB.T6G(SCH_1):PAGE452_I19@PURE_QUANTA.PT5161LRS(CHIPS)':
 'GND57': CDS_PINID='GND57';
NODE_NAME     U6016 CM13
 '@T6G_MB_LIB.T6G(SCH_1):PAGE452_I19@PURE_QUANTA.PT5161LRS(CHIPS)':
 'GND58': CDS_PINID='GND58';
NODE_NAME     U6016 CM22
 '@T6G_MB_LIB.T6G(SCH_1):PAGE452_I19@PURE_QUANTA.PT5161LRS(CHIPS)':
 'GND59': CDS_PINID='GND59';
NODE_NAME     U6016 CM32
 '@T6G_MB_LIB.T6G(SCH_1):PAGE452_I19@PURE_QUANTA.PT5161LRS(CHIPS)':
 'GND60': CDS_PINID='GND60';
NODE_NAME     U6016 CM4
 '@T6G_MB_LIB.T6G(SCH_1):PAGE452_I19@PURE_QUANTA.PT5161LRS(CHIPS)':
 'GND61': CDS_PINID='GND61';
NODE_NAME     U6016 CN2
 '@T6G_MB_LIB.T6G(SCH_1):PAGE452_I19@PURE_QUANTA.PT5161LRS(CHIPS)':
 'GND62': CDS_PINID='GND62';
NODE_NAME     U6016 CN34
 '@T6G_MB_LIB.T6G(SCH_1):PAGE452_I19@PURE_QUANTA.PT5161LRS(CHIPS)':
 'GND63': CDS_PINID='GND63';
NODE_NAME     U6016 CP1
 '@T6G_MB_LIB.T6G(SCH_1):PAGE452_I19@PURE_QUANTA.PT5161LRS(CHIPS)':
 'GND64': CDS_PINID='GND64';
NODE_NAME     U6016 CP35
 '@T6G_MB_LIB.T6G(SCH_1):PAGE452_I19@PURE_QUANTA.PT5161LRS(CHIPS)':
 'GND65': CDS_PINID='GND65';
NODE_NAME     U6016 CW13
 '@T6G_MB_LIB.T6G(SCH_1):PAGE452_I19@PURE_QUANTA.PT5161LRS(CHIPS)':
 'GND66': CDS_PINID='GND66';
NODE_NAME     U6016 CW22
 '@T6G_MB_LIB.T6G(SCH_1):PAGE452_I19@PURE_QUANTA.PT5161LRS(CHIPS)':
 'GND67': CDS_PINID='GND67';
NODE_NAME     U6016 CW32
 '@T6G_MB_LIB.T6G(SCH_1):PAGE452_I19@PURE_QUANTA.PT5161LRS(CHIPS)':
 'GND68': CDS_PINID='GND68';
NODE_NAME     U6016 CW4
 '@T6G_MB_LIB.T6G(SCH_1):PAGE452_I19@PURE_QUANTA.PT5161LRS(CHIPS)':
 'GND69': CDS_PINID='GND69';
NODE_NAME     U6016 CY2
 '@T6G_MB_LIB.T6G(SCH_1):PAGE452_I19@PURE_QUANTA.PT5161LRS(CHIPS)':
 'GND70': CDS_PINID='GND70';
NODE_NAME     U6016 CY34
 '@T6G_MB_LIB.T6G(SCH_1):PAGE452_I19@PURE_QUANTA.PT5161LRS(CHIPS)':
 'GND71': CDS_PINID='GND71';
NODE_NAME     U6016 DA1
 '@T6G_MB_LIB.T6G(SCH_1):PAGE452_I19@PURE_QUANTA.PT5161LRS(CHIPS)':
 'GND72': CDS_PINID='GND72';
NODE_NAME     U6016 DA35
 '@T6G_MB_LIB.T6G(SCH_1):PAGE452_I19@PURE_QUANTA.PT5161LRS(CHIPS)':
 'GND73': CDS_PINID='GND73';
NODE_NAME     U6016 DF13
 '@T6G_MB_LIB.T6G(SCH_1):PAGE452_I19@PURE_QUANTA.PT5161LRS(CHIPS)':
 'GND74': CDS_PINID='GND74';
NODE_NAME     U6016 DF22
 '@T6G_MB_LIB.T6G(SCH_1):PAGE452_I19@PURE_QUANTA.PT5161LRS(CHIPS)':
 'GND75': CDS_PINID='GND75';
NODE_NAME     U6016 DF32
 '@T6G_MB_LIB.T6G(SCH_1):PAGE452_I19@PURE_QUANTA.PT5161LRS(CHIPS)':
 'GND76': CDS_PINID='GND76';
NODE_NAME     U6016 DF4
 '@T6G_MB_LIB.T6G(SCH_1):PAGE452_I19@PURE_QUANTA.PT5161LRS(CHIPS)':
 'GND77': CDS_PINID='GND77';
NODE_NAME     U6016 DG2
 '@T6G_MB_LIB.T6G(SCH_1):PAGE452_I19@PURE_QUANTA.PT5161LRS(CHIPS)':
 'GND78': CDS_PINID='GND78';
NODE_NAME     U6016 DG34
 '@T6G_MB_LIB.T6G(SCH_1):PAGE452_I19@PURE_QUANTA.PT5161LRS(CHIPS)':
 'GND79': CDS_PINID='GND79';
NODE_NAME     U6016 DH1
 '@T6G_MB_LIB.T6G(SCH_1):PAGE452_I19@PURE_QUANTA.PT5161LRS(CHIPS)':
 'GND80': CDS_PINID='GND80';
NODE_NAME     U6016 DH35
 '@T6G_MB_LIB.T6G(SCH_1):PAGE452_I19@PURE_QUANTA.PT5161LRS(CHIPS)':
 'GND81': CDS_PINID='GND81';
NODE_NAME     U6016 DN13
 '@T6G_MB_LIB.T6G(SCH_1):PAGE452_I19@PURE_QUANTA.PT5161LRS(CHIPS)':
 'GND82': CDS_PINID='GND82';
NODE_NAME     U6016 DN22
 '@T6G_MB_LIB.T6G(SCH_1):PAGE452_I19@PURE_QUANTA.PT5161LRS(CHIPS)':
 'GND83': CDS_PINID='GND83';
NODE_NAME     U6016 DN32
 '@T6G_MB_LIB.T6G(SCH_1):PAGE452_I19@PURE_QUANTA.PT5161LRS(CHIPS)':
 'GND84': CDS_PINID='GND84';
NODE_NAME     U6016 DN4
 '@T6G_MB_LIB.T6G(SCH_1):PAGE452_I19@PURE_QUANTA.PT5161LRS(CHIPS)':
 'GND85': CDS_PINID='GND85';
NODE_NAME     U6016 DP2
 '@T6G_MB_LIB.T6G(SCH_1):PAGE452_I19@PURE_QUANTA.PT5161LRS(CHIPS)':
 'GND86': CDS_PINID='GND86';
NODE_NAME     U6016 DP34
 '@T6G_MB_LIB.T6G(SCH_1):PAGE452_I19@PURE_QUANTA.PT5161LRS(CHIPS)':
 'GND87': CDS_PINID='GND87';
NODE_NAME     U6016 DR1
 '@T6G_MB_LIB.T6G(SCH_1):PAGE452_I19@PURE_QUANTA.PT5161LRS(CHIPS)':
 'GND88': CDS_PINID='GND88';
NODE_NAME     U6016 DR35
 '@T6G_MB_LIB.T6G(SCH_1):PAGE452_I19@PURE_QUANTA.PT5161LRS(CHIPS)':
 'GND89': CDS_PINID='GND89';
NODE_NAME     U6016 DY13
 '@T6G_MB_LIB.T6G(SCH_1):PAGE452_I19@PURE_QUANTA.PT5161LRS(CHIPS)':
 'GND90': CDS_PINID='GND90';
NODE_NAME     U6016 DY22
 '@T6G_MB_LIB.T6G(SCH_1):PAGE452_I19@PURE_QUANTA.PT5161LRS(CHIPS)':
 'GND91': CDS_PINID='GND91';
NODE_NAME     U6016 DY32
 '@T6G_MB_LIB.T6G(SCH_1):PAGE452_I19@PURE_QUANTA.PT5161LRS(CHIPS)':
 'GND92': CDS_PINID='GND92';
NODE_NAME     U6016 DY4
 '@T6G_MB_LIB.T6G(SCH_1):PAGE452_I19@PURE_QUANTA.PT5161LRS(CHIPS)':
 'GND93': CDS_PINID='GND93';
NODE_NAME     U6016 E14
 '@T6G_MB_LIB.T6G(SCH_1):PAGE452_I19@PURE_QUANTA.PT5161LRS(CHIPS)':
 'GND94': CDS_PINID='GND94';
NODE_NAME     U6016 E27
 '@T6G_MB_LIB.T6G(SCH_1):PAGE452_I19@PURE_QUANTA.PT5161LRS(CHIPS)':
 'GND95': CDS_PINID='GND95';
NODE_NAME     U6016 E33
 '@T6G_MB_LIB.T6G(SCH_1):PAGE452_I19@PURE_QUANTA.PT5161LRS(CHIPS)':
 'GND96': CDS_PINID='GND96';
NODE_NAME     U6016 EA2
 '@T6G_MB_LIB.T6G(SCH_1):PAGE452_I19@PURE_QUANTA.PT5161LRS(CHIPS)':
 'GND97': CDS_PINID='GND97';
NODE_NAME     U6016 EA34
 '@T6G_MB_LIB.T6G(SCH_1):PAGE452_I19@PURE_QUANTA.PT5161LRS(CHIPS)':
 'GND98': CDS_PINID='GND98';
NODE_NAME     U6016 EB1
 '@T6G_MB_LIB.T6G(SCH_1):PAGE452_I19@PURE_QUANTA.PT5161LRS(CHIPS)':
 'GND99': CDS_PINID='GND99';
NODE_NAME     U6016 EB35
 '@T6G_MB_LIB.T6G(SCH_1):PAGE452_I19@PURE_QUANTA.PT5161LRS(CHIPS)':
 'GND100': CDS_PINID='GND100';
NODE_NAME     U6016 EG13
 '@T6G_MB_LIB.T6G(SCH_1):PAGE452_I19@PURE_QUANTA.PT5161LRS(CHIPS)':
 'GND101': CDS_PINID='GND101';
NODE_NAME     U6016 EG22
 '@T6G_MB_LIB.T6G(SCH_1):PAGE452_I19@PURE_QUANTA.PT5161LRS(CHIPS)':
 'GND102': CDS_PINID='GND102';
NODE_NAME     U6016 EG32
 '@T6G_MB_LIB.T6G(SCH_1):PAGE452_I19@PURE_QUANTA.PT5161LRS(CHIPS)':
 'GND103': CDS_PINID='GND103';
NODE_NAME     U6016 EG4
 '@T6G_MB_LIB.T6G(SCH_1):PAGE452_I19@PURE_QUANTA.PT5161LRS(CHIPS)':
 'GND104': CDS_PINID='GND104';
NODE_NAME     U6016 EH2
 '@T6G_MB_LIB.T6G(SCH_1):PAGE452_I19@PURE_QUANTA.PT5161LRS(CHIPS)':
 'GND105': CDS_PINID='GND105';
NODE_NAME     U6016 EH34
 '@T6G_MB_LIB.T6G(SCH_1):PAGE452_I19@PURE_QUANTA.PT5161LRS(CHIPS)':
 'GND106': CDS_PINID='GND106';
NODE_NAME     U6016 EJ1
 '@T6G_MB_LIB.T6G(SCH_1):PAGE452_I19@PURE_QUANTA.PT5161LRS(CHIPS)':
 'GND107': CDS_PINID='GND107';
NODE_NAME     U6016 EJ35
 '@T6G_MB_LIB.T6G(SCH_1):PAGE452_I19@PURE_QUANTA.PT5161LRS(CHIPS)':
 'GND108': CDS_PINID='GND108';
NODE_NAME     U6016 EP13
 '@T6G_MB_LIB.T6G(SCH_1):PAGE452_I19@PURE_QUANTA.PT5161LRS(CHIPS)':
 'GND109': CDS_PINID='GND109';
NODE_NAME     U6016 EP22
 '@T6G_MB_LIB.T6G(SCH_1):PAGE452_I19@PURE_QUANTA.PT5161LRS(CHIPS)':
 'GND110': CDS_PINID='GND110';
NODE_NAME     U6016 EP32
 '@T6G_MB_LIB.T6G(SCH_1):PAGE452_I19@PURE_QUANTA.PT5161LRS(CHIPS)':
 'GND111': CDS_PINID='GND111';
NODE_NAME     U6016 EP4
 '@T6G_MB_LIB.T6G(SCH_1):PAGE452_I19@PURE_QUANTA.PT5161LRS(CHIPS)':
 'GND112': CDS_PINID='GND112';
NODE_NAME     U6016 ER2
 '@T6G_MB_LIB.T6G(SCH_1):PAGE452_I19@PURE_QUANTA.PT5161LRS(CHIPS)':
 'GND113': CDS_PINID='GND113';
NODE_NAME     U6016 ER34
 '@T6G_MB_LIB.T6G(SCH_1):PAGE452_I19@PURE_QUANTA.PT5161LRS(CHIPS)':
 'GND114': CDS_PINID='GND114';
NODE_NAME     U6016 ET1
 '@T6G_MB_LIB.T6G(SCH_1):PAGE452_I19@PURE_QUANTA.PT5161LRS(CHIPS)':
 'GND115': CDS_PINID='GND115';
NODE_NAME     U6016 ET35
 '@T6G_MB_LIB.T6G(SCH_1):PAGE452_I19@PURE_QUANTA.PT5161LRS(CHIPS)':
 'GND116': CDS_PINID='GND116';
NODE_NAME     U6016 FA15
 '@T6G_MB_LIB.T6G(SCH_1):PAGE452_I19@PURE_QUANTA.PT5161LRS(CHIPS)':
 'GND117': CDS_PINID='GND117';
NODE_NAME     U6016 FA32
 '@T6G_MB_LIB.T6G(SCH_1):PAGE452_I19@PURE_QUANTA.PT5161LRS(CHIPS)':
 'GND118': CDS_PINID='GND118';
NODE_NAME     U6016 FB2
 '@T6G_MB_LIB.T6G(SCH_1):PAGE452_I19@PURE_QUANTA.PT5161LRS(CHIPS)':
 'GND119': CDS_PINID='GND119';
NODE_NAME     U6016 FB34
 '@T6G_MB_LIB.T6G(SCH_1):PAGE452_I19@PURE_QUANTA.PT5161LRS(CHIPS)':
 'GND120': CDS_PINID='GND120';
NODE_NAME     U6016 FC19
 '@T6G_MB_LIB.T6G(SCH_1):PAGE452_I19@PURE_QUANTA.PT5161LRS(CHIPS)':
 'GND121': CDS_PINID='GND121';
NODE_NAME     U6016 FC23
 '@T6G_MB_LIB.T6G(SCH_1):PAGE452_I19@PURE_QUANTA.PT5161LRS(CHIPS)':
 'GND122': CDS_PINID='GND122';
NODE_NAME     U6016 FC25
 '@T6G_MB_LIB.T6G(SCH_1):PAGE452_I19@PURE_QUANTA.PT5161LRS(CHIPS)':
 'GND123': CDS_PINID='GND123';
NODE_NAME     U6016 FC28
 '@T6G_MB_LIB.T6G(SCH_1):PAGE452_I19@PURE_QUANTA.PT5161LRS(CHIPS)':
 'GND124': CDS_PINID='GND124';
NODE_NAME     U6016 FC3
 '@T6G_MB_LIB.T6G(SCH_1):PAGE452_I19@PURE_QUANTA.PT5161LRS(CHIPS)':
 'GND125': CDS_PINID='GND125';
NODE_NAME     U6016 FC6
 '@T6G_MB_LIB.T6G(SCH_1):PAGE452_I19@PURE_QUANTA.PT5161LRS(CHIPS)':
 'GND126': CDS_PINID='GND126';
NODE_NAME     U6016 FC9
 '@T6G_MB_LIB.T6G(SCH_1):PAGE452_I19@PURE_QUANTA.PT5161LRS(CHIPS)':
 'GND127': CDS_PINID='GND127';
NODE_NAME     U6016 FD1
 '@T6G_MB_LIB.T6G(SCH_1):PAGE452_I19@PURE_QUANTA.PT5161LRS(CHIPS)':
 'GND128': CDS_PINID='GND128';
NODE_NAME     U6016 FD35
 '@T6G_MB_LIB.T6G(SCH_1):PAGE452_I19@PURE_QUANTA.PT5161LRS(CHIPS)':
 'GND129': CDS_PINID='GND129';
NODE_NAME     U6016 FF14
 '@T6G_MB_LIB.T6G(SCH_1):PAGE452_I19@PURE_QUANTA.PT5161LRS(CHIPS)':
 'GND130': CDS_PINID='GND130';
NODE_NAME     U6016 FF21
 '@T6G_MB_LIB.T6G(SCH_1):PAGE452_I19@PURE_QUANTA.PT5161LRS(CHIPS)':
 'GND131': CDS_PINID='GND131';
NODE_NAME     U6016 FJ12
 '@T6G_MB_LIB.T6G(SCH_1):PAGE452_I19@PURE_QUANTA.PT5161LRS(CHIPS)':
 'GND132': CDS_PINID='GND132';
NODE_NAME     U6016 FJ19
 '@T6G_MB_LIB.T6G(SCH_1):PAGE452_I19@PURE_QUANTA.PT5161LRS(CHIPS)':
 'GND133': CDS_PINID='GND133';
NODE_NAME     U6016 H12
 '@T6G_MB_LIB.T6G(SCH_1):PAGE452_I19@PURE_QUANTA.PT5161LRS(CHIPS)':
 'GND134': CDS_PINID='GND134';
NODE_NAME     U6016 H16
 '@T6G_MB_LIB.T6G(SCH_1):PAGE452_I19@PURE_QUANTA.PT5161LRS(CHIPS)':
 'GND135': CDS_PINID='GND135';
NODE_NAME     U6016 H19
 '@T6G_MB_LIB.T6G(SCH_1):PAGE452_I19@PURE_QUANTA.PT5161LRS(CHIPS)':
 'GND136': CDS_PINID='GND136';
NODE_NAME     U6016 H31
 '@T6G_MB_LIB.T6G(SCH_1):PAGE452_I19@PURE_QUANTA.PT5161LRS(CHIPS)':
 'GND137': CDS_PINID='GND137';
NODE_NAME     U6016 J22
 '@T6G_MB_LIB.T6G(SCH_1):PAGE452_I19@PURE_QUANTA.PT5161LRS(CHIPS)':
 'GND138': CDS_PINID='GND138';
NODE_NAME     U6016 J4
 '@T6G_MB_LIB.T6G(SCH_1):PAGE452_I19@PURE_QUANTA.PT5161LRS(CHIPS)':
 'GND139': CDS_PINID='GND139';
NODE_NAME     U6016 K2
 '@T6G_MB_LIB.T6G(SCH_1):PAGE452_I19@PURE_QUANTA.PT5161LRS(CHIPS)':
 'GND140': CDS_PINID='GND140';
NODE_NAME     U6016 K34
 '@T6G_MB_LIB.T6G(SCH_1):PAGE452_I19@PURE_QUANTA.PT5161LRS(CHIPS)':
 'GND141': CDS_PINID='GND141';
NODE_NAME     U6016 L1
 '@T6G_MB_LIB.T6G(SCH_1):PAGE452_I19@PURE_QUANTA.PT5161LRS(CHIPS)':
 'GND142': CDS_PINID='GND142';
NODE_NAME     U6016 L35
 '@T6G_MB_LIB.T6G(SCH_1):PAGE452_I19@PURE_QUANTA.PT5161LRS(CHIPS)':
 'GND143': CDS_PINID='GND143';
NODE_NAME     U6016 T13
 '@T6G_MB_LIB.T6G(SCH_1):PAGE452_I19@PURE_QUANTA.PT5161LRS(CHIPS)':
 'GND144': CDS_PINID='GND144';
NODE_NAME     U6016 T22
 '@T6G_MB_LIB.T6G(SCH_1):PAGE452_I19@PURE_QUANTA.PT5161LRS(CHIPS)':
 'GND145': CDS_PINID='GND145';
NODE_NAME     U6016 T32
 '@T6G_MB_LIB.T6G(SCH_1):PAGE452_I19@PURE_QUANTA.PT5161LRS(CHIPS)':
 'GND146': CDS_PINID='GND146';
NODE_NAME     U6016 T4
 '@T6G_MB_LIB.T6G(SCH_1):PAGE452_I19@PURE_QUANTA.PT5161LRS(CHIPS)':
 'GND147': CDS_PINID='GND147';
NODE_NAME     U6016 U2
 '@T6G_MB_LIB.T6G(SCH_1):PAGE452_I19@PURE_QUANTA.PT5161LRS(CHIPS)':
 'GND148': CDS_PINID='GND148';
NODE_NAME     U6016 U34
 '@T6G_MB_LIB.T6G(SCH_1):PAGE452_I19@PURE_QUANTA.PT5161LRS(CHIPS)':
 'GND149': CDS_PINID='GND149';
NODE_NAME     U6016 V1
 '@T6G_MB_LIB.T6G(SCH_1):PAGE452_I19@PURE_QUANTA.PT5161LRS(CHIPS)':
 'GND150': CDS_PINID='GND150';
NODE_NAME     U6016 V35
 '@T6G_MB_LIB.T6G(SCH_1):PAGE452_I19@PURE_QUANTA.PT5161LRS(CHIPS)':
 'GND151': CDS_PINID='GND151';
NODE_NAME     C367 2
 '@T6G_MB_LIB.T6G(SCH_1):PAGE454_I5@PURE_QUANTA.Q_CAP(CHIPS)':
 'B': CDS_PINID='B';
NODE_NAME     C375 2
 '@T6G_MB_LIB.T6G(SCH_1):PAGE454_I6@PURE_QUANTA.Q_CAP(CHIPS)':
 'B': CDS_PINID='B';
NODE_NAME     C378 2
 '@T6G_MB_LIB.T6G(SCH_1):PAGE454_I8@PURE_QUANTA.Q_CAP(CHIPS)':
 'B': CDS_PINID='B';
NODE_NAME     C369 2
 '@T6G_MB_LIB.T6G(SCH_1):PAGE454_I10@PURE_QUANTA.Q_CAP(CHIPS)':
 'B': CDS_PINID='B';
NODE_NAME     C372 2
 '@T6G_MB_LIB.T6G(SCH_1):PAGE454_I11@PURE_QUANTA.Q_CAP(CHIPS)':
 'B': CDS_PINID='B';
NODE_NAME     C371 2
 '@T6G_MB_LIB.T6G(SCH_1):PAGE454_I12@PURE_QUANTA.Q_CAP(CHIPS)':
 'B': CDS_PINID='B';
NODE_NAME     C374 2
 '@T6G_MB_LIB.T6G(SCH_1):PAGE454_I13@PURE_QUANTA.Q_CAP(CHIPS)':
 'B': CDS_PINID='B';
NODE_NAME     C376 2
 '@T6G_MB_LIB.T6G(SCH_1):PAGE454_I15@PURE_QUANTA.Q_CAP(CHIPS)':
 'B': CDS_PINID='B';
NODE_NAME     C377 2
 '@T6G_MB_LIB.T6G(SCH_1):PAGE454_I16@PURE_QUANTA.Q_CAP(CHIPS)':
 'B': CDS_PINID='B';
NODE_NAME     C379 2
 '@T6G_MB_LIB.T6G(SCH_1):PAGE454_I17@PURE_QUANTA.Q_CAP(CHIPS)':
 'B': CDS_PINID='B';
NODE_NAME     C380 2
 '@T6G_MB_LIB.T6G(SCH_1):PAGE454_I18@PURE_QUANTA.Q_CAP(CHIPS)':
 'B': CDS_PINID='B';
NODE_NAME     C381 2
 '@T6G_MB_LIB.T6G(SCH_1):PAGE454_I19@PURE_QUANTA.Q_CAP(CHIPS)':
 'B': CDS_PINID='B';
NODE_NAME     C366 2
 '@T6G_MB_LIB.T6G(SCH_1):PAGE454_I24@PURE_QUANTA.Q_CAP(CHIPS)':
 'B': CDS_PINID='B';
NODE_NAME     C368 2
 '@T6G_MB_LIB.T6G(SCH_1):PAGE454_I25@PURE_QUANTA.Q_CAP(CHIPS)':
 'B': CDS_PINID='B';
NODE_NAME     C370 2
 '@T6G_MB_LIB.T6G(SCH_1):PAGE454_I27@PURE_QUANTA.Q_CAP(CHIPS)':
 'B': CDS_PINID='B';
NODE_NAME     C373 2
 '@T6G_MB_LIB.T6G(SCH_1):PAGE454_I28@PURE_QUANTA.Q_CAP(CHIPS)':
 'B': CDS_PINID='B';
NODE_NAME     C421 2
 '@T6G_MB_LIB.T6G(SCH_1):PAGE454_I31@PURE_QUANTA.Q_CAP(CHIPS)':
 'B': CDS_PINID='B';
NODE_NAME     C396 2
 '@T6G_MB_LIB.T6G(SCH_1):PAGE454_I35@PURE_QUANTA.Q_CAP(CHIPS)':
 'B': CDS_PINID='B';
NODE_NAME     C397 2
 '@T6G_MB_LIB.T6G(SCH_1):PAGE454_I36@PURE_QUANTA.Q_CAP(CHIPS)':
 'B': CDS_PINID='B';
NODE_NAME     C427 2
 '@T6G_MB_LIB.T6G(SCH_1):PAGE454_I37@PURE_QUANTA.Q_CAP(CHIPS)':
 'B': CDS_PINID='B';
NODE_NAME     C393 2
 '@T6G_MB_LIB.T6G(SCH_1):PAGE454_I38@PURE_QUANTA.Q_CAP(CHIPS)':
 'B': CDS_PINID='B';
NODE_NAME     C430 2
 '@T6G_MB_LIB.T6G(SCH_1):PAGE454_I39@PURE_QUANTA.Q_CAP(CHIPS)':
 'B': CDS_PINID='B';
NODE_NAME     C400 2
 '@T6G_MB_LIB.T6G(SCH_1):PAGE454_I40@PURE_QUANTA.Q_CAP(CHIPS)':
 'B': CDS_PINID='B';
NODE_NAME     C384 2
 '@T6G_MB_LIB.T6G(SCH_1):PAGE454_I42@PURE_QUANTA.Q_CAP(CHIPS)':
 'B': CDS_PINID='B';
NODE_NAME     C387 2
 '@T6G_MB_LIB.T6G(SCH_1):PAGE454_I43@PURE_QUANTA.Q_CAP(CHIPS)':
 'B': CDS_PINID='B';
NODE_NAME     C410 2
 '@T6G_MB_LIB.T6G(SCH_1):PAGE454_I44@PURE_QUANTA.Q_CAP(CHIPS)':
 'B': CDS_PINID='B';
NODE_NAME     C420 2
 '@T6G_MB_LIB.T6G(SCH_1):PAGE454_I45@PURE_QUANTA.Q_CAP(CHIPS)':
 'B': CDS_PINID='B';
NODE_NAME     C398 2
 '@T6G_MB_LIB.T6G(SCH_1):PAGE454_I46@PURE_QUANTA.Q_CAP(CHIPS)':
 'B': CDS_PINID='B';
NODE_NAME     C401 2
 '@T6G_MB_LIB.T6G(SCH_1):PAGE454_I47@PURE_QUANTA.Q_CAP(CHIPS)':
 'B': CDS_PINID='B';
NODE_NAME     C406 2
 '@T6G_MB_LIB.T6G(SCH_1):PAGE454_I48@PURE_QUANTA.Q_CAP(CHIPS)':
 'B': CDS_PINID='B';
NODE_NAME     C407 2
 '@T6G_MB_LIB.T6G(SCH_1):PAGE454_I49@PURE_QUANTA.Q_CAP(CHIPS)':
 'B': CDS_PINID='B';
NODE_NAME     C391 2
 '@T6G_MB_LIB.T6G(SCH_1):PAGE454_I50@PURE_QUANTA.Q_CAP(CHIPS)':
 'B': CDS_PINID='B';
NODE_NAME     C415 2
 '@T6G_MB_LIB.T6G(SCH_1):PAGE454_I51@PURE_QUANTA.Q_CAP(CHIPS)':
 'B': CDS_PINID='B';
NODE_NAME     C418 2
 '@T6G_MB_LIB.T6G(SCH_1):PAGE454_I52@PURE_QUANTA.Q_CAP(CHIPS)':
 'B': CDS_PINID='B';
NODE_NAME     C422 2
 '@T6G_MB_LIB.T6G(SCH_1):PAGE454_I53@PURE_QUANTA.Q_CAP(CHIPS)':
 'B': CDS_PINID='B';
NODE_NAME     C416 2
 '@T6G_MB_LIB.T6G(SCH_1):PAGE454_I54@PURE_QUANTA.Q_CAP(CHIPS)':
 'B': CDS_PINID='B';
NODE_NAME     C413 2
 '@T6G_MB_LIB.T6G(SCH_1):PAGE454_I55@PURE_QUANTA.Q_CAP(CHIPS)':
 'B': CDS_PINID='B';
NODE_NAME     C417 2
 '@T6G_MB_LIB.T6G(SCH_1):PAGE454_I56@PURE_QUANTA.Q_CAP(CHIPS)':
 'B': CDS_PINID='B';
NODE_NAME     C412 2
 '@T6G_MB_LIB.T6G(SCH_1):PAGE454_I57@PURE_QUANTA.Q_CAP(CHIPS)':
 'B': CDS_PINID='B';
NODE_NAME     C386 2
 '@T6G_MB_LIB.T6G(SCH_1):PAGE454_I58@PURE_QUANTA.Q_CAP(CHIPS)':
 'B': CDS_PINID='B';
NODE_NAME     C399 2
 '@T6G_MB_LIB.T6G(SCH_1):PAGE454_I59@PURE_QUANTA.Q_CAP(CHIPS)':
 'B': CDS_PINID='B';
NODE_NAME     C402 2
 '@T6G_MB_LIB.T6G(SCH_1):PAGE454_I60@PURE_QUANTA.Q_CAP(CHIPS)':
 'B': CDS_PINID='B';
NODE_NAME     C403 2
 '@T6G_MB_LIB.T6G(SCH_1):PAGE454_I61@PURE_QUANTA.Q_CAP(CHIPS)':
 'B': CDS_PINID='B';
NODE_NAME     C411 2
 '@T6G_MB_LIB.T6G(SCH_1):PAGE454_I62@PURE_QUANTA.Q_CAP(CHIPS)':
 'B': CDS_PINID='B';
NODE_NAME     C395 2
 '@T6G_MB_LIB.T6G(SCH_1):PAGE454_I64@PURE_QUANTA.Q_CAP(CHIPS)':
 'B': CDS_PINID='B';
NODE_NAME     C425 2
 '@T6G_MB_LIB.T6G(SCH_1):PAGE454_I67@PURE_QUANTA.Q_CAP(CHIPS)':
 'B': CDS_PINID='B';
NODE_NAME     C389 2
 '@T6G_MB_LIB.T6G(SCH_1):PAGE454_I68@PURE_QUANTA.Q_CAP(CHIPS)':
 'B': CDS_PINID='B';
NODE_NAME     C424 2
 '@T6G_MB_LIB.T6G(SCH_1):PAGE454_I69@PURE_QUANTA.Q_CAP(CHIPS)':
 'B': CDS_PINID='B';
NODE_NAME     C429 2
 '@T6G_MB_LIB.T6G(SCH_1):PAGE454_I70@PURE_QUANTA.Q_CAP(CHIPS)':
 'B': CDS_PINID='B';
NODE_NAME     C382 2
 '@T6G_MB_LIB.T6G(SCH_1):PAGE454_I71@PURE_QUANTA.Q_CAP(CHIPS)':
 'B': CDS_PINID='B';
NODE_NAME     C431 2
 '@T6G_MB_LIB.T6G(SCH_1):PAGE454_I72@PURE_QUANTA.Q_CAP(CHIPS)':
 'B': CDS_PINID='B';
NODE_NAME     C404 2
 '@T6G_MB_LIB.T6G(SCH_1):PAGE454_I76@PURE_QUANTA.Q_CAP(CHIPS)':
 'B': CDS_PINID='B';
NODE_NAME     C408 2
 '@T6G_MB_LIB.T6G(SCH_1):PAGE454_I77@PURE_QUANTA.Q_CAP(CHIPS)':
 'B': CDS_PINID='B';
NODE_NAME     C414 2
 '@T6G_MB_LIB.T6G(SCH_1):PAGE454_I78@PURE_QUANTA.Q_CAP(CHIPS)':
 'B': CDS_PINID='B';
NODE_NAME     C419 2
 '@T6G_MB_LIB.T6G(SCH_1):PAGE454_I79@PURE_QUANTA.Q_CAP(CHIPS)':
 'B': CDS_PINID='B';
NODE_NAME     C423 2
 '@T6G_MB_LIB.T6G(SCH_1):PAGE454_I80@PURE_QUANTA.Q_CAP(CHIPS)':
 'B': CDS_PINID='B';
NODE_NAME     C383 2
 '@T6G_MB_LIB.T6G(SCH_1):PAGE454_I82@PURE_QUANTA.Q_CAP(CHIPS)':
 'B': CDS_PINID='B';
NODE_NAME     C385 2
 '@T6G_MB_LIB.T6G(SCH_1):PAGE454_I83@PURE_QUANTA.Q_CAP(CHIPS)':
 'B': CDS_PINID='B';
NODE_NAME     C388 2
 '@T6G_MB_LIB.T6G(SCH_1):PAGE454_I84@PURE_QUANTA.Q_CAP(CHIPS)':
 'B': CDS_PINID='B';
NODE_NAME     C392 2
 '@T6G_MB_LIB.T6G(SCH_1):PAGE454_I85@PURE_QUANTA.Q_CAP(CHIPS)':
 'B': CDS_PINID='B';
NODE_NAME     C405 2
 '@T6G_MB_LIB.T6G(SCH_1):PAGE454_I86@PURE_QUANTA.Q_CAP(CHIPS)':
 'B': CDS_PINID='B';
NODE_NAME     C409 2
 '@T6G_MB_LIB.T6G(SCH_1):PAGE454_I87@PURE_QUANTA.Q_CAP(CHIPS)':
 'B': CDS_PINID='B';
NODE_NAME     R916 2
 '@T6G_MB_LIB.T6G(SCH_1):PAGE462_I19@PURE_QUANTA.Q_RES(CHIPS)':
 'B': CDS_PINID='B';
NODE_NAME     R917 2
 '@T6G_MB_LIB.T6G(SCH_1):PAGE462_I20@PURE_QUANTA.Q_RES(CHIPS)':
 'B': CDS_PINID='B';
NODE_NAME     R919 2
 '@T6G_MB_LIB.T6G(SCH_1):PAGE462_I21@PURE_QUANTA.Q_RES(CHIPS)':
 'B': CDS_PINID='B';
NODE_NAME     R641 2
 '@T6G_MB_LIB.T6G(SCH_1):PAGE462_I30@PURE_QUANTA.Q_RES(CHIPS)':
 'B': CDS_PINID='B';
NODE_NAME     R642 2
 '@T6G_MB_LIB.T6G(SCH_1):PAGE462_I46@PURE_QUANTA.Q_RES(CHIPS)':
 'B': CDS_PINID='B';
NODE_NAME     R921 2
 '@T6G_MB_LIB.T6G(SCH_1):PAGE462_I50@PURE_QUANTA.Q_RES(CHIPS)':
 'B': CDS_PINID='B';
NODE_NAME     R923 2
 '@T6G_MB_LIB.T6G(SCH_1):PAGE462_I51@PURE_QUANTA.Q_RES(CHIPS)':
 'B': CDS_PINID='B';
NODE_NAME     R924 2
 '@T6G_MB_LIB.T6G(SCH_1):PAGE462_I53@PURE_QUANTA.Q_RES(CHIPS)':
 'B': CDS_PINID='B';
NODE_NAME     R926 2
 '@T6G_MB_LIB.T6G(SCH_1):PAGE462_I64@PURE_QUANTA.Q_RES(CHIPS)':
 'B': CDS_PINID='B';
NODE_NAME     R903 2
 '@T6G_MB_LIB.T6G(SCH_1):PAGE462_I79@PURE_QUANTA.Q_RES(CHIPS)':
 'B': CDS_PINID='B';
NODE_NAME     R906 2
 '@T6G_MB_LIB.T6G(SCH_1):PAGE462_I81@PURE_QUANTA.Q_RES(CHIPS)':
 'B': CDS_PINID='B';
NODE_NAME     R949 2
 '@T6G_MB_LIB.T6G(SCH_1):PAGE462_I83@PURE_QUANTA.Q_RES(CHIPS)':
 'B': CDS_PINID='B';
NODE_NAME     R908 2
 '@T6G_MB_LIB.T6G(SCH_1):PAGE462_I90@PURE_QUANTA.Q_RES(CHIPS)':
 'B': CDS_PINID='B';
NODE_NAME     R907 2
 '@T6G_MB_LIB.T6G(SCH_1):PAGE462_I92@PURE_QUANTA.Q_RES(CHIPS)':
 'B': CDS_PINID='B';
NODE_NAME     U6017 E30
 '@T6G_MB_LIB.T6G(SCH_1):PAGE462_I97@PURE_QUANTA.PT5161LRS(CHIPS)':
 'T_SENSE': CDS_PINID='T_SENSE';
NODE_NAME     R6903 2
 '@T6G_MB_LIB.T6G(SCH_1):PAGE463_I13@PURE_QUANTA.Q_RES(CHIPS)':
 'B': CDS_PINID='B';
NODE_NAME     R6902 2
 '@T6G_MB_LIB.T6G(SCH_1):PAGE463_I15@PURE_QUANTA.Q_RES(CHIPS)':
 'B': CDS_PINID='B';
NODE_NAME     U6017 AC13
 '@T6G_MB_LIB.T6G(SCH_1):PAGE463_I17@PURE_QUANTA.PT5161LRS(CHIPS)':
 'GND1': CDS_PINID='GND1';
NODE_NAME     U6017 AC22
 '@T6G_MB_LIB.T6G(SCH_1):PAGE463_I17@PURE_QUANTA.PT5161LRS(CHIPS)':
 'GND2': CDS_PINID='GND2';
NODE_NAME     U6017 AC32
 '@T6G_MB_LIB.T6G(SCH_1):PAGE463_I17@PURE_QUANTA.PT5161LRS(CHIPS)':
 'GND3': CDS_PINID='GND3';
NODE_NAME     U6017 AC4
 '@T6G_MB_LIB.T6G(SCH_1):PAGE463_I17@PURE_QUANTA.PT5161LRS(CHIPS)':
 'GND4': CDS_PINID='GND4';
NODE_NAME     U6017 AD2
 '@T6G_MB_LIB.T6G(SCH_1):PAGE463_I17@PURE_QUANTA.PT5161LRS(CHIPS)':
 'GND5': CDS_PINID='GND5';
NODE_NAME     U6017 AD34
 '@T6G_MB_LIB.T6G(SCH_1):PAGE463_I17@PURE_QUANTA.PT5161LRS(CHIPS)':
 'GND6': CDS_PINID='GND6';
NODE_NAME     U6017 AE1
 '@T6G_MB_LIB.T6G(SCH_1):PAGE463_I17@PURE_QUANTA.PT5161LRS(CHIPS)':
 'GND7': CDS_PINID='GND7';
NODE_NAME     U6017 AE35
 '@T6G_MB_LIB.T6G(SCH_1):PAGE463_I17@PURE_QUANTA.PT5161LRS(CHIPS)':
 'GND8': CDS_PINID='GND8';
NODE_NAME     U6017 AK13
 '@T6G_MB_LIB.T6G(SCH_1):PAGE463_I17@PURE_QUANTA.PT5161LRS(CHIPS)':
 'GND9': CDS_PINID='GND9';
NODE_NAME     U6017 AK22
 '@T6G_MB_LIB.T6G(SCH_1):PAGE463_I17@PURE_QUANTA.PT5161LRS(CHIPS)':
 'GND10': CDS_PINID='GND10';
NODE_NAME     U6017 AK32
 '@T6G_MB_LIB.T6G(SCH_1):PAGE463_I17@PURE_QUANTA.PT5161LRS(CHIPS)':
 'GND11': CDS_PINID='GND11';
NODE_NAME     U6017 AK4
 '@T6G_MB_LIB.T6G(SCH_1):PAGE463_I17@PURE_QUANTA.PT5161LRS(CHIPS)':
 'GND12': CDS_PINID='GND12';
NODE_NAME     U6017 AL2
 '@T6G_MB_LIB.T6G(SCH_1):PAGE463_I17@PURE_QUANTA.PT5161LRS(CHIPS)':
 'GND13': CDS_PINID='GND13';
NODE_NAME     U6017 AL34
 '@T6G_MB_LIB.T6G(SCH_1):PAGE463_I17@PURE_QUANTA.PT5161LRS(CHIPS)':
 'GND14': CDS_PINID='GND14';
NODE_NAME     U6017 AM1
 '@T6G_MB_LIB.T6G(SCH_1):PAGE463_I17@PURE_QUANTA.PT5161LRS(CHIPS)':
 'GND15': CDS_PINID='GND15';
NODE_NAME     U6017 AM35
 '@T6G_MB_LIB.T6G(SCH_1):PAGE463_I17@PURE_QUANTA.PT5161LRS(CHIPS)':
 'GND16': CDS_PINID='GND16';
NODE_NAME     U6017 AU13
 '@T6G_MB_LIB.T6G(SCH_1):PAGE463_I17@PURE_QUANTA.PT5161LRS(CHIPS)':
 'GND17': CDS_PINID='GND17';
NODE_NAME     U6017 AU22
 '@T6G_MB_LIB.T6G(SCH_1):PAGE463_I17@PURE_QUANTA.PT5161LRS(CHIPS)':
 'GND18': CDS_PINID='GND18';
NODE_NAME     U6017 AU32
 '@T6G_MB_LIB.T6G(SCH_1):PAGE463_I17@PURE_QUANTA.PT5161LRS(CHIPS)':
 'GND19': CDS_PINID='GND19';
NODE_NAME     U6017 AU4
 '@T6G_MB_LIB.T6G(SCH_1):PAGE463_I17@PURE_QUANTA.PT5161LRS(CHIPS)':
 'GND20': CDS_PINID='GND20';
NODE_NAME     U6017 AV2
 '@T6G_MB_LIB.T6G(SCH_1):PAGE463_I17@PURE_QUANTA.PT5161LRS(CHIPS)':
 'GND21': CDS_PINID='GND21';
NODE_NAME     U6017 AV34
 '@T6G_MB_LIB.T6G(SCH_1):PAGE463_I17@PURE_QUANTA.PT5161LRS(CHIPS)':
 'GND22': CDS_PINID='GND22';
NODE_NAME     U6017 AW1
 '@T6G_MB_LIB.T6G(SCH_1):PAGE463_I17@PURE_QUANTA.PT5161LRS(CHIPS)':
 'GND23': CDS_PINID='GND23';
NODE_NAME     U6017 AW35
 '@T6G_MB_LIB.T6G(SCH_1):PAGE463_I17@PURE_QUANTA.PT5161LRS(CHIPS)':
 'GND24': CDS_PINID='GND24';
NODE_NAME     U6017 B19
 '@T6G_MB_LIB.T6G(SCH_1):PAGE463_I17@PURE_QUANTA.PT5161LRS(CHIPS)':
 'GND25': CDS_PINID='GND25';
NODE_NAME     U6017 BD13
 '@T6G_MB_LIB.T6G(SCH_1):PAGE463_I17@PURE_QUANTA.PT5161LRS(CHIPS)':
 'GND26': CDS_PINID='GND26';
NODE_NAME     U6017 BD22
 '@T6G_MB_LIB.T6G(SCH_1):PAGE463_I17@PURE_QUANTA.PT5161LRS(CHIPS)':
 'GND27': CDS_PINID='GND27';
NODE_NAME     U6017 BD32
 '@T6G_MB_LIB.T6G(SCH_1):PAGE463_I17@PURE_QUANTA.PT5161LRS(CHIPS)':
 'GND28': CDS_PINID='GND28';
NODE_NAME     U6017 BD4
 '@T6G_MB_LIB.T6G(SCH_1):PAGE463_I17@PURE_QUANTA.PT5161LRS(CHIPS)':
 'GND29': CDS_PINID='GND29';
NODE_NAME     U6017 BE2
 '@T6G_MB_LIB.T6G(SCH_1):PAGE463_I17@PURE_QUANTA.PT5161LRS(CHIPS)':
 'GND30': CDS_PINID='GND30';
NODE_NAME     U6017 BE34
 '@T6G_MB_LIB.T6G(SCH_1):PAGE463_I17@PURE_QUANTA.PT5161LRS(CHIPS)':
 'GND31': CDS_PINID='GND31';
NODE_NAME     U6017 BF1
 '@T6G_MB_LIB.T6G(SCH_1):PAGE463_I17@PURE_QUANTA.PT5161LRS(CHIPS)':
 'GND32': CDS_PINID='GND32';
NODE_NAME     U6017 BF35
 '@T6G_MB_LIB.T6G(SCH_1):PAGE463_I17@PURE_QUANTA.PT5161LRS(CHIPS)':
 'GND33': CDS_PINID='GND33';
NODE_NAME     U6017 BL13
 '@T6G_MB_LIB.T6G(SCH_1):PAGE463_I17@PURE_QUANTA.PT5161LRS(CHIPS)':
 'GND34': CDS_PINID='GND34';
NODE_NAME     U6017 BL22
 '@T6G_MB_LIB.T6G(SCH_1):PAGE463_I17@PURE_QUANTA.PT5161LRS(CHIPS)':
 'GND35': CDS_PINID='GND35';
NODE_NAME     U6017 BL32
 '@T6G_MB_LIB.T6G(SCH_1):PAGE463_I17@PURE_QUANTA.PT5161LRS(CHIPS)':
 'GND36': CDS_PINID='GND36';
NODE_NAME     U6017 BL4
 '@T6G_MB_LIB.T6G(SCH_1):PAGE463_I17@PURE_QUANTA.PT5161LRS(CHIPS)':
 'GND37': CDS_PINID='GND37';
NODE_NAME     U6017 BM2
 '@T6G_MB_LIB.T6G(SCH_1):PAGE463_I17@PURE_QUANTA.PT5161LRS(CHIPS)':
 'GND38': CDS_PINID='GND38';
NODE_NAME     U6017 BM34
 '@T6G_MB_LIB.T6G(SCH_1):PAGE463_I17@PURE_QUANTA.PT5161LRS(CHIPS)':
 'GND39': CDS_PINID='GND39';
NODE_NAME     U6017 BN1
 '@T6G_MB_LIB.T6G(SCH_1):PAGE463_I17@PURE_QUANTA.PT5161LRS(CHIPS)':
 'GND40': CDS_PINID='GND40';
NODE_NAME     U6017 BN35
 '@T6G_MB_LIB.T6G(SCH_1):PAGE463_I17@PURE_QUANTA.PT5161LRS(CHIPS)':
 'GND41': CDS_PINID='GND41';
NODE_NAME     U6017 BV13
 '@T6G_MB_LIB.T6G(SCH_1):PAGE463_I17@PURE_QUANTA.PT5161LRS(CHIPS)':
 'GND42': CDS_PINID='GND42';
NODE_NAME     U6017 BV22
 '@T6G_MB_LIB.T6G(SCH_1):PAGE463_I17@PURE_QUANTA.PT5161LRS(CHIPS)':
 'GND43': CDS_PINID='GND43';
NODE_NAME     U6017 BV32
 '@T6G_MB_LIB.T6G(SCH_1):PAGE463_I17@PURE_QUANTA.PT5161LRS(CHIPS)':
 'GND44': CDS_PINID='GND44';
NODE_NAME     U6017 BV4
 '@T6G_MB_LIB.T6G(SCH_1):PAGE463_I17@PURE_QUANTA.PT5161LRS(CHIPS)':
 'GND45': CDS_PINID='GND45';
NODE_NAME     U6017 BW2
 '@T6G_MB_LIB.T6G(SCH_1):PAGE463_I17@PURE_QUANTA.PT5161LRS(CHIPS)':
 'GND46': CDS_PINID='GND46';
NODE_NAME     U6017 BW34
 '@T6G_MB_LIB.T6G(SCH_1):PAGE463_I17@PURE_QUANTA.PT5161LRS(CHIPS)':
 'GND47': CDS_PINID='GND47';
NODE_NAME     U6017 BY1
 '@T6G_MB_LIB.T6G(SCH_1):PAGE463_I17@PURE_QUANTA.PT5161LRS(CHIPS)':
 'GND48': CDS_PINID='GND48';
NODE_NAME     U6017 BY35
 '@T6G_MB_LIB.T6G(SCH_1):PAGE463_I17@PURE_QUANTA.PT5161LRS(CHIPS)':
 'GND49': CDS_PINID='GND49';
NODE_NAME     U6017 CE13
 '@T6G_MB_LIB.T6G(SCH_1):PAGE463_I17@PURE_QUANTA.PT5161LRS(CHIPS)':
 'GND50': CDS_PINID='GND50';
NODE_NAME     U6017 CE22
 '@T6G_MB_LIB.T6G(SCH_1):PAGE463_I17@PURE_QUANTA.PT5161LRS(CHIPS)':
 'GND51': CDS_PINID='GND51';
NODE_NAME     U6017 CE32
 '@T6G_MB_LIB.T6G(SCH_1):PAGE463_I17@PURE_QUANTA.PT5161LRS(CHIPS)':
 'GND52': CDS_PINID='GND52';
NODE_NAME     U6017 CE4
 '@T6G_MB_LIB.T6G(SCH_1):PAGE463_I17@PURE_QUANTA.PT5161LRS(CHIPS)':
 'GND53': CDS_PINID='GND53';
NODE_NAME     U6017 CF2
 '@T6G_MB_LIB.T6G(SCH_1):PAGE463_I17@PURE_QUANTA.PT5161LRS(CHIPS)':
 'GND54': CDS_PINID='GND54';
NODE_NAME     U6017 CF34
 '@T6G_MB_LIB.T6G(SCH_1):PAGE463_I17@PURE_QUANTA.PT5161LRS(CHIPS)':
 'GND55': CDS_PINID='GND55';
NODE_NAME     U6017 CG1
 '@T6G_MB_LIB.T6G(SCH_1):PAGE463_I17@PURE_QUANTA.PT5161LRS(CHIPS)':
 'GND56': CDS_PINID='GND56';
NODE_NAME     U6017 CG35
 '@T6G_MB_LIB.T6G(SCH_1):PAGE463_I17@PURE_QUANTA.PT5161LRS(CHIPS)':
 'GND57': CDS_PINID='GND57';
NODE_NAME     U6017 CM13
 '@T6G_MB_LIB.T6G(SCH_1):PAGE463_I17@PURE_QUANTA.PT5161LRS(CHIPS)':
 'GND58': CDS_PINID='GND58';
NODE_NAME     U6017 CM22
 '@T6G_MB_LIB.T6G(SCH_1):PAGE463_I17@PURE_QUANTA.PT5161LRS(CHIPS)':
 'GND59': CDS_PINID='GND59';
NODE_NAME     U6017 CM32
 '@T6G_MB_LIB.T6G(SCH_1):PAGE463_I17@PURE_QUANTA.PT5161LRS(CHIPS)':
 'GND60': CDS_PINID='GND60';
NODE_NAME     U6017 CM4
 '@T6G_MB_LIB.T6G(SCH_1):PAGE463_I17@PURE_QUANTA.PT5161LRS(CHIPS)':
 'GND61': CDS_PINID='GND61';
NODE_NAME     U6017 CN2
 '@T6G_MB_LIB.T6G(SCH_1):PAGE463_I17@PURE_QUANTA.PT5161LRS(CHIPS)':
 'GND62': CDS_PINID='GND62';
NODE_NAME     U6017 CN34
 '@T6G_MB_LIB.T6G(SCH_1):PAGE463_I17@PURE_QUANTA.PT5161LRS(CHIPS)':
 'GND63': CDS_PINID='GND63';
NODE_NAME     U6017 CP1
 '@T6G_MB_LIB.T6G(SCH_1):PAGE463_I17@PURE_QUANTA.PT5161LRS(CHIPS)':
 'GND64': CDS_PINID='GND64';
NODE_NAME     U6017 CP35
 '@T6G_MB_LIB.T6G(SCH_1):PAGE463_I17@PURE_QUANTA.PT5161LRS(CHIPS)':
 'GND65': CDS_PINID='GND65';
NODE_NAME     U6017 CW13
 '@T6G_MB_LIB.T6G(SCH_1):PAGE463_I17@PURE_QUANTA.PT5161LRS(CHIPS)':
 'GND66': CDS_PINID='GND66';
NODE_NAME     U6017 CW22
 '@T6G_MB_LIB.T6G(SCH_1):PAGE463_I17@PURE_QUANTA.PT5161LRS(CHIPS)':
 'GND67': CDS_PINID='GND67';
NODE_NAME     U6017 CW32
 '@T6G_MB_LIB.T6G(SCH_1):PAGE463_I17@PURE_QUANTA.PT5161LRS(CHIPS)':
 'GND68': CDS_PINID='GND68';
NODE_NAME     U6017 CW4
 '@T6G_MB_LIB.T6G(SCH_1):PAGE463_I17@PURE_QUANTA.PT5161LRS(CHIPS)':
 'GND69': CDS_PINID='GND69';
NODE_NAME     U6017 CY2
 '@T6G_MB_LIB.T6G(SCH_1):PAGE463_I17@PURE_QUANTA.PT5161LRS(CHIPS)':
 'GND70': CDS_PINID='GND70';
NODE_NAME     U6017 CY34
 '@T6G_MB_LIB.T6G(SCH_1):PAGE463_I17@PURE_QUANTA.PT5161LRS(CHIPS)':
 'GND71': CDS_PINID='GND71';
NODE_NAME     U6017 DA1
 '@T6G_MB_LIB.T6G(SCH_1):PAGE463_I17@PURE_QUANTA.PT5161LRS(CHIPS)':
 'GND72': CDS_PINID='GND72';
NODE_NAME     U6017 DA35
 '@T6G_MB_LIB.T6G(SCH_1):PAGE463_I17@PURE_QUANTA.PT5161LRS(CHIPS)':
 'GND73': CDS_PINID='GND73';
NODE_NAME     U6017 DF13
 '@T6G_MB_LIB.T6G(SCH_1):PAGE463_I17@PURE_QUANTA.PT5161LRS(CHIPS)':
 'GND74': CDS_PINID='GND74';
NODE_NAME     U6017 DF22
 '@T6G_MB_LIB.T6G(SCH_1):PAGE463_I17@PURE_QUANTA.PT5161LRS(CHIPS)':
 'GND75': CDS_PINID='GND75';
NODE_NAME     U6017 DF32
 '@T6G_MB_LIB.T6G(SCH_1):PAGE463_I17@PURE_QUANTA.PT5161LRS(CHIPS)':
 'GND76': CDS_PINID='GND76';
NODE_NAME     U6017 DF4
 '@T6G_MB_LIB.T6G(SCH_1):PAGE463_I17@PURE_QUANTA.PT5161LRS(CHIPS)':
 'GND77': CDS_PINID='GND77';
NODE_NAME     U6017 DG2
 '@T6G_MB_LIB.T6G(SCH_1):PAGE463_I17@PURE_QUANTA.PT5161LRS(CHIPS)':
 'GND78': CDS_PINID='GND78';
NODE_NAME     U6017 DG34
 '@T6G_MB_LIB.T6G(SCH_1):PAGE463_I17@PURE_QUANTA.PT5161LRS(CHIPS)':
 'GND79': CDS_PINID='GND79';
NODE_NAME     U6017 DH1
 '@T6G_MB_LIB.T6G(SCH_1):PAGE463_I17@PURE_QUANTA.PT5161LRS(CHIPS)':
 'GND80': CDS_PINID='GND80';
NODE_NAME     U6017 DH35
 '@T6G_MB_LIB.T6G(SCH_1):PAGE463_I17@PURE_QUANTA.PT5161LRS(CHIPS)':
 'GND81': CDS_PINID='GND81';
NODE_NAME     U6017 DN13
 '@T6G_MB_LIB.T6G(SCH_1):PAGE463_I17@PURE_QUANTA.PT5161LRS(CHIPS)':
 'GND82': CDS_PINID='GND82';
NODE_NAME     U6017 DN22
 '@T6G_MB_LIB.T6G(SCH_1):PAGE463_I17@PURE_QUANTA.PT5161LRS(CHIPS)':
 'GND83': CDS_PINID='GND83';
NODE_NAME     U6017 DN32
 '@T6G_MB_LIB.T6G(SCH_1):PAGE463_I17@PURE_QUANTA.PT5161LRS(CHIPS)':
 'GND84': CDS_PINID='GND84';
NODE_NAME     U6017 DN4
 '@T6G_MB_LIB.T6G(SCH_1):PAGE463_I17@PURE_QUANTA.PT5161LRS(CHIPS)':
 'GND85': CDS_PINID='GND85';
NODE_NAME     U6017 DP2
 '@T6G_MB_LIB.T6G(SCH_1):PAGE463_I17@PURE_QUANTA.PT5161LRS(CHIPS)':
 'GND86': CDS_PINID='GND86';
NODE_NAME     U6017 DP34
 '@T6G_MB_LIB.T6G(SCH_1):PAGE463_I17@PURE_QUANTA.PT5161LRS(CHIPS)':
 'GND87': CDS_PINID='GND87';
NODE_NAME     U6017 DR1
 '@T6G_MB_LIB.T6G(SCH_1):PAGE463_I17@PURE_QUANTA.PT5161LRS(CHIPS)':
 'GND88': CDS_PINID='GND88';
NODE_NAME     U6017 DR35
 '@T6G_MB_LIB.T6G(SCH_1):PAGE463_I17@PURE_QUANTA.PT5161LRS(CHIPS)':
 'GND89': CDS_PINID='GND89';
NODE_NAME     U6017 DY13
 '@T6G_MB_LIB.T6G(SCH_1):PAGE463_I17@PURE_QUANTA.PT5161LRS(CHIPS)':
 'GND90': CDS_PINID='GND90';
NODE_NAME     U6017 DY22
 '@T6G_MB_LIB.T6G(SCH_1):PAGE463_I17@PURE_QUANTA.PT5161LRS(CHIPS)':
 'GND91': CDS_PINID='GND91';
NODE_NAME     U6017 DY32
 '@T6G_MB_LIB.T6G(SCH_1):PAGE463_I17@PURE_QUANTA.PT5161LRS(CHIPS)':
 'GND92': CDS_PINID='GND92';
NODE_NAME     U6017 DY4
 '@T6G_MB_LIB.T6G(SCH_1):PAGE463_I17@PURE_QUANTA.PT5161LRS(CHIPS)':
 'GND93': CDS_PINID='GND93';
NODE_NAME     U6017 E14
 '@T6G_MB_LIB.T6G(SCH_1):PAGE463_I17@PURE_QUANTA.PT5161LRS(CHIPS)':
 'GND94': CDS_PINID='GND94';
NODE_NAME     U6017 E27
 '@T6G_MB_LIB.T6G(SCH_1):PAGE463_I17@PURE_QUANTA.PT5161LRS(CHIPS)':
 'GND95': CDS_PINID='GND95';
NODE_NAME     U6017 E33
 '@T6G_MB_LIB.T6G(SCH_1):PAGE463_I17@PURE_QUANTA.PT5161LRS(CHIPS)':
 'GND96': CDS_PINID='GND96';
NODE_NAME     U6017 EA2
 '@T6G_MB_LIB.T6G(SCH_1):PAGE463_I17@PURE_QUANTA.PT5161LRS(CHIPS)':
 'GND97': CDS_PINID='GND97';
NODE_NAME     U6017 EA34
 '@T6G_MB_LIB.T6G(SCH_1):PAGE463_I17@PURE_QUANTA.PT5161LRS(CHIPS)':
 'GND98': CDS_PINID='GND98';
NODE_NAME     U6017 EB1
 '@T6G_MB_LIB.T6G(SCH_1):PAGE463_I17@PURE_QUANTA.PT5161LRS(CHIPS)':
 'GND99': CDS_PINID='GND99';
NODE_NAME     U6017 EB35
 '@T6G_MB_LIB.T6G(SCH_1):PAGE463_I17@PURE_QUANTA.PT5161LRS(CHIPS)':
 'GND100': CDS_PINID='GND100';
NODE_NAME     U6017 EG13
 '@T6G_MB_LIB.T6G(SCH_1):PAGE463_I17@PURE_QUANTA.PT5161LRS(CHIPS)':
 'GND101': CDS_PINID='GND101';
NODE_NAME     U6017 EG22
 '@T6G_MB_LIB.T6G(SCH_1):PAGE463_I17@PURE_QUANTA.PT5161LRS(CHIPS)':
 'GND102': CDS_PINID='GND102';
NODE_NAME     U6017 EG32
 '@T6G_MB_LIB.T6G(SCH_1):PAGE463_I17@PURE_QUANTA.PT5161LRS(CHIPS)':
 'GND103': CDS_PINID='GND103';
NODE_NAME     U6017 EG4
 '@T6G_MB_LIB.T6G(SCH_1):PAGE463_I17@PURE_QUANTA.PT5161LRS(CHIPS)':
 'GND104': CDS_PINID='GND104';
NODE_NAME     U6017 EH2
 '@T6G_MB_LIB.T6G(SCH_1):PAGE463_I17@PURE_QUANTA.PT5161LRS(CHIPS)':
 'GND105': CDS_PINID='GND105';
NODE_NAME     U6017 EH34
 '@T6G_MB_LIB.T6G(SCH_1):PAGE463_I17@PURE_QUANTA.PT5161LRS(CHIPS)':
 'GND106': CDS_PINID='GND106';
NODE_NAME     U6017 EJ1
 '@T6G_MB_LIB.T6G(SCH_1):PAGE463_I17@PURE_QUANTA.PT5161LRS(CHIPS)':
 'GND107': CDS_PINID='GND107';
NODE_NAME     U6017 EJ35
 '@T6G_MB_LIB.T6G(SCH_1):PAGE463_I17@PURE_QUANTA.PT5161LRS(CHIPS)':
 'GND108': CDS_PINID='GND108';
NODE_NAME     U6017 EP13
 '@T6G_MB_LIB.T6G(SCH_1):PAGE463_I17@PURE_QUANTA.PT5161LRS(CHIPS)':
 'GND109': CDS_PINID='GND109';
NODE_NAME     U6017 EP22
 '@T6G_MB_LIB.T6G(SCH_1):PAGE463_I17@PURE_QUANTA.PT5161LRS(CHIPS)':
 'GND110': CDS_PINID='GND110';
NODE_NAME     U6017 EP32
 '@T6G_MB_LIB.T6G(SCH_1):PAGE463_I17@PURE_QUANTA.PT5161LRS(CHIPS)':
 'GND111': CDS_PINID='GND111';
NODE_NAME     U6017 EP4
 '@T6G_MB_LIB.T6G(SCH_1):PAGE463_I17@PURE_QUANTA.PT5161LRS(CHIPS)':
 'GND112': CDS_PINID='GND112';
NODE_NAME     U6017 ER2
 '@T6G_MB_LIB.T6G(SCH_1):PAGE463_I17@PURE_QUANTA.PT5161LRS(CHIPS)':
 'GND113': CDS_PINID='GND113';
NODE_NAME     U6017 ER34
 '@T6G_MB_LIB.T6G(SCH_1):PAGE463_I17@PURE_QUANTA.PT5161LRS(CHIPS)':
 'GND114': CDS_PINID='GND114';
NODE_NAME     U6017 ET1
 '@T6G_MB_LIB.T6G(SCH_1):PAGE463_I17@PURE_QUANTA.PT5161LRS(CHIPS)':
 'GND115': CDS_PINID='GND115';
NODE_NAME     U6017 ET35
 '@T6G_MB_LIB.T6G(SCH_1):PAGE463_I17@PURE_QUANTA.PT5161LRS(CHIPS)':
 'GND116': CDS_PINID='GND116';
NODE_NAME     U6017 FA15
 '@T6G_MB_LIB.T6G(SCH_1):PAGE463_I17@PURE_QUANTA.PT5161LRS(CHIPS)':
 'GND117': CDS_PINID='GND117';
NODE_NAME     U6017 FA32
 '@T6G_MB_LIB.T6G(SCH_1):PAGE463_I17@PURE_QUANTA.PT5161LRS(CHIPS)':
 'GND118': CDS_PINID='GND118';
NODE_NAME     U6017 FB2
 '@T6G_MB_LIB.T6G(SCH_1):PAGE463_I17@PURE_QUANTA.PT5161LRS(CHIPS)':
 'GND119': CDS_PINID='GND119';
NODE_NAME     U6017 FB34
 '@T6G_MB_LIB.T6G(SCH_1):PAGE463_I17@PURE_QUANTA.PT5161LRS(CHIPS)':
 'GND120': CDS_PINID='GND120';
NODE_NAME     U6017 FC19
 '@T6G_MB_LIB.T6G(SCH_1):PAGE463_I17@PURE_QUANTA.PT5161LRS(CHIPS)':
 'GND121': CDS_PINID='GND121';
NODE_NAME     U6017 FC23
 '@T6G_MB_LIB.T6G(SCH_1):PAGE463_I17@PURE_QUANTA.PT5161LRS(CHIPS)':
 'GND122': CDS_PINID='GND122';
NODE_NAME     U6017 FC25
 '@T6G_MB_LIB.T6G(SCH_1):PAGE463_I17@PURE_QUANTA.PT5161LRS(CHIPS)':
 'GND123': CDS_PINID='GND123';
NODE_NAME     U6017 FC28
 '@T6G_MB_LIB.T6G(SCH_1):PAGE463_I17@PURE_QUANTA.PT5161LRS(CHIPS)':
 'GND124': CDS_PINID='GND124';
NODE_NAME     U6017 FC3
 '@T6G_MB_LIB.T6G(SCH_1):PAGE463_I17@PURE_QUANTA.PT5161LRS(CHIPS)':
 'GND125': CDS_PINID='GND125';
NODE_NAME     U6017 FC6
 '@T6G_MB_LIB.T6G(SCH_1):PAGE463_I17@PURE_QUANTA.PT5161LRS(CHIPS)':
 'GND126': CDS_PINID='GND126';
NODE_NAME     U6017 FC9
 '@T6G_MB_LIB.T6G(SCH_1):PAGE463_I17@PURE_QUANTA.PT5161LRS(CHIPS)':
 'GND127': CDS_PINID='GND127';
NODE_NAME     U6017 FD1
 '@T6G_MB_LIB.T6G(SCH_1):PAGE463_I17@PURE_QUANTA.PT5161LRS(CHIPS)':
 'GND128': CDS_PINID='GND128';
NODE_NAME     U6017 FD35
 '@T6G_MB_LIB.T6G(SCH_1):PAGE463_I17@PURE_QUANTA.PT5161LRS(CHIPS)':
 'GND129': CDS_PINID='GND129';
NODE_NAME     U6017 FF14
 '@T6G_MB_LIB.T6G(SCH_1):PAGE463_I17@PURE_QUANTA.PT5161LRS(CHIPS)':
 'GND130': CDS_PINID='GND130';
NODE_NAME     U6017 FF21
 '@T6G_MB_LIB.T6G(SCH_1):PAGE463_I17@PURE_QUANTA.PT5161LRS(CHIPS)':
 'GND131': CDS_PINID='GND131';
NODE_NAME     U6017 FJ12
 '@T6G_MB_LIB.T6G(SCH_1):PAGE463_I17@PURE_QUANTA.PT5161LRS(CHIPS)':
 'GND132': CDS_PINID='GND132';
NODE_NAME     U6017 FJ19
 '@T6G_MB_LIB.T6G(SCH_1):PAGE463_I17@PURE_QUANTA.PT5161LRS(CHIPS)':
 'GND133': CDS_PINID='GND133';
NODE_NAME     U6017 H12
 '@T6G_MB_LIB.T6G(SCH_1):PAGE463_I17@PURE_QUANTA.PT5161LRS(CHIPS)':
 'GND134': CDS_PINID='GND134';
NODE_NAME     U6017 H16
 '@T6G_MB_LIB.T6G(SCH_1):PAGE463_I17@PURE_QUANTA.PT5161LRS(CHIPS)':
 'GND135': CDS_PINID='GND135';
NODE_NAME     U6017 H19
 '@T6G_MB_LIB.T6G(SCH_1):PAGE463_I17@PURE_QUANTA.PT5161LRS(CHIPS)':
 'GND136': CDS_PINID='GND136';
NODE_NAME     U6017 H31
 '@T6G_MB_LIB.T6G(SCH_1):PAGE463_I17@PURE_QUANTA.PT5161LRS(CHIPS)':
 'GND137': CDS_PINID='GND137';
NODE_NAME     U6017 J22
 '@T6G_MB_LIB.T6G(SCH_1):PAGE463_I17@PURE_QUANTA.PT5161LRS(CHIPS)':
 'GND138': CDS_PINID='GND138';
NODE_NAME     U6017 J4
 '@T6G_MB_LIB.T6G(SCH_1):PAGE463_I17@PURE_QUANTA.PT5161LRS(CHIPS)':
 'GND139': CDS_PINID='GND139';
NODE_NAME     U6017 K2
 '@T6G_MB_LIB.T6G(SCH_1):PAGE463_I17@PURE_QUANTA.PT5161LRS(CHIPS)':
 'GND140': CDS_PINID='GND140';
NODE_NAME     U6017 K34
 '@T6G_MB_LIB.T6G(SCH_1):PAGE463_I17@PURE_QUANTA.PT5161LRS(CHIPS)':
 'GND141': CDS_PINID='GND141';
NODE_NAME     U6017 L1
 '@T6G_MB_LIB.T6G(SCH_1):PAGE463_I17@PURE_QUANTA.PT5161LRS(CHIPS)':
 'GND142': CDS_PINID='GND142';
NODE_NAME     U6017 L35
 '@T6G_MB_LIB.T6G(SCH_1):PAGE463_I17@PURE_QUANTA.PT5161LRS(CHIPS)':
 'GND143': CDS_PINID='GND143';
NODE_NAME     U6017 T13
 '@T6G_MB_LIB.T6G(SCH_1):PAGE463_I17@PURE_QUANTA.PT5161LRS(CHIPS)':
 'GND144': CDS_PINID='GND144';
NODE_NAME     U6017 T22
 '@T6G_MB_LIB.T6G(SCH_1):PAGE463_I17@PURE_QUANTA.PT5161LRS(CHIPS)':
 'GND145': CDS_PINID='GND145';
NODE_NAME     U6017 T32
 '@T6G_MB_LIB.T6G(SCH_1):PAGE463_I17@PURE_QUANTA.PT5161LRS(CHIPS)':
 'GND146': CDS_PINID='GND146';
NODE_NAME     U6017 T4
 '@T6G_MB_LIB.T6G(SCH_1):PAGE463_I17@PURE_QUANTA.PT5161LRS(CHIPS)':
 'GND147': CDS_PINID='GND147';
NODE_NAME     U6017 U2
 '@T6G_MB_LIB.T6G(SCH_1):PAGE463_I17@PURE_QUANTA.PT5161LRS(CHIPS)':
 'GND148': CDS_PINID='GND148';
NODE_NAME     U6017 U34
 '@T6G_MB_LIB.T6G(SCH_1):PAGE463_I17@PURE_QUANTA.PT5161LRS(CHIPS)':
 'GND149': CDS_PINID='GND149';
NODE_NAME     U6017 V1
 '@T6G_MB_LIB.T6G(SCH_1):PAGE463_I17@PURE_QUANTA.PT5161LRS(CHIPS)':
 'GND150': CDS_PINID='GND150';
NODE_NAME     U6017 V35
 '@T6G_MB_LIB.T6G(SCH_1):PAGE463_I17@PURE_QUANTA.PT5161LRS(CHIPS)':
 'GND151': CDS_PINID='GND151';
NODE_NAME     C441 2
 '@T6G_MB_LIB.T6G(SCH_1):PAGE465_I4@PURE_QUANTA.Q_CAP(CHIPS)':
 'B': CDS_PINID='B';
NODE_NAME     C444 2
 '@T6G_MB_LIB.T6G(SCH_1):PAGE465_I6@PURE_QUANTA.Q_CAP(CHIPS)':
 'B': CDS_PINID='B';
NODE_NAME     C433 2
 '@T6G_MB_LIB.T6G(SCH_1):PAGE465_I14@PURE_QUANTA.Q_CAP(CHIPS)':
 'B': CDS_PINID='B';
NODE_NAME     C435 2
 '@T6G_MB_LIB.T6G(SCH_1):PAGE465_I15@PURE_QUANTA.Q_CAP(CHIPS)':
 'B': CDS_PINID='B';
NODE_NAME     C437 2
 '@T6G_MB_LIB.T6G(SCH_1):PAGE465_I16@PURE_QUANTA.Q_CAP(CHIPS)':
 'B': CDS_PINID='B';
NODE_NAME     C432 2
 '@T6G_MB_LIB.T6G(SCH_1):PAGE465_I17@PURE_QUANTA.Q_CAP(CHIPS)':
 'B': CDS_PINID='B';
NODE_NAME     C434 2
 '@T6G_MB_LIB.T6G(SCH_1):PAGE465_I18@PURE_QUANTA.Q_CAP(CHIPS)':
 'B': CDS_PINID='B';
NODE_NAME     C438 2
 '@T6G_MB_LIB.T6G(SCH_1):PAGE465_I19@PURE_QUANTA.Q_CAP(CHIPS)':
 'B': CDS_PINID='B';
NODE_NAME     C440 2
 '@T6G_MB_LIB.T6G(SCH_1):PAGE465_I20@PURE_QUANTA.Q_CAP(CHIPS)':
 'B': CDS_PINID='B';
NODE_NAME     C436 2
 '@T6G_MB_LIB.T6G(SCH_1):PAGE465_I21@PURE_QUANTA.Q_CAP(CHIPS)':
 'B': CDS_PINID='B';
NODE_NAME     C439 2
 '@T6G_MB_LIB.T6G(SCH_1):PAGE465_I23@PURE_QUANTA.Q_CAP(CHIPS)':
 'B': CDS_PINID='B';
NODE_NAME     C442 2
 '@T6G_MB_LIB.T6G(SCH_1):PAGE465_I24@PURE_QUANTA.Q_CAP(CHIPS)':
 'B': CDS_PINID='B';
NODE_NAME     C443 2
 '@T6G_MB_LIB.T6G(SCH_1):PAGE465_I25@PURE_QUANTA.Q_CAP(CHIPS)':
 'B': CDS_PINID='B';
NODE_NAME     C445 2
 '@T6G_MB_LIB.T6G(SCH_1):PAGE465_I26@PURE_QUANTA.Q_CAP(CHIPS)':
 'B': CDS_PINID='B';
NODE_NAME     C446 2
 '@T6G_MB_LIB.T6G(SCH_1):PAGE465_I27@PURE_QUANTA.Q_CAP(CHIPS)':
 'B': CDS_PINID='B';
NODE_NAME     C447 2
 '@T6G_MB_LIB.T6G(SCH_1):PAGE465_I28@PURE_QUANTA.Q_CAP(CHIPS)':
 'B': CDS_PINID='B';
NODE_NAME     C463 2
 '@T6G_MB_LIB.T6G(SCH_1):PAGE465_I34@PURE_QUANTA.Q_CAP(CHIPS)':
 'B': CDS_PINID='B';
NODE_NAME     C464 2
 '@T6G_MB_LIB.T6G(SCH_1):PAGE465_I35@PURE_QUANTA.Q_CAP(CHIPS)':
 'B': CDS_PINID='B';
NODE_NAME     C495 2
 '@T6G_MB_LIB.T6G(SCH_1):PAGE465_I37@PURE_QUANTA.Q_CAP(CHIPS)':
 'B': CDS_PINID='B';
NODE_NAME     C470 2
 '@T6G_MB_LIB.T6G(SCH_1):PAGE465_I38@PURE_QUANTA.Q_CAP(CHIPS)':
 'B': CDS_PINID='B';
NODE_NAME     C459 2
 '@T6G_MB_LIB.T6G(SCH_1):PAGE465_I39@PURE_QUANTA.Q_CAP(CHIPS)':
 'B': CDS_PINID='B';
NODE_NAME     C480 2
 '@T6G_MB_LIB.T6G(SCH_1):PAGE465_I40@PURE_QUANTA.Q_CAP(CHIPS)':
 'B': CDS_PINID='B';
NODE_NAME     C490 2
 '@T6G_MB_LIB.T6G(SCH_1):PAGE465_I41@PURE_QUANTA.Q_CAP(CHIPS)':
 'B': CDS_PINID='B';
NODE_NAME     C500 2
 '@T6G_MB_LIB.T6G(SCH_1):PAGE465_I42@PURE_QUANTA.Q_CAP(CHIPS)':
 'B': CDS_PINID='B';
NODE_NAME     C473 2
 '@T6G_MB_LIB.T6G(SCH_1):PAGE465_I43@PURE_QUANTA.Q_CAP(CHIPS)':
 'B': CDS_PINID='B';
NODE_NAME     C448 2
 '@T6G_MB_LIB.T6G(SCH_1):PAGE465_I44@PURE_QUANTA.Q_CAP(CHIPS)':
 'B': CDS_PINID='B';
NODE_NAME     C453 2
 '@T6G_MB_LIB.T6G(SCH_1):PAGE465_I45@PURE_QUANTA.Q_CAP(CHIPS)':
 'B': CDS_PINID='B';
NODE_NAME     C477 2
 '@T6G_MB_LIB.T6G(SCH_1):PAGE465_I46@PURE_QUANTA.Q_CAP(CHIPS)':
 'B': CDS_PINID='B';
NODE_NAME     C450 2
 '@T6G_MB_LIB.T6G(SCH_1):PAGE465_I47@PURE_QUANTA.Q_CAP(CHIPS)':
 'B': CDS_PINID='B';
NODE_NAME     C485 2
 '@T6G_MB_LIB.T6G(SCH_1):PAGE465_I48@PURE_QUANTA.Q_CAP(CHIPS)':
 'B': CDS_PINID='B';
NODE_NAME     C488 2
 '@T6G_MB_LIB.T6G(SCH_1):PAGE465_I49@PURE_QUANTA.Q_CAP(CHIPS)':
 'B': CDS_PINID='B';
NODE_NAME     C472 2
 '@T6G_MB_LIB.T6G(SCH_1):PAGE465_I50@PURE_QUANTA.Q_CAP(CHIPS)':
 'B': CDS_PINID='B';
NODE_NAME     C469 2
 '@T6G_MB_LIB.T6G(SCH_1):PAGE465_I51@PURE_QUANTA.Q_CAP(CHIPS)':
 'B': CDS_PINID='B';
NODE_NAME     C494 2
 '@T6G_MB_LIB.T6G(SCH_1):PAGE465_I52@PURE_QUANTA.Q_CAP(CHIPS)':
 'B': CDS_PINID='B';
NODE_NAME     C491 2
 '@T6G_MB_LIB.T6G(SCH_1):PAGE465_I53@PURE_QUANTA.Q_CAP(CHIPS)':
 'B': CDS_PINID='B';
NODE_NAME     C492 2
 '@T6G_MB_LIB.T6G(SCH_1):PAGE465_I54@PURE_QUANTA.Q_CAP(CHIPS)':
 'B': CDS_PINID='B';
NODE_NAME     C481 2
 '@T6G_MB_LIB.T6G(SCH_1):PAGE465_I56@PURE_QUANTA.Q_CAP(CHIPS)':
 'B': CDS_PINID='B';
NODE_NAME     C457 2
 '@T6G_MB_LIB.T6G(SCH_1):PAGE465_I57@PURE_QUANTA.Q_CAP(CHIPS)':
 'B': CDS_PINID='B';
NODE_NAME     C497 2
 '@T6G_MB_LIB.T6G(SCH_1):PAGE465_I60@PURE_QUANTA.Q_CAP(CHIPS)':
 'B': CDS_PINID='B';
NODE_NAME     C455 2
 '@T6G_MB_LIB.T6G(SCH_1):PAGE465_I61@PURE_QUANTA.Q_CAP(CHIPS)':
 'B': CDS_PINID='B';
NODE_NAME     C466 2
 '@T6G_MB_LIB.T6G(SCH_1):PAGE465_I64@PURE_QUANTA.Q_CAP(CHIPS)':
 'B': CDS_PINID='B';
NODE_NAME     C471 2
 '@T6G_MB_LIB.T6G(SCH_1):PAGE465_I65@PURE_QUANTA.Q_CAP(CHIPS)':
 'B': CDS_PINID='B';
NODE_NAME     C474 2
 '@T6G_MB_LIB.T6G(SCH_1):PAGE465_I67@PURE_QUANTA.Q_CAP(CHIPS)':
 'B': CDS_PINID='B';
NODE_NAME     C478 2
 '@T6G_MB_LIB.T6G(SCH_1):PAGE465_I68@PURE_QUANTA.Q_CAP(CHIPS)':
 'B': CDS_PINID='B';
NODE_NAME     C475 2
 '@T6G_MB_LIB.T6G(SCH_1):PAGE465_I69@PURE_QUANTA.Q_CAP(CHIPS)':
 'B': CDS_PINID='B';
NODE_NAME     C501 2
 '@T6G_MB_LIB.T6G(SCH_1):PAGE465_I70@PURE_QUANTA.Q_CAP(CHIPS)':
 'B': CDS_PINID='B';
NODE_NAME     C476 2
 '@T6G_MB_LIB.T6G(SCH_1):PAGE465_I71@PURE_QUANTA.Q_CAP(CHIPS)':
 'B': CDS_PINID='B';
NODE_NAME     C489 2
 '@T6G_MB_LIB.T6G(SCH_1):PAGE465_I72@PURE_QUANTA.Q_CAP(CHIPS)':
 'B': CDS_PINID='B';
NODE_NAME     C484 2
 '@T6G_MB_LIB.T6G(SCH_1):PAGE465_I73@PURE_QUANTA.Q_CAP(CHIPS)':
 'B': CDS_PINID='B';
NODE_NAME     C454 2
 '@T6G_MB_LIB.T6G(SCH_1):PAGE465_I74@PURE_QUANTA.Q_CAP(CHIPS)':
 'B': CDS_PINID='B';
NODE_NAME     C487 2
 '@T6G_MB_LIB.T6G(SCH_1):PAGE465_I75@PURE_QUANTA.Q_CAP(CHIPS)':
 'B': CDS_PINID='B';
NODE_NAME     C499 2
 '@T6G_MB_LIB.T6G(SCH_1):PAGE465_I76@PURE_QUANTA.Q_CAP(CHIPS)':
 'B': CDS_PINID='B';
NODE_NAME     C482 2
 '@T6G_MB_LIB.T6G(SCH_1):PAGE465_I77@PURE_QUANTA.Q_CAP(CHIPS)':
 'B': CDS_PINID='B';
NODE_NAME     C449 2
 '@T6G_MB_LIB.T6G(SCH_1):PAGE465_I78@PURE_QUANTA.Q_CAP(CHIPS)':
 'B': CDS_PINID='B';
NODE_NAME     C451 2
 '@T6G_MB_LIB.T6G(SCH_1):PAGE465_I79@PURE_QUANTA.Q_CAP(CHIPS)':
 'B': CDS_PINID='B';
NODE_NAME     C493 2
 '@T6G_MB_LIB.T6G(SCH_1):PAGE465_I80@PURE_QUANTA.Q_CAP(CHIPS)':
 'B': CDS_PINID='B';
NODE_NAME     C458 2
 '@T6G_MB_LIB.T6G(SCH_1):PAGE465_I82@PURE_QUANTA.Q_CAP(CHIPS)':
 'B': CDS_PINID='B';
NODE_NAME     C462 2
 '@T6G_MB_LIB.T6G(SCH_1):PAGE465_I83@PURE_QUANTA.Q_CAP(CHIPS)':
 'B': CDS_PINID='B';
NODE_NAME     C452 2
 '@T6G_MB_LIB.T6G(SCH_1):PAGE465_I84@PURE_QUANTA.Q_CAP(CHIPS)':
 'B': CDS_PINID='B';
NODE_NAME     C486 2
 '@T6G_MB_LIB.T6G(SCH_1):PAGE465_I85@PURE_QUANTA.Q_CAP(CHIPS)':
 'B': CDS_PINID='B';
NODE_NAME     C483 2
 '@T6G_MB_LIB.T6G(SCH_1):PAGE465_I86@PURE_QUANTA.Q_CAP(CHIPS)':
 'B': CDS_PINID='B';
NODE_NAME     C479 2
 '@T6G_MB_LIB.T6G(SCH_1):PAGE465_I87@PURE_QUANTA.Q_CAP(CHIPS)':
 'B': CDS_PINID='B';
NODE_NAME     C1713 2
 '@T6G_MB_LIB.T6G(SCH_1):PAGE246_I61@PURE_QUANTA.Q_CAP(CHIPS)':
 'B': CDS_PINID='B';
NODE_NAME     U181 12
 '@T6G_MB_LIB.T6G(SCH_1):PAGE246_I83@PURE_QUANTA.PCA9539RPW(CHIPS)':
 'VSS': CDS_PINID='VSS';
NODE_NAME     R4154 2
 '@T6G_MB_LIB.T6G(SCH_1):PAGE332_I2@PURE_QUANTA.Q_RES(CHIPS)':
 'B': CDS_PINID='B';
NODE_NAME     Q134 1
 '@T6G_MB_LIB.T6G(SCH_1):PAGE332_I6@PURE_QUANTA.MOSFET_NCH_DUAL(CHIPS)':
 'S1': CDS_PINID='S1';
NODE_NAME     Q134 4
 '@T6G_MB_LIB.T6G(SCH_1):PAGE332_I10@PURE_QUANTA.MOSFET_NCH_DUAL(CHIPS)':
 'S2': CDS_PINID='S2';
NODE_NAME     R4122 2
 '@T6G_MB_LIB.T6G(SCH_1):PAGE332_I13@PURE_QUANTA.Q_RES(CHIPS)':
 'B': CDS_PINID='B';
NODE_NAME     R4120 2
 '@T6G_MB_LIB.T6G(SCH_1):PAGE332_I22@PURE_QUANTA.Q_RES(CHIPS)':
 'B': CDS_PINID='B';
NODE_NAME     Q132 1
 '@T6G_MB_LIB.T6G(SCH_1):PAGE332_I25@PURE_QUANTA.MOSFET_NCH_DUAL(CHIPS)':
 'S1': CDS_PINID='S1';
NODE_NAME     Q131 1
 '@T6G_MB_LIB.T6G(SCH_1):PAGE332_I30@PURE_QUANTA.MOSFET_NCH_DUAL(CHIPS)':
 'S1': CDS_PINID='S1';
NODE_NAME     Q132 4
 '@T6G_MB_LIB.T6G(SCH_1):PAGE332_I32@PURE_QUANTA.MOSFET_NCH_DUAL(CHIPS)':
 'S2': CDS_PINID='S2';
NODE_NAME     Q128 1
 '@T6G_MB_LIB.T6G(SCH_1):PAGE332_I37@PURE_QUANTA.MOSFET_NCH_DUAL(CHIPS)':
 'S1': CDS_PINID='S1';
NODE_NAME     Q131 4
 '@T6G_MB_LIB.T6G(SCH_1):PAGE332_I40@PURE_QUANTA.MOSFET_NCH_DUAL(CHIPS)':
 'S2': CDS_PINID='S2';
NODE_NAME     Q128 4
 '@T6G_MB_LIB.T6G(SCH_1):PAGE332_I42@PURE_QUANTA.MOSFET_NCH_DUAL(CHIPS)':
 'S2': CDS_PINID='S2';
NODE_NAME     C15 2
 '@T6G_MB_LIB.T6G(SCH_1):PAGE332_I50@PURE_QUANTA.Q_CAP(CHIPS)':
 'B': CDS_PINID='B';
NODE_NAME     R4559 2
 '@T6G_MB_LIB.T6G(SCH_1):PAGE332_I54@PURE_QUANTA.Q_RES(CHIPS)':
 'B': CDS_PINID='B';
NODE_NAME     Q146 1
 '@T6G_MB_LIB.T6G(SCH_1):PAGE332_I57@PURE_QUANTA.MOSFET_NCH_DUAL(CHIPS)':
 'S1': CDS_PINID='S1';
NODE_NAME     C18 2
 '@T6G_MB_LIB.T6G(SCH_1):PAGE332_I61@PURE_QUANTA.Q_CAP(CHIPS)':
 'B': CDS_PINID='B';
NODE_NAME     C13 2
 '@T6G_MB_LIB.T6G(SCH_1):PAGE332_I64@PURE_QUANTA.Q_CAP(CHIPS)':
 'B': CDS_PINID='B';
NODE_NAME     C14 2
 '@T6G_MB_LIB.T6G(SCH_1):PAGE332_I73@PURE_QUANTA.Q_CAP(CHIPS)':
 'B': CDS_PINID='B';
NODE_NAME     C12 2
 '@T6G_MB_LIB.T6G(SCH_1):PAGE332_I75@PURE_QUANTA.Q_CAP(CHIPS)':
 'B': CDS_PINID='B';
NODE_NAME     R4134 2
 '@T6G_MB_LIB.T6G(SCH_1):PAGE332_I81@PURE_QUANTA.Q_RES(CHIPS)':
 'B': CDS_PINID='B';
NODE_NAME     Q129 1
 '@T6G_MB_LIB.T6G(SCH_1):PAGE332_I86@PURE_QUANTA.MOSFET_NCH_DUAL(CHIPS)':
 'S1': CDS_PINID='S1';
NODE_NAME     R4136 2
 '@T6G_MB_LIB.T6G(SCH_1):PAGE332_I92@PURE_QUANTA.Q_RES(CHIPS)':
 'B': CDS_PINID='B';
NODE_NAME     R4132 2
 '@T6G_MB_LIB.T6G(SCH_1):PAGE332_I96@PURE_QUANTA.Q_RES(CHIPS)':
 'B': CDS_PINID='B';
NODE_NAME     Q133 1
 '@T6G_MB_LIB.T6G(SCH_1):PAGE332_I98@PURE_QUANTA.MOSFET_NCH_DUAL(CHIPS)':
 'S1': CDS_PINID='S1';
NODE_NAME     Q130 1
 '@T6G_MB_LIB.T6G(SCH_1):PAGE332_I102@PURE_QUANTA.MOSFET_NCH_DUAL(CHIPS)':
 'S1': CDS_PINID='S1';
NODE_NAME     Q129 4
 '@T6G_MB_LIB.T6G(SCH_1):PAGE332_I113@PURE_QUANTA.MOSFET_NCH_DUAL(CHIPS)':
 'S2': CDS_PINID='S2';
NODE_NAME     C17 2
 '@T6G_MB_LIB.T6G(SCH_1):PAGE332_I118@PURE_QUANTA.Q_CAP(CHIPS)':
 'B': CDS_PINID='B';
NODE_NAME     Q133 4
 '@T6G_MB_LIB.T6G(SCH_1):PAGE332_I120@PURE_QUANTA.MOSFET_NCH_DUAL(CHIPS)':
 'S2': CDS_PINID='S2';
NODE_NAME     Q130 4
 '@T6G_MB_LIB.T6G(SCH_1):PAGE332_I123@PURE_QUANTA.MOSFET_NCH_DUAL(CHIPS)':
 'S2': CDS_PINID='S2';
NODE_NAME     C19 2
 '@T6G_MB_LIB.T6G(SCH_1):PAGE332_I127@PURE_QUANTA.Q_CAP(CHIPS)':
 'B': CDS_PINID='B';
NODE_NAME     C16 2
 '@T6G_MB_LIB.T6G(SCH_1):PAGE332_I130@PURE_QUANTA.Q_CAP(CHIPS)':
 'B': CDS_PINID='B';
NODE_NAME     Q146 4
 '@T6G_MB_LIB.T6G(SCH_1):PAGE332_I134@PURE_QUANTA.MOSFET_NCH_DUAL(CHIPS)':
 'S2': CDS_PINID='S2';
NODE_NAME     R4124 2
 '@T6G_MB_LIB.T6G(SCH_1):PAGE332_I135@PURE_QUANTA.Q_RES(CHIPS)':
 'B': CDS_PINID='B';
NODE_NAME     R9007 2
 '@T6G_MB_LIB.T6G(SCH_1):PAGE330_I2@PURE_QUANTA.Q_RES(CHIPS)':
 'B': CDS_PINID='B';
NODE_NAME     Q9001 1
 '@T6G_MB_LIB.T6G(SCH_1):PAGE330_I3@PURE_QUANTA.MOSFET_NCH_DUAL(CHIPS)':
 'S1': CDS_PINID='S1';
NODE_NAME     R8001 2
 '@T6G_MB_LIB.T6G(SCH_1):PAGE330_I12@PURE_QUANTA.Q_RES(CHIPS)':
 'B': CDS_PINID='B';
NODE_NAME     R9003 2
 '@T6G_MB_LIB.T6G(SCH_1):PAGE330_I20@PURE_QUANTA.Q_RES(CHIPS)':
 'B': CDS_PINID='B';
NODE_NAME     Q9001 4
 '@T6G_MB_LIB.T6G(SCH_1):PAGE330_I22@PURE_QUANTA.MOSFET_NCH_DUAL(CHIPS)':
 'S2': CDS_PINID='S2';
NODE_NAME     Q8000 1
 '@T6G_MB_LIB.T6G(SCH_1):PAGE330_I29@PURE_QUANTA.MOSFET_NCH_DUAL(CHIPS)':
 'S1': CDS_PINID='S1';
NODE_NAME     Q9000 4
 '@T6G_MB_LIB.T6G(SCH_1):PAGE330_I31@PURE_QUANTA.MOSFET_NCH_DUAL(CHIPS)':
 'S2': CDS_PINID='S2';
NODE_NAME     C8000 2
 '@T6G_MB_LIB.T6G(SCH_1):PAGE330_I36@PURE_QUANTA.Q_CAP(CHIPS)':
 'B': CDS_PINID='B';
NODE_NAME     C9001 2
 '@T6G_MB_LIB.T6G(SCH_1):PAGE330_I42@PURE_QUANTA.Q_CAP(CHIPS)':
 'B': CDS_PINID='B';
NODE_NAME     C9000 2
 '@T6G_MB_LIB.T6G(SCH_1):PAGE330_I45@PURE_QUANTA.Q_CAP(CHIPS)':
 'B': CDS_PINID='B';
NODE_NAME     R9015 2
 '@T6G_MB_LIB.T6G(SCH_1):PAGE330_I50@PURE_QUANTA.Q_RES(CHIPS)':
 'B': CDS_PINID='B';
NODE_NAME     Q9002 1
 '@T6G_MB_LIB.T6G(SCH_1):PAGE330_I52@PURE_QUANTA.MOSFET_NCH_DUAL(CHIPS)':
 'S1': CDS_PINID='S1';
NODE_NAME     R3441 2
 '@T6G_MB_LIB.T6G(SCH_1):PAGE330_I64@PURE_QUANTA.Q_RES(CHIPS)':
 'B': CDS_PINID='B';
NODE_NAME     R3440 2
 '@T6G_MB_LIB.T6G(SCH_1):PAGE330_I65@PURE_QUANTA.Q_RES(CHIPS)':
 'B': CDS_PINID='B';
NODE_NAME     R3443 2
 '@T6G_MB_LIB.T6G(SCH_1):PAGE330_I66@PURE_QUANTA.Q_RES(CHIPS)':
 'B': CDS_PINID='B';
NODE_NAME     R3442 2
 '@T6G_MB_LIB.T6G(SCH_1):PAGE330_I67@PURE_QUANTA.Q_RES(CHIPS)':
 'B': CDS_PINID='B';
NODE_NAME     R2656 2
 '@T6G_MB_LIB.T6G(SCH_1):PAGE330_I69@PURE_QUANTA.Q_RES(CHIPS)':
 'B': CDS_PINID='B';
NODE_NAME     C9002 2
 '@T6G_MB_LIB.T6G(SCH_1):PAGE330_I71@PURE_QUANTA.Q_CAP(CHIPS)':
 'B': CDS_PINID='B';
NODE_NAME     Q9002 4
 '@T6G_MB_LIB.T6G(SCH_1):PAGE330_I75@PURE_QUANTA.MOSFET_NCH_DUAL(CHIPS)':
 'S2': CDS_PINID='S2';
NODE_NAME     C6084 2
 '@T6G_MB_LIB.T6G(SCH_1):PAGE371_I107@PURE_QUANTA.Q_CAP(CHIPS)':
 'B': CDS_PINID='B';
NODE_NAME     C9003 2
 '@T6G_MB_LIB.T6G(SCH_1):PAGE371_I110@PURE_QUANTA.Q_CAP(CHIPS)':
 'B': CDS_PINID='B';
NODE_NAME     C1561 2
 '@T6G_MB_LIB.T6G(SCH_1):PAGE372_I96@PURE_QUANTA.Q_CAP(CHIPS)':
 'B': CDS_PINID='B';
NODE_NAME     C9004 2
 '@T6G_MB_LIB.T6G(SCH_1):PAGE372_I99@PURE_QUANTA.Q_CAP(CHIPS)':
 'B': CDS_PINID='B';
NODE_NAME     R979 2
 '@T6G_MB_LIB.T6G(SCH_1):PAGE385_I27@PURE_QUANTA.Q_RES(CHIPS)':
 'B': CDS_PINID='B';
NODE_NAME     R980 2
 '@T6G_MB_LIB.T6G(SCH_1):PAGE385_I28@PURE_QUANTA.Q_RES(CHIPS)':
 'B': CDS_PINID='B';
NODE_NAME     R982 2
 '@T6G_MB_LIB.T6G(SCH_1):PAGE385_I29@PURE_QUANTA.Q_RES(CHIPS)':
 'B': CDS_PINID='B';
NODE_NAME     R623 2
 '@T6G_MB_LIB.T6G(SCH_1):PAGE385_I37@PURE_QUANTA.Q_RES(CHIPS)':
 'B': CDS_PINID='B';
NODE_NAME     R624 2
 '@T6G_MB_LIB.T6G(SCH_1):PAGE385_I38@PURE_QUANTA.Q_RES(CHIPS)':
 'B': CDS_PINID='B';
NODE_NAME     U6010 E30
 '@T6G_MB_LIB.T6G(SCH_1):PAGE385_I53@PURE_QUANTA.PT5161LRS(CHIPS)':
 'T_SENSE': CDS_PINID='T_SENSE';
NODE_NAME     R984 2
 '@T6G_MB_LIB.T6G(SCH_1):PAGE385_I57@PURE_QUANTA.Q_RES(CHIPS)':
 'B': CDS_PINID='B';
NODE_NAME     R995 2
 '@T6G_MB_LIB.T6G(SCH_1):PAGE385_I58@PURE_QUANTA.Q_RES(CHIPS)':
 'B': CDS_PINID='B';
NODE_NAME     R997 2
 '@T6G_MB_LIB.T6G(SCH_1):PAGE385_I60@PURE_QUANTA.Q_RES(CHIPS)':
 'B': CDS_PINID='B';
NODE_NAME     R1001 2
 '@T6G_MB_LIB.T6G(SCH_1):PAGE385_I71@PURE_QUANTA.Q_RES(CHIPS)':
 'B': CDS_PINID='B';
NODE_NAME     R965 2
 '@T6G_MB_LIB.T6G(SCH_1):PAGE385_I86@PURE_QUANTA.Q_RES(CHIPS)':
 'B': CDS_PINID='B';
NODE_NAME     R967 2
 '@T6G_MB_LIB.T6G(SCH_1):PAGE385_I87@PURE_QUANTA.Q_RES(CHIPS)':
 'B': CDS_PINID='B';
NODE_NAME     R969 2
 '@T6G_MB_LIB.T6G(SCH_1):PAGE385_I90@PURE_QUANTA.Q_RES(CHIPS)':
 'B': CDS_PINID='B';
NODE_NAME     R971 2
 '@T6G_MB_LIB.T6G(SCH_1):PAGE385_I96@PURE_QUANTA.Q_RES(CHIPS)':
 'B': CDS_PINID='B';
NODE_NAME     R970 2
 '@T6G_MB_LIB.T6G(SCH_1):PAGE385_I97@PURE_QUANTA.Q_RES(CHIPS)':
 'B': CDS_PINID='B';
NODE_NAME     R6821 2
 '@T6G_MB_LIB.T6G(SCH_1):PAGE386_I13@PURE_QUANTA.Q_RES(CHIPS)':
 'B': CDS_PINID='B';
NODE_NAME     R6820 2
 '@T6G_MB_LIB.T6G(SCH_1):PAGE386_I15@PURE_QUANTA.Q_RES(CHIPS)':
 'B': CDS_PINID='B';
NODE_NAME     U6010 AC13
 '@T6G_MB_LIB.T6G(SCH_1):PAGE386_I17@PURE_QUANTA.PT5161LRS(CHIPS)':
 'GND1': CDS_PINID='GND1';
NODE_NAME     U6010 AC22
 '@T6G_MB_LIB.T6G(SCH_1):PAGE386_I17@PURE_QUANTA.PT5161LRS(CHIPS)':
 'GND2': CDS_PINID='GND2';
NODE_NAME     U6010 AC32
 '@T6G_MB_LIB.T6G(SCH_1):PAGE386_I17@PURE_QUANTA.PT5161LRS(CHIPS)':
 'GND3': CDS_PINID='GND3';
NODE_NAME     U6010 AC4
 '@T6G_MB_LIB.T6G(SCH_1):PAGE386_I17@PURE_QUANTA.PT5161LRS(CHIPS)':
 'GND4': CDS_PINID='GND4';
NODE_NAME     U6010 AD2
 '@T6G_MB_LIB.T6G(SCH_1):PAGE386_I17@PURE_QUANTA.PT5161LRS(CHIPS)':
 'GND5': CDS_PINID='GND5';
NODE_NAME     U6010 AD34
 '@T6G_MB_LIB.T6G(SCH_1):PAGE386_I17@PURE_QUANTA.PT5161LRS(CHIPS)':
 'GND6': CDS_PINID='GND6';
NODE_NAME     U6010 AE1
 '@T6G_MB_LIB.T6G(SCH_1):PAGE386_I17@PURE_QUANTA.PT5161LRS(CHIPS)':
 'GND7': CDS_PINID='GND7';
NODE_NAME     U6010 AE35
 '@T6G_MB_LIB.T6G(SCH_1):PAGE386_I17@PURE_QUANTA.PT5161LRS(CHIPS)':
 'GND8': CDS_PINID='GND8';
NODE_NAME     U6010 AK13
 '@T6G_MB_LIB.T6G(SCH_1):PAGE386_I17@PURE_QUANTA.PT5161LRS(CHIPS)':
 'GND9': CDS_PINID='GND9';
NODE_NAME     U6010 AK22
 '@T6G_MB_LIB.T6G(SCH_1):PAGE386_I17@PURE_QUANTA.PT5161LRS(CHIPS)':
 'GND10': CDS_PINID='GND10';
NODE_NAME     U6010 AK32
 '@T6G_MB_LIB.T6G(SCH_1):PAGE386_I17@PURE_QUANTA.PT5161LRS(CHIPS)':
 'GND11': CDS_PINID='GND11';
NODE_NAME     U6010 AK4
 '@T6G_MB_LIB.T6G(SCH_1):PAGE386_I17@PURE_QUANTA.PT5161LRS(CHIPS)':
 'GND12': CDS_PINID='GND12';
NODE_NAME     U6010 AL2
 '@T6G_MB_LIB.T6G(SCH_1):PAGE386_I17@PURE_QUANTA.PT5161LRS(CHIPS)':
 'GND13': CDS_PINID='GND13';
NODE_NAME     U6010 AL34
 '@T6G_MB_LIB.T6G(SCH_1):PAGE386_I17@PURE_QUANTA.PT5161LRS(CHIPS)':
 'GND14': CDS_PINID='GND14';
NODE_NAME     U6010 AM1
 '@T6G_MB_LIB.T6G(SCH_1):PAGE386_I17@PURE_QUANTA.PT5161LRS(CHIPS)':
 'GND15': CDS_PINID='GND15';
NODE_NAME     U6010 AM35
 '@T6G_MB_LIB.T6G(SCH_1):PAGE386_I17@PURE_QUANTA.PT5161LRS(CHIPS)':
 'GND16': CDS_PINID='GND16';
NODE_NAME     U6010 AU13
 '@T6G_MB_LIB.T6G(SCH_1):PAGE386_I17@PURE_QUANTA.PT5161LRS(CHIPS)':
 'GND17': CDS_PINID='GND17';
NODE_NAME     U6010 AU22
 '@T6G_MB_LIB.T6G(SCH_1):PAGE386_I17@PURE_QUANTA.PT5161LRS(CHIPS)':
 'GND18': CDS_PINID='GND18';
NODE_NAME     U6010 AU32
 '@T6G_MB_LIB.T6G(SCH_1):PAGE386_I17@PURE_QUANTA.PT5161LRS(CHIPS)':
 'GND19': CDS_PINID='GND19';
NODE_NAME     U6010 AU4
 '@T6G_MB_LIB.T6G(SCH_1):PAGE386_I17@PURE_QUANTA.PT5161LRS(CHIPS)':
 'GND20': CDS_PINID='GND20';
NODE_NAME     U6010 AV2
 '@T6G_MB_LIB.T6G(SCH_1):PAGE386_I17@PURE_QUANTA.PT5161LRS(CHIPS)':
 'GND21': CDS_PINID='GND21';
NODE_NAME     U6010 AV34
 '@T6G_MB_LIB.T6G(SCH_1):PAGE386_I17@PURE_QUANTA.PT5161LRS(CHIPS)':
 'GND22': CDS_PINID='GND22';
NODE_NAME     U6010 AW1
 '@T6G_MB_LIB.T6G(SCH_1):PAGE386_I17@PURE_QUANTA.PT5161LRS(CHIPS)':
 'GND23': CDS_PINID='GND23';
NODE_NAME     U6010 AW35
 '@T6G_MB_LIB.T6G(SCH_1):PAGE386_I17@PURE_QUANTA.PT5161LRS(CHIPS)':
 'GND24': CDS_PINID='GND24';
NODE_NAME     U6010 B19
 '@T6G_MB_LIB.T6G(SCH_1):PAGE386_I17@PURE_QUANTA.PT5161LRS(CHIPS)':
 'GND25': CDS_PINID='GND25';
NODE_NAME     U6010 BD13
 '@T6G_MB_LIB.T6G(SCH_1):PAGE386_I17@PURE_QUANTA.PT5161LRS(CHIPS)':
 'GND26': CDS_PINID='GND26';
NODE_NAME     U6010 BD22
 '@T6G_MB_LIB.T6G(SCH_1):PAGE386_I17@PURE_QUANTA.PT5161LRS(CHIPS)':
 'GND27': CDS_PINID='GND27';
NODE_NAME     U6010 BD32
 '@T6G_MB_LIB.T6G(SCH_1):PAGE386_I17@PURE_QUANTA.PT5161LRS(CHIPS)':
 'GND28': CDS_PINID='GND28';
NODE_NAME     U6010 BD4
 '@T6G_MB_LIB.T6G(SCH_1):PAGE386_I17@PURE_QUANTA.PT5161LRS(CHIPS)':
 'GND29': CDS_PINID='GND29';
NODE_NAME     U6010 BE2
 '@T6G_MB_LIB.T6G(SCH_1):PAGE386_I17@PURE_QUANTA.PT5161LRS(CHIPS)':
 'GND30': CDS_PINID='GND30';
NODE_NAME     U6010 BE34
 '@T6G_MB_LIB.T6G(SCH_1):PAGE386_I17@PURE_QUANTA.PT5161LRS(CHIPS)':
 'GND31': CDS_PINID='GND31';
NODE_NAME     U6010 BF1
 '@T6G_MB_LIB.T6G(SCH_1):PAGE386_I17@PURE_QUANTA.PT5161LRS(CHIPS)':
 'GND32': CDS_PINID='GND32';
NODE_NAME     U6010 BF35
 '@T6G_MB_LIB.T6G(SCH_1):PAGE386_I17@PURE_QUANTA.PT5161LRS(CHIPS)':
 'GND33': CDS_PINID='GND33';
NODE_NAME     U6010 BL13
 '@T6G_MB_LIB.T6G(SCH_1):PAGE386_I17@PURE_QUANTA.PT5161LRS(CHIPS)':
 'GND34': CDS_PINID='GND34';
NODE_NAME     U6010 BL22
 '@T6G_MB_LIB.T6G(SCH_1):PAGE386_I17@PURE_QUANTA.PT5161LRS(CHIPS)':
 'GND35': CDS_PINID='GND35';
NODE_NAME     U6010 BL32
 '@T6G_MB_LIB.T6G(SCH_1):PAGE386_I17@PURE_QUANTA.PT5161LRS(CHIPS)':
 'GND36': CDS_PINID='GND36';
NODE_NAME     U6010 BL4
 '@T6G_MB_LIB.T6G(SCH_1):PAGE386_I17@PURE_QUANTA.PT5161LRS(CHIPS)':
 'GND37': CDS_PINID='GND37';
NODE_NAME     U6010 BM2
 '@T6G_MB_LIB.T6G(SCH_1):PAGE386_I17@PURE_QUANTA.PT5161LRS(CHIPS)':
 'GND38': CDS_PINID='GND38';
NODE_NAME     U6010 BM34
 '@T6G_MB_LIB.T6G(SCH_1):PAGE386_I17@PURE_QUANTA.PT5161LRS(CHIPS)':
 'GND39': CDS_PINID='GND39';
NODE_NAME     U6010 BN1
 '@T6G_MB_LIB.T6G(SCH_1):PAGE386_I17@PURE_QUANTA.PT5161LRS(CHIPS)':
 'GND40': CDS_PINID='GND40';
NODE_NAME     U6010 BN35
 '@T6G_MB_LIB.T6G(SCH_1):PAGE386_I17@PURE_QUANTA.PT5161LRS(CHIPS)':
 'GND41': CDS_PINID='GND41';
NODE_NAME     U6010 BV13
 '@T6G_MB_LIB.T6G(SCH_1):PAGE386_I17@PURE_QUANTA.PT5161LRS(CHIPS)':
 'GND42': CDS_PINID='GND42';
NODE_NAME     U6010 BV22
 '@T6G_MB_LIB.T6G(SCH_1):PAGE386_I17@PURE_QUANTA.PT5161LRS(CHIPS)':
 'GND43': CDS_PINID='GND43';
NODE_NAME     U6010 BV32
 '@T6G_MB_LIB.T6G(SCH_1):PAGE386_I17@PURE_QUANTA.PT5161LRS(CHIPS)':
 'GND44': CDS_PINID='GND44';
NODE_NAME     U6010 BV4
 '@T6G_MB_LIB.T6G(SCH_1):PAGE386_I17@PURE_QUANTA.PT5161LRS(CHIPS)':
 'GND45': CDS_PINID='GND45';
NODE_NAME     U6010 BW2
 '@T6G_MB_LIB.T6G(SCH_1):PAGE386_I17@PURE_QUANTA.PT5161LRS(CHIPS)':
 'GND46': CDS_PINID='GND46';
NODE_NAME     U6010 BW34
 '@T6G_MB_LIB.T6G(SCH_1):PAGE386_I17@PURE_QUANTA.PT5161LRS(CHIPS)':
 'GND47': CDS_PINID='GND47';
NODE_NAME     U6010 BY1
 '@T6G_MB_LIB.T6G(SCH_1):PAGE386_I17@PURE_QUANTA.PT5161LRS(CHIPS)':
 'GND48': CDS_PINID='GND48';
NODE_NAME     U6010 BY35
 '@T6G_MB_LIB.T6G(SCH_1):PAGE386_I17@PURE_QUANTA.PT5161LRS(CHIPS)':
 'GND49': CDS_PINID='GND49';
NODE_NAME     U6010 CE13
 '@T6G_MB_LIB.T6G(SCH_1):PAGE386_I17@PURE_QUANTA.PT5161LRS(CHIPS)':
 'GND50': CDS_PINID='GND50';
NODE_NAME     U6010 CE22
 '@T6G_MB_LIB.T6G(SCH_1):PAGE386_I17@PURE_QUANTA.PT5161LRS(CHIPS)':
 'GND51': CDS_PINID='GND51';
NODE_NAME     U6010 CE32
 '@T6G_MB_LIB.T6G(SCH_1):PAGE386_I17@PURE_QUANTA.PT5161LRS(CHIPS)':
 'GND52': CDS_PINID='GND52';
NODE_NAME     U6010 CE4
 '@T6G_MB_LIB.T6G(SCH_1):PAGE386_I17@PURE_QUANTA.PT5161LRS(CHIPS)':
 'GND53': CDS_PINID='GND53';
NODE_NAME     U6010 CF2
 '@T6G_MB_LIB.T6G(SCH_1):PAGE386_I17@PURE_QUANTA.PT5161LRS(CHIPS)':
 'GND54': CDS_PINID='GND54';
NODE_NAME     U6010 CF34
 '@T6G_MB_LIB.T6G(SCH_1):PAGE386_I17@PURE_QUANTA.PT5161LRS(CHIPS)':
 'GND55': CDS_PINID='GND55';
NODE_NAME     U6010 CG1
 '@T6G_MB_LIB.T6G(SCH_1):PAGE386_I17@PURE_QUANTA.PT5161LRS(CHIPS)':
 'GND56': CDS_PINID='GND56';
NODE_NAME     U6010 CG35
 '@T6G_MB_LIB.T6G(SCH_1):PAGE386_I17@PURE_QUANTA.PT5161LRS(CHIPS)':
 'GND57': CDS_PINID='GND57';
NODE_NAME     U6010 CM13
 '@T6G_MB_LIB.T6G(SCH_1):PAGE386_I17@PURE_QUANTA.PT5161LRS(CHIPS)':
 'GND58': CDS_PINID='GND58';
NODE_NAME     U6010 CM22
 '@T6G_MB_LIB.T6G(SCH_1):PAGE386_I17@PURE_QUANTA.PT5161LRS(CHIPS)':
 'GND59': CDS_PINID='GND59';
NODE_NAME     U6010 CM32
 '@T6G_MB_LIB.T6G(SCH_1):PAGE386_I17@PURE_QUANTA.PT5161LRS(CHIPS)':
 'GND60': CDS_PINID='GND60';
NODE_NAME     U6010 CM4
 '@T6G_MB_LIB.T6G(SCH_1):PAGE386_I17@PURE_QUANTA.PT5161LRS(CHIPS)':
 'GND61': CDS_PINID='GND61';
NODE_NAME     U6010 CN2
 '@T6G_MB_LIB.T6G(SCH_1):PAGE386_I17@PURE_QUANTA.PT5161LRS(CHIPS)':
 'GND62': CDS_PINID='GND62';
NODE_NAME     U6010 CN34
 '@T6G_MB_LIB.T6G(SCH_1):PAGE386_I17@PURE_QUANTA.PT5161LRS(CHIPS)':
 'GND63': CDS_PINID='GND63';
NODE_NAME     U6010 CP1
 '@T6G_MB_LIB.T6G(SCH_1):PAGE386_I17@PURE_QUANTA.PT5161LRS(CHIPS)':
 'GND64': CDS_PINID='GND64';
NODE_NAME     U6010 CP35
 '@T6G_MB_LIB.T6G(SCH_1):PAGE386_I17@PURE_QUANTA.PT5161LRS(CHIPS)':
 'GND65': CDS_PINID='GND65';
NODE_NAME     U6010 CW13
 '@T6G_MB_LIB.T6G(SCH_1):PAGE386_I17@PURE_QUANTA.PT5161LRS(CHIPS)':
 'GND66': CDS_PINID='GND66';
NODE_NAME     U6010 CW22
 '@T6G_MB_LIB.T6G(SCH_1):PAGE386_I17@PURE_QUANTA.PT5161LRS(CHIPS)':
 'GND67': CDS_PINID='GND67';
NODE_NAME     U6010 CW32
 '@T6G_MB_LIB.T6G(SCH_1):PAGE386_I17@PURE_QUANTA.PT5161LRS(CHIPS)':
 'GND68': CDS_PINID='GND68';
NODE_NAME     U6010 CW4
 '@T6G_MB_LIB.T6G(SCH_1):PAGE386_I17@PURE_QUANTA.PT5161LRS(CHIPS)':
 'GND69': CDS_PINID='GND69';
NODE_NAME     U6010 CY2
 '@T6G_MB_LIB.T6G(SCH_1):PAGE386_I17@PURE_QUANTA.PT5161LRS(CHIPS)':
 'GND70': CDS_PINID='GND70';
NODE_NAME     U6010 CY34
 '@T6G_MB_LIB.T6G(SCH_1):PAGE386_I17@PURE_QUANTA.PT5161LRS(CHIPS)':
 'GND71': CDS_PINID='GND71';
NODE_NAME     U6010 DA1
 '@T6G_MB_LIB.T6G(SCH_1):PAGE386_I17@PURE_QUANTA.PT5161LRS(CHIPS)':
 'GND72': CDS_PINID='GND72';
NODE_NAME     U6010 DA35
 '@T6G_MB_LIB.T6G(SCH_1):PAGE386_I17@PURE_QUANTA.PT5161LRS(CHIPS)':
 'GND73': CDS_PINID='GND73';
NODE_NAME     U6010 DF13
 '@T6G_MB_LIB.T6G(SCH_1):PAGE386_I17@PURE_QUANTA.PT5161LRS(CHIPS)':
 'GND74': CDS_PINID='GND74';
NODE_NAME     U6010 DF22
 '@T6G_MB_LIB.T6G(SCH_1):PAGE386_I17@PURE_QUANTA.PT5161LRS(CHIPS)':
 'GND75': CDS_PINID='GND75';
NODE_NAME     U6010 DF32
 '@T6G_MB_LIB.T6G(SCH_1):PAGE386_I17@PURE_QUANTA.PT5161LRS(CHIPS)':
 'GND76': CDS_PINID='GND76';
NODE_NAME     U6010 DF4
 '@T6G_MB_LIB.T6G(SCH_1):PAGE386_I17@PURE_QUANTA.PT5161LRS(CHIPS)':
 'GND77': CDS_PINID='GND77';
NODE_NAME     U6010 DG2
 '@T6G_MB_LIB.T6G(SCH_1):PAGE386_I17@PURE_QUANTA.PT5161LRS(CHIPS)':
 'GND78': CDS_PINID='GND78';
NODE_NAME     U6010 DG34
 '@T6G_MB_LIB.T6G(SCH_1):PAGE386_I17@PURE_QUANTA.PT5161LRS(CHIPS)':
 'GND79': CDS_PINID='GND79';
NODE_NAME     U6010 DH1
 '@T6G_MB_LIB.T6G(SCH_1):PAGE386_I17@PURE_QUANTA.PT5161LRS(CHIPS)':
 'GND80': CDS_PINID='GND80';
NODE_NAME     U6010 DH35
 '@T6G_MB_LIB.T6G(SCH_1):PAGE386_I17@PURE_QUANTA.PT5161LRS(CHIPS)':
 'GND81': CDS_PINID='GND81';
NODE_NAME     U6010 DN13
 '@T6G_MB_LIB.T6G(SCH_1):PAGE386_I17@PURE_QUANTA.PT5161LRS(CHIPS)':
 'GND82': CDS_PINID='GND82';
NODE_NAME     U6010 DN22
 '@T6G_MB_LIB.T6G(SCH_1):PAGE386_I17@PURE_QUANTA.PT5161LRS(CHIPS)':
 'GND83': CDS_PINID='GND83';
NODE_NAME     U6010 DN32
 '@T6G_MB_LIB.T6G(SCH_1):PAGE386_I17@PURE_QUANTA.PT5161LRS(CHIPS)':
 'GND84': CDS_PINID='GND84';
NODE_NAME     U6010 DN4
 '@T6G_MB_LIB.T6G(SCH_1):PAGE386_I17@PURE_QUANTA.PT5161LRS(CHIPS)':
 'GND85': CDS_PINID='GND85';
NODE_NAME     U6010 DP2
 '@T6G_MB_LIB.T6G(SCH_1):PAGE386_I17@PURE_QUANTA.PT5161LRS(CHIPS)':
 'GND86': CDS_PINID='GND86';
NODE_NAME     U6010 DP34
 '@T6G_MB_LIB.T6G(SCH_1):PAGE386_I17@PURE_QUANTA.PT5161LRS(CHIPS)':
 'GND87': CDS_PINID='GND87';
NODE_NAME     U6010 DR1
 '@T6G_MB_LIB.T6G(SCH_1):PAGE386_I17@PURE_QUANTA.PT5161LRS(CHIPS)':
 'GND88': CDS_PINID='GND88';
NODE_NAME     U6010 DR35
 '@T6G_MB_LIB.T6G(SCH_1):PAGE386_I17@PURE_QUANTA.PT5161LRS(CHIPS)':
 'GND89': CDS_PINID='GND89';
NODE_NAME     U6010 DY13
 '@T6G_MB_LIB.T6G(SCH_1):PAGE386_I17@PURE_QUANTA.PT5161LRS(CHIPS)':
 'GND90': CDS_PINID='GND90';
NODE_NAME     U6010 DY22
 '@T6G_MB_LIB.T6G(SCH_1):PAGE386_I17@PURE_QUANTA.PT5161LRS(CHIPS)':
 'GND91': CDS_PINID='GND91';
NODE_NAME     U6010 DY32
 '@T6G_MB_LIB.T6G(SCH_1):PAGE386_I17@PURE_QUANTA.PT5161LRS(CHIPS)':
 'GND92': CDS_PINID='GND92';
NODE_NAME     U6010 DY4
 '@T6G_MB_LIB.T6G(SCH_1):PAGE386_I17@PURE_QUANTA.PT5161LRS(CHIPS)':
 'GND93': CDS_PINID='GND93';
NODE_NAME     U6010 E14
 '@T6G_MB_LIB.T6G(SCH_1):PAGE386_I17@PURE_QUANTA.PT5161LRS(CHIPS)':
 'GND94': CDS_PINID='GND94';
NODE_NAME     U6010 E27
 '@T6G_MB_LIB.T6G(SCH_1):PAGE386_I17@PURE_QUANTA.PT5161LRS(CHIPS)':
 'GND95': CDS_PINID='GND95';
NODE_NAME     U6010 E33
 '@T6G_MB_LIB.T6G(SCH_1):PAGE386_I17@PURE_QUANTA.PT5161LRS(CHIPS)':
 'GND96': CDS_PINID='GND96';
NODE_NAME     U6010 EA2
 '@T6G_MB_LIB.T6G(SCH_1):PAGE386_I17@PURE_QUANTA.PT5161LRS(CHIPS)':
 'GND97': CDS_PINID='GND97';
NODE_NAME     U6010 EA34
 '@T6G_MB_LIB.T6G(SCH_1):PAGE386_I17@PURE_QUANTA.PT5161LRS(CHIPS)':
 'GND98': CDS_PINID='GND98';
NODE_NAME     U6010 EB1
 '@T6G_MB_LIB.T6G(SCH_1):PAGE386_I17@PURE_QUANTA.PT5161LRS(CHIPS)':
 'GND99': CDS_PINID='GND99';
NODE_NAME     U6010 EB35
 '@T6G_MB_LIB.T6G(SCH_1):PAGE386_I17@PURE_QUANTA.PT5161LRS(CHIPS)':
 'GND100': CDS_PINID='GND100';
NODE_NAME     U6010 EG13
 '@T6G_MB_LIB.T6G(SCH_1):PAGE386_I17@PURE_QUANTA.PT5161LRS(CHIPS)':
 'GND101': CDS_PINID='GND101';
NODE_NAME     U6010 EG22
 '@T6G_MB_LIB.T6G(SCH_1):PAGE386_I17@PURE_QUANTA.PT5161LRS(CHIPS)':
 'GND102': CDS_PINID='GND102';
NODE_NAME     U6010 EG32
 '@T6G_MB_LIB.T6G(SCH_1):PAGE386_I17@PURE_QUANTA.PT5161LRS(CHIPS)':
 'GND103': CDS_PINID='GND103';
NODE_NAME     U6010 EG4
 '@T6G_MB_LIB.T6G(SCH_1):PAGE386_I17@PURE_QUANTA.PT5161LRS(CHIPS)':
 'GND104': CDS_PINID='GND104';
NODE_NAME     U6010 EH2
 '@T6G_MB_LIB.T6G(SCH_1):PAGE386_I17@PURE_QUANTA.PT5161LRS(CHIPS)':
 'GND105': CDS_PINID='GND105';
NODE_NAME     U6010 EH34
 '@T6G_MB_LIB.T6G(SCH_1):PAGE386_I17@PURE_QUANTA.PT5161LRS(CHIPS)':
 'GND106': CDS_PINID='GND106';
NODE_NAME     U6010 EJ1
 '@T6G_MB_LIB.T6G(SCH_1):PAGE386_I17@PURE_QUANTA.PT5161LRS(CHIPS)':
 'GND107': CDS_PINID='GND107';
NODE_NAME     U6010 EJ35
 '@T6G_MB_LIB.T6G(SCH_1):PAGE386_I17@PURE_QUANTA.PT5161LRS(CHIPS)':
 'GND108': CDS_PINID='GND108';
NODE_NAME     U6010 EP13
 '@T6G_MB_LIB.T6G(SCH_1):PAGE386_I17@PURE_QUANTA.PT5161LRS(CHIPS)':
 'GND109': CDS_PINID='GND109';
NODE_NAME     U6010 EP22
 '@T6G_MB_LIB.T6G(SCH_1):PAGE386_I17@PURE_QUANTA.PT5161LRS(CHIPS)':
 'GND110': CDS_PINID='GND110';
NODE_NAME     U6010 EP32
 '@T6G_MB_LIB.T6G(SCH_1):PAGE386_I17@PURE_QUANTA.PT5161LRS(CHIPS)':
 'GND111': CDS_PINID='GND111';
NODE_NAME     U6010 EP4
 '@T6G_MB_LIB.T6G(SCH_1):PAGE386_I17@PURE_QUANTA.PT5161LRS(CHIPS)':
 'GND112': CDS_PINID='GND112';
NODE_NAME     U6010 ER2
 '@T6G_MB_LIB.T6G(SCH_1):PAGE386_I17@PURE_QUANTA.PT5161LRS(CHIPS)':
 'GND113': CDS_PINID='GND113';
NODE_NAME     U6010 ER34
 '@T6G_MB_LIB.T6G(SCH_1):PAGE386_I17@PURE_QUANTA.PT5161LRS(CHIPS)':
 'GND114': CDS_PINID='GND114';
NODE_NAME     U6010 ET1
 '@T6G_MB_LIB.T6G(SCH_1):PAGE386_I17@PURE_QUANTA.PT5161LRS(CHIPS)':
 'GND115': CDS_PINID='GND115';
NODE_NAME     U6010 ET35
 '@T6G_MB_LIB.T6G(SCH_1):PAGE386_I17@PURE_QUANTA.PT5161LRS(CHIPS)':
 'GND116': CDS_PINID='GND116';
NODE_NAME     U6010 FA15
 '@T6G_MB_LIB.T6G(SCH_1):PAGE386_I17@PURE_QUANTA.PT5161LRS(CHIPS)':
 'GND117': CDS_PINID='GND117';
NODE_NAME     U6010 FA32
 '@T6G_MB_LIB.T6G(SCH_1):PAGE386_I17@PURE_QUANTA.PT5161LRS(CHIPS)':
 'GND118': CDS_PINID='GND118';
NODE_NAME     U6010 FB2
 '@T6G_MB_LIB.T6G(SCH_1):PAGE386_I17@PURE_QUANTA.PT5161LRS(CHIPS)':
 'GND119': CDS_PINID='GND119';
NODE_NAME     U6010 FB34
 '@T6G_MB_LIB.T6G(SCH_1):PAGE386_I17@PURE_QUANTA.PT5161LRS(CHIPS)':
 'GND120': CDS_PINID='GND120';
NODE_NAME     U6010 FC19
 '@T6G_MB_LIB.T6G(SCH_1):PAGE386_I17@PURE_QUANTA.PT5161LRS(CHIPS)':
 'GND121': CDS_PINID='GND121';
NODE_NAME     U6010 FC23
 '@T6G_MB_LIB.T6G(SCH_1):PAGE386_I17@PURE_QUANTA.PT5161LRS(CHIPS)':
 'GND122': CDS_PINID='GND122';
NODE_NAME     U6010 FC25
 '@T6G_MB_LIB.T6G(SCH_1):PAGE386_I17@PURE_QUANTA.PT5161LRS(CHIPS)':
 'GND123': CDS_PINID='GND123';
NODE_NAME     U6010 FC28
 '@T6G_MB_LIB.T6G(SCH_1):PAGE386_I17@PURE_QUANTA.PT5161LRS(CHIPS)':
 'GND124': CDS_PINID='GND124';
NODE_NAME     U6010 FC3
 '@T6G_MB_LIB.T6G(SCH_1):PAGE386_I17@PURE_QUANTA.PT5161LRS(CHIPS)':
 'GND125': CDS_PINID='GND125';
NODE_NAME     U6010 FC6
 '@T6G_MB_LIB.T6G(SCH_1):PAGE386_I17@PURE_QUANTA.PT5161LRS(CHIPS)':
 'GND126': CDS_PINID='GND126';
NODE_NAME     U6010 FC9
 '@T6G_MB_LIB.T6G(SCH_1):PAGE386_I17@PURE_QUANTA.PT5161LRS(CHIPS)':
 'GND127': CDS_PINID='GND127';
NODE_NAME     U6010 FD1
 '@T6G_MB_LIB.T6G(SCH_1):PAGE386_I17@PURE_QUANTA.PT5161LRS(CHIPS)':
 'GND128': CDS_PINID='GND128';
NODE_NAME     U6010 FD35
 '@T6G_MB_LIB.T6G(SCH_1):PAGE386_I17@PURE_QUANTA.PT5161LRS(CHIPS)':
 'GND129': CDS_PINID='GND129';
NODE_NAME     U6010 FF14
 '@T6G_MB_LIB.T6G(SCH_1):PAGE386_I17@PURE_QUANTA.PT5161LRS(CHIPS)':
 'GND130': CDS_PINID='GND130';
NODE_NAME     U6010 FF21
 '@T6G_MB_LIB.T6G(SCH_1):PAGE386_I17@PURE_QUANTA.PT5161LRS(CHIPS)':
 'GND131': CDS_PINID='GND131';
NODE_NAME     U6010 FJ12
 '@T6G_MB_LIB.T6G(SCH_1):PAGE386_I17@PURE_QUANTA.PT5161LRS(CHIPS)':
 'GND132': CDS_PINID='GND132';
NODE_NAME     U6010 FJ19
 '@T6G_MB_LIB.T6G(SCH_1):PAGE386_I17@PURE_QUANTA.PT5161LRS(CHIPS)':
 'GND133': CDS_PINID='GND133';
NODE_NAME     U6010 H12
 '@T6G_MB_LIB.T6G(SCH_1):PAGE386_I17@PURE_QUANTA.PT5161LRS(CHIPS)':
 'GND134': CDS_PINID='GND134';
NODE_NAME     U6010 H16
 '@T6G_MB_LIB.T6G(SCH_1):PAGE386_I17@PURE_QUANTA.PT5161LRS(CHIPS)':
 'GND135': CDS_PINID='GND135';
NODE_NAME     U6010 H19
 '@T6G_MB_LIB.T6G(SCH_1):PAGE386_I17@PURE_QUANTA.PT5161LRS(CHIPS)':
 'GND136': CDS_PINID='GND136';
NODE_NAME     U6010 H31
 '@T6G_MB_LIB.T6G(SCH_1):PAGE386_I17@PURE_QUANTA.PT5161LRS(CHIPS)':
 'GND137': CDS_PINID='GND137';
NODE_NAME     U6010 J22
 '@T6G_MB_LIB.T6G(SCH_1):PAGE386_I17@PURE_QUANTA.PT5161LRS(CHIPS)':
 'GND138': CDS_PINID='GND138';
NODE_NAME     U6010 J4
 '@T6G_MB_LIB.T6G(SCH_1):PAGE386_I17@PURE_QUANTA.PT5161LRS(CHIPS)':
 'GND139': CDS_PINID='GND139';
NODE_NAME     U6010 K2
 '@T6G_MB_LIB.T6G(SCH_1):PAGE386_I17@PURE_QUANTA.PT5161LRS(CHIPS)':
 'GND140': CDS_PINID='GND140';
NODE_NAME     U6010 K34
 '@T6G_MB_LIB.T6G(SCH_1):PAGE386_I17@PURE_QUANTA.PT5161LRS(CHIPS)':
 'GND141': CDS_PINID='GND141';
NODE_NAME     U6010 L1
 '@T6G_MB_LIB.T6G(SCH_1):PAGE386_I17@PURE_QUANTA.PT5161LRS(CHIPS)':
 'GND142': CDS_PINID='GND142';
NODE_NAME     U6010 L35
 '@T6G_MB_LIB.T6G(SCH_1):PAGE386_I17@PURE_QUANTA.PT5161LRS(CHIPS)':
 'GND143': CDS_PINID='GND143';
NODE_NAME     U6010 T13
 '@T6G_MB_LIB.T6G(SCH_1):PAGE386_I17@PURE_QUANTA.PT5161LRS(CHIPS)':
 'GND144': CDS_PINID='GND144';
NODE_NAME     U6010 T22
 '@T6G_MB_LIB.T6G(SCH_1):PAGE386_I17@PURE_QUANTA.PT5161LRS(CHIPS)':
 'GND145': CDS_PINID='GND145';
NODE_NAME     U6010 T32
 '@T6G_MB_LIB.T6G(SCH_1):PAGE386_I17@PURE_QUANTA.PT5161LRS(CHIPS)':
 'GND146': CDS_PINID='GND146';
NODE_NAME     U6010 T4
 '@T6G_MB_LIB.T6G(SCH_1):PAGE386_I17@PURE_QUANTA.PT5161LRS(CHIPS)':
 'GND147': CDS_PINID='GND147';
NODE_NAME     U6010 U2
 '@T6G_MB_LIB.T6G(SCH_1):PAGE386_I17@PURE_QUANTA.PT5161LRS(CHIPS)':
 'GND148': CDS_PINID='GND148';
NODE_NAME     U6010 U34
 '@T6G_MB_LIB.T6G(SCH_1):PAGE386_I17@PURE_QUANTA.PT5161LRS(CHIPS)':
 'GND149': CDS_PINID='GND149';
NODE_NAME     U6010 V1
 '@T6G_MB_LIB.T6G(SCH_1):PAGE386_I17@PURE_QUANTA.PT5161LRS(CHIPS)':
 'GND150': CDS_PINID='GND150';
NODE_NAME     U6010 V35
 '@T6G_MB_LIB.T6G(SCH_1):PAGE386_I17@PURE_QUANTA.PT5161LRS(CHIPS)':
 'GND151': CDS_PINID='GND151';
NODE_NAME     C7510 2
 '@T6G_MB_LIB.T6G(SCH_1):PAGE387_I21@PURE_QUANTA.Q_CAP(CHIPS)':
 'B': CDS_PINID='B';
NODE_NAME     R6822 2
 '@T6G_MB_LIB.T6G(SCH_1):PAGE387_I24@PURE_QUANTA.Q_RES(CHIPS)':
 'B': CDS_PINID='B';
NODE_NAME     C513 2
 '@T6G_MB_LIB.T6G(SCH_1):PAGE388_I8@PURE_QUANTA.Q_CAP(CHIPS)':
 'B': CDS_PINID='B';
NODE_NAME     C516 2
 '@T6G_MB_LIB.T6G(SCH_1):PAGE388_I9@PURE_QUANTA.Q_CAP(CHIPS)':
 'B': CDS_PINID='B';
NODE_NAME     C503 2
 '@T6G_MB_LIB.T6G(SCH_1):PAGE388_I13@PURE_QUANTA.Q_CAP(CHIPS)':
 'B': CDS_PINID='B';
NODE_NAME     C505 2
 '@T6G_MB_LIB.T6G(SCH_1):PAGE388_I14@PURE_QUANTA.Q_CAP(CHIPS)':
 'B': CDS_PINID='B';
NODE_NAME     C502 2
 '@T6G_MB_LIB.T6G(SCH_1):PAGE388_I16@PURE_QUANTA.Q_CAP(CHIPS)':
 'B': CDS_PINID='B';
NODE_NAME     C507 2
 '@T6G_MB_LIB.T6G(SCH_1):PAGE388_I17@PURE_QUANTA.Q_CAP(CHIPS)':
 'B': CDS_PINID='B';
NODE_NAME     C510 2
 '@T6G_MB_LIB.T6G(SCH_1):PAGE388_I18@PURE_QUANTA.Q_CAP(CHIPS)':
 'B': CDS_PINID='B';
NODE_NAME     C512 2
 '@T6G_MB_LIB.T6G(SCH_1):PAGE388_I19@PURE_QUANTA.Q_CAP(CHIPS)':
 'B': CDS_PINID='B';
NODE_NAME     C514 2
 '@T6G_MB_LIB.T6G(SCH_1):PAGE388_I22@PURE_QUANTA.Q_CAP(CHIPS)':
 'B': CDS_PINID='B';
NODE_NAME     C515 2
 '@T6G_MB_LIB.T6G(SCH_1):PAGE388_I23@PURE_QUANTA.Q_CAP(CHIPS)':
 'B': CDS_PINID='B';
NODE_NAME     C504 2
 '@T6G_MB_LIB.T6G(SCH_1):PAGE388_I24@PURE_QUANTA.Q_CAP(CHIPS)':
 'B': CDS_PINID='B';
NODE_NAME     C506 2
 '@T6G_MB_LIB.T6G(SCH_1):PAGE388_I25@PURE_QUANTA.Q_CAP(CHIPS)':
 'B': CDS_PINID='B';
NODE_NAME     C511 2
 '@T6G_MB_LIB.T6G(SCH_1):PAGE388_I26@PURE_QUANTA.Q_CAP(CHIPS)':
 'B': CDS_PINID='B';
NODE_NAME     C517 2
 '@T6G_MB_LIB.T6G(SCH_1):PAGE388_I27@PURE_QUANTA.Q_CAP(CHIPS)':
 'B': CDS_PINID='B';
NODE_NAME     C519 2
 '@T6G_MB_LIB.T6G(SCH_1):PAGE388_I28@PURE_QUANTA.Q_CAP(CHIPS)':
 'B': CDS_PINID='B';
NODE_NAME     C520 2
 '@T6G_MB_LIB.T6G(SCH_1):PAGE388_I29@PURE_QUANTA.Q_CAP(CHIPS)':
 'B': CDS_PINID='B';
NODE_NAME     C538 2
 '@T6G_MB_LIB.T6G(SCH_1):PAGE388_I32@PURE_QUANTA.Q_CAP(CHIPS)':
 'B': CDS_PINID='B';
NODE_NAME     C544 2
 '@T6G_MB_LIB.T6G(SCH_1):PAGE388_I36@PURE_QUANTA.Q_CAP(CHIPS)':
 'B': CDS_PINID='B';
NODE_NAME     C576 2
 '@T6G_MB_LIB.T6G(SCH_1):PAGE388_I38@PURE_QUANTA.Q_CAP(CHIPS)':
 'B': CDS_PINID='B';
NODE_NAME     C580 2
 '@T6G_MB_LIB.T6G(SCH_1):PAGE388_I39@PURE_QUANTA.Q_CAP(CHIPS)':
 'B': CDS_PINID='B';
NODE_NAME     C555 2
 '@T6G_MB_LIB.T6G(SCH_1):PAGE388_I40@PURE_QUANTA.Q_CAP(CHIPS)':
 'B': CDS_PINID='B';
NODE_NAME     C561 2
 '@T6G_MB_LIB.T6G(SCH_1):PAGE388_I41@PURE_QUANTA.Q_CAP(CHIPS)':
 'B': CDS_PINID='B';
NODE_NAME     C539 2
 '@T6G_MB_LIB.T6G(SCH_1):PAGE388_I42@PURE_QUANTA.Q_CAP(CHIPS)':
 'B': CDS_PINID='B';
NODE_NAME     C562 2
 '@T6G_MB_LIB.T6G(SCH_1):PAGE388_I43@PURE_QUANTA.Q_CAP(CHIPS)':
 'B': CDS_PINID='B';
NODE_NAME     C579 2
 '@T6G_MB_LIB.T6G(SCH_1):PAGE388_I44@PURE_QUANTA.Q_CAP(CHIPS)':
 'B': CDS_PINID='B';
NODE_NAME     C554 2
 '@T6G_MB_LIB.T6G(SCH_1):PAGE388_I45@PURE_QUANTA.Q_CAP(CHIPS)':
 'B': CDS_PINID='B';
NODE_NAME     C571 2
 '@T6G_MB_LIB.T6G(SCH_1):PAGE388_I46@PURE_QUANTA.Q_CAP(CHIPS)':
 'B': CDS_PINID='B';
NODE_NAME     C541 2
 '@T6G_MB_LIB.T6G(SCH_1):PAGE388_I48@PURE_QUANTA.Q_CAP(CHIPS)':
 'B': CDS_PINID='B';
NODE_NAME     C582 2
 '@T6G_MB_LIB.T6G(SCH_1):PAGE388_I49@PURE_QUANTA.Q_CAP(CHIPS)':
 'B': CDS_PINID='B';
NODE_NAME     C523 2
 '@T6G_MB_LIB.T6G(SCH_1):PAGE388_I50@PURE_QUANTA.Q_CAP(CHIPS)':
 'B': CDS_PINID='B';
NODE_NAME     C585 2
 '@T6G_MB_LIB.T6G(SCH_1):PAGE388_I51@PURE_QUANTA.Q_CAP(CHIPS)':
 'B': CDS_PINID='B';
NODE_NAME     C570 2
 '@T6G_MB_LIB.T6G(SCH_1):PAGE388_I52@PURE_QUANTA.Q_CAP(CHIPS)':
 'B': CDS_PINID='B';
NODE_NAME     C573 2
 '@T6G_MB_LIB.T6G(SCH_1):PAGE388_I53@PURE_QUANTA.Q_CAP(CHIPS)':
 'B': CDS_PINID='B';
NODE_NAME     C557 2
 '@T6G_MB_LIB.T6G(SCH_1):PAGE388_I54@PURE_QUANTA.Q_CAP(CHIPS)':
 'B': CDS_PINID='B';
NODE_NAME     C572 2
 '@T6G_MB_LIB.T6G(SCH_1):PAGE388_I55@PURE_QUANTA.Q_CAP(CHIPS)':
 'B': CDS_PINID='B';
NODE_NAME     C577 2
 '@T6G_MB_LIB.T6G(SCH_1):PAGE388_I56@PURE_QUANTA.Q_CAP(CHIPS)':
 'B': CDS_PINID='B';
NODE_NAME     C581 2
 '@T6G_MB_LIB.T6G(SCH_1):PAGE388_I57@PURE_QUANTA.Q_CAP(CHIPS)':
 'B': CDS_PINID='B';
NODE_NAME     C525 2
 '@T6G_MB_LIB.T6G(SCH_1):PAGE388_I58@PURE_QUANTA.Q_CAP(CHIPS)':
 'B': CDS_PINID='B';
NODE_NAME     C529 2
 '@T6G_MB_LIB.T6G(SCH_1):PAGE388_I59@PURE_QUANTA.Q_CAP(CHIPS)':
 'B': CDS_PINID='B';
NODE_NAME     C558 2
 '@T6G_MB_LIB.T6G(SCH_1):PAGE388_I60@PURE_QUANTA.Q_CAP(CHIPS)':
 'B': CDS_PINID='B';
NODE_NAME     C543 2
 '@T6G_MB_LIB.T6G(SCH_1):PAGE388_I62@PURE_QUANTA.Q_CAP(CHIPS)':
 'B': CDS_PINID='B';
NODE_NAME     C521 2
 '@T6G_MB_LIB.T6G(SCH_1):PAGE388_I65@PURE_QUANTA.Q_CAP(CHIPS)':
 'B': CDS_PINID='B';
NODE_NAME     C526 2
 '@T6G_MB_LIB.T6G(SCH_1):PAGE388_I66@PURE_QUANTA.Q_CAP(CHIPS)':
 'B': CDS_PINID='B';
NODE_NAME     C550 2
 '@T6G_MB_LIB.T6G(SCH_1):PAGE388_I67@PURE_QUANTA.Q_CAP(CHIPS)':
 'B': CDS_PINID='B';
NODE_NAME     C556 2
 '@T6G_MB_LIB.T6G(SCH_1):PAGE388_I69@PURE_QUANTA.Q_CAP(CHIPS)':
 'B': CDS_PINID='B';
NODE_NAME     C560 2
 '@T6G_MB_LIB.T6G(SCH_1):PAGE388_I70@PURE_QUANTA.Q_CAP(CHIPS)':
 'B': CDS_PINID='B';
NODE_NAME     C564 2
 '@T6G_MB_LIB.T6G(SCH_1):PAGE388_I71@PURE_QUANTA.Q_CAP(CHIPS)':
 'B': CDS_PINID='B';
NODE_NAME     C559 2
 '@T6G_MB_LIB.T6G(SCH_1):PAGE388_I72@PURE_QUANTA.Q_CAP(CHIPS)':
 'B': CDS_PINID='B';
NODE_NAME     C574 2
 '@T6G_MB_LIB.T6G(SCH_1):PAGE388_I73@PURE_QUANTA.Q_CAP(CHIPS)':
 'B': CDS_PINID='B';
NODE_NAME     C563 2
 '@T6G_MB_LIB.T6G(SCH_1):PAGE388_I74@PURE_QUANTA.Q_CAP(CHIPS)':
 'B': CDS_PINID='B';
NODE_NAME     C586 2
 '@T6G_MB_LIB.T6G(SCH_1):PAGE388_I75@PURE_QUANTA.Q_CAP(CHIPS)':
 'B': CDS_PINID='B';
NODE_NAME     C565 2
 '@T6G_MB_LIB.T6G(SCH_1):PAGE388_I76@PURE_QUANTA.Q_CAP(CHIPS)':
 'B': CDS_PINID='B';
NODE_NAME     C575 2
 '@T6G_MB_LIB.T6G(SCH_1):PAGE388_I77@PURE_QUANTA.Q_CAP(CHIPS)':
 'B': CDS_PINID='B';
NODE_NAME     C568 2
 '@T6G_MB_LIB.T6G(SCH_1):PAGE388_I78@PURE_QUANTA.Q_CAP(CHIPS)':
 'B': CDS_PINID='B';
NODE_NAME     C569 2
 '@T6G_MB_LIB.T6G(SCH_1):PAGE388_I79@PURE_QUANTA.Q_CAP(CHIPS)':
 'B': CDS_PINID='B';
NODE_NAME     C528 2
 '@T6G_MB_LIB.T6G(SCH_1):PAGE388_I80@PURE_QUANTA.Q_CAP(CHIPS)':
 'B': CDS_PINID='B';
NODE_NAME     C522 2
 '@T6G_MB_LIB.T6G(SCH_1):PAGE388_I81@PURE_QUANTA.Q_CAP(CHIPS)':
 'B': CDS_PINID='B';
NODE_NAME     C584 2
 '@T6G_MB_LIB.T6G(SCH_1):PAGE388_I82@PURE_QUANTA.Q_CAP(CHIPS)':
 'B': CDS_PINID='B';
NODE_NAME     C567 2
 '@T6G_MB_LIB.T6G(SCH_1):PAGE388_I83@PURE_QUANTA.Q_CAP(CHIPS)':
 'B': CDS_PINID='B';
NODE_NAME     C524 2
 '@T6G_MB_LIB.T6G(SCH_1):PAGE388_I84@PURE_QUANTA.Q_CAP(CHIPS)':
 'B': CDS_PINID='B';
NODE_NAME     C578 2
 '@T6G_MB_LIB.T6G(SCH_1):PAGE388_I85@PURE_QUANTA.Q_CAP(CHIPS)':
 'B': CDS_PINID='B';
NODE_NAME     C540 2
 '@T6G_MB_LIB.T6G(SCH_1):PAGE388_I87@PURE_QUANTA.Q_CAP(CHIPS)':
 'B': CDS_PINID='B';
NODE_NAME     R1028 2
 '@T6G_MB_LIB.T6G(SCH_1):PAGE408_I7@PURE_QUANTA.Q_RES(CHIPS)':
 'B': CDS_PINID='B';
NODE_NAME     R1029 2
 '@T6G_MB_LIB.T6G(SCH_1):PAGE408_I8@PURE_QUANTA.Q_RES(CHIPS)':
 'B': CDS_PINID='B';
NODE_NAME     R1031 2
 '@T6G_MB_LIB.T6G(SCH_1):PAGE408_I9@PURE_QUANTA.Q_RES(CHIPS)':
 'B': CDS_PINID='B';
NODE_NAME     R1033 2
 '@T6G_MB_LIB.T6G(SCH_1):PAGE408_I36@PURE_QUANTA.Q_RES(CHIPS)':
 'B': CDS_PINID='B';
NODE_NAME     R1035 2
 '@T6G_MB_LIB.T6G(SCH_1):PAGE408_I37@PURE_QUANTA.Q_RES(CHIPS)':
 'B': CDS_PINID='B';
NODE_NAME     R1037 2
 '@T6G_MB_LIB.T6G(SCH_1):PAGE408_I39@PURE_QUANTA.Q_RES(CHIPS)':
 'B': CDS_PINID='B';
NODE_NAME     R1006 2
 '@T6G_MB_LIB.T6G(SCH_1):PAGE408_I50@PURE_QUANTA.Q_RES(CHIPS)':
 'B': CDS_PINID='B';
NODE_NAME     R1014 2
 '@T6G_MB_LIB.T6G(SCH_1):PAGE408_I64@PURE_QUANTA.Q_RES(CHIPS)':
 'B': CDS_PINID='B';
NODE_NAME     R1016 2
 '@T6G_MB_LIB.T6G(SCH_1):PAGE408_I65@PURE_QUANTA.Q_RES(CHIPS)':
 'B': CDS_PINID='B';
NODE_NAME     R1018 2
 '@T6G_MB_LIB.T6G(SCH_1):PAGE408_I68@PURE_QUANTA.Q_RES(CHIPS)':
 'B': CDS_PINID='B';
NODE_NAME     R1019 2
 '@T6G_MB_LIB.T6G(SCH_1):PAGE408_I73@PURE_QUANTA.Q_RES(CHIPS)':
 'B': CDS_PINID='B';
NODE_NAME     R1020 2
 '@T6G_MB_LIB.T6G(SCH_1):PAGE408_I74@PURE_QUANTA.Q_RES(CHIPS)':
 'B': CDS_PINID='B';
NODE_NAME     U6011 E30
 '@T6G_MB_LIB.T6G(SCH_1):PAGE408_I83@PURE_QUANTA.PT5161LRS(CHIPS)':
 'T_SENSE': CDS_PINID='T_SENSE';
NODE_NAME     R1042 2
 '@T6G_MB_LIB.T6G(SCH_1):PAGE409_I13@PURE_QUANTA.Q_RES(CHIPS)':
 'B': CDS_PINID='B';
NODE_NAME     R1043 2
 '@T6G_MB_LIB.T6G(SCH_1):PAGE409_I15@PURE_QUANTA.Q_RES(CHIPS)':
 'B': CDS_PINID='B';
NODE_NAME     U6011 AC13
 '@T6G_MB_LIB.T6G(SCH_1):PAGE409_I17@PURE_QUANTA.PT5161LRS(CHIPS)':
 'GND1': CDS_PINID='GND1';
NODE_NAME     U6011 AC22
 '@T6G_MB_LIB.T6G(SCH_1):PAGE409_I17@PURE_QUANTA.PT5161LRS(CHIPS)':
 'GND2': CDS_PINID='GND2';
NODE_NAME     U6011 AC32
 '@T6G_MB_LIB.T6G(SCH_1):PAGE409_I17@PURE_QUANTA.PT5161LRS(CHIPS)':
 'GND3': CDS_PINID='GND3';
NODE_NAME     U6011 AC4
 '@T6G_MB_LIB.T6G(SCH_1):PAGE409_I17@PURE_QUANTA.PT5161LRS(CHIPS)':
 'GND4': CDS_PINID='GND4';
NODE_NAME     U6011 AD2
 '@T6G_MB_LIB.T6G(SCH_1):PAGE409_I17@PURE_QUANTA.PT5161LRS(CHIPS)':
 'GND5': CDS_PINID='GND5';
NODE_NAME     U6011 AD34
 '@T6G_MB_LIB.T6G(SCH_1):PAGE409_I17@PURE_QUANTA.PT5161LRS(CHIPS)':
 'GND6': CDS_PINID='GND6';
NODE_NAME     U6011 AE1
 '@T6G_MB_LIB.T6G(SCH_1):PAGE409_I17@PURE_QUANTA.PT5161LRS(CHIPS)':
 'GND7': CDS_PINID='GND7';
NODE_NAME     U6011 AE35
 '@T6G_MB_LIB.T6G(SCH_1):PAGE409_I17@PURE_QUANTA.PT5161LRS(CHIPS)':
 'GND8': CDS_PINID='GND8';
NODE_NAME     U6011 AK13
 '@T6G_MB_LIB.T6G(SCH_1):PAGE409_I17@PURE_QUANTA.PT5161LRS(CHIPS)':
 'GND9': CDS_PINID='GND9';
NODE_NAME     U6011 AK22
 '@T6G_MB_LIB.T6G(SCH_1):PAGE409_I17@PURE_QUANTA.PT5161LRS(CHIPS)':
 'GND10': CDS_PINID='GND10';
NODE_NAME     U6011 AK32
 '@T6G_MB_LIB.T6G(SCH_1):PAGE409_I17@PURE_QUANTA.PT5161LRS(CHIPS)':
 'GND11': CDS_PINID='GND11';
NODE_NAME     U6011 AK4
 '@T6G_MB_LIB.T6G(SCH_1):PAGE409_I17@PURE_QUANTA.PT5161LRS(CHIPS)':
 'GND12': CDS_PINID='GND12';
NODE_NAME     U6011 AL2
 '@T6G_MB_LIB.T6G(SCH_1):PAGE409_I17@PURE_QUANTA.PT5161LRS(CHIPS)':
 'GND13': CDS_PINID='GND13';
NODE_NAME     U6011 AL34
 '@T6G_MB_LIB.T6G(SCH_1):PAGE409_I17@PURE_QUANTA.PT5161LRS(CHIPS)':
 'GND14': CDS_PINID='GND14';
NODE_NAME     U6011 AM1
 '@T6G_MB_LIB.T6G(SCH_1):PAGE409_I17@PURE_QUANTA.PT5161LRS(CHIPS)':
 'GND15': CDS_PINID='GND15';
NODE_NAME     U6011 AM35
 '@T6G_MB_LIB.T6G(SCH_1):PAGE409_I17@PURE_QUANTA.PT5161LRS(CHIPS)':
 'GND16': CDS_PINID='GND16';
NODE_NAME     U6011 AU13
 '@T6G_MB_LIB.T6G(SCH_1):PAGE409_I17@PURE_QUANTA.PT5161LRS(CHIPS)':
 'GND17': CDS_PINID='GND17';
NODE_NAME     U6011 AU22
 '@T6G_MB_LIB.T6G(SCH_1):PAGE409_I17@PURE_QUANTA.PT5161LRS(CHIPS)':
 'GND18': CDS_PINID='GND18';
NODE_NAME     U6011 AU32
 '@T6G_MB_LIB.T6G(SCH_1):PAGE409_I17@PURE_QUANTA.PT5161LRS(CHIPS)':
 'GND19': CDS_PINID='GND19';
NODE_NAME     U6011 AU4
 '@T6G_MB_LIB.T6G(SCH_1):PAGE409_I17@PURE_QUANTA.PT5161LRS(CHIPS)':
 'GND20': CDS_PINID='GND20';
NODE_NAME     U6011 AV2
 '@T6G_MB_LIB.T6G(SCH_1):PAGE409_I17@PURE_QUANTA.PT5161LRS(CHIPS)':
 'GND21': CDS_PINID='GND21';
NODE_NAME     U6011 AV34
 '@T6G_MB_LIB.T6G(SCH_1):PAGE409_I17@PURE_QUANTA.PT5161LRS(CHIPS)':
 'GND22': CDS_PINID='GND22';
NODE_NAME     U6011 AW1
 '@T6G_MB_LIB.T6G(SCH_1):PAGE409_I17@PURE_QUANTA.PT5161LRS(CHIPS)':
 'GND23': CDS_PINID='GND23';
NODE_NAME     U6011 AW35
 '@T6G_MB_LIB.T6G(SCH_1):PAGE409_I17@PURE_QUANTA.PT5161LRS(CHIPS)':
 'GND24': CDS_PINID='GND24';
NODE_NAME     U6011 B19
 '@T6G_MB_LIB.T6G(SCH_1):PAGE409_I17@PURE_QUANTA.PT5161LRS(CHIPS)':
 'GND25': CDS_PINID='GND25';
NODE_NAME     U6011 BD13
 '@T6G_MB_LIB.T6G(SCH_1):PAGE409_I17@PURE_QUANTA.PT5161LRS(CHIPS)':
 'GND26': CDS_PINID='GND26';
NODE_NAME     U6011 BD22
 '@T6G_MB_LIB.T6G(SCH_1):PAGE409_I17@PURE_QUANTA.PT5161LRS(CHIPS)':
 'GND27': CDS_PINID='GND27';
NODE_NAME     U6011 BD32
 '@T6G_MB_LIB.T6G(SCH_1):PAGE409_I17@PURE_QUANTA.PT5161LRS(CHIPS)':
 'GND28': CDS_PINID='GND28';
NODE_NAME     U6011 BD4
 '@T6G_MB_LIB.T6G(SCH_1):PAGE409_I17@PURE_QUANTA.PT5161LRS(CHIPS)':
 'GND29': CDS_PINID='GND29';
NODE_NAME     U6011 BE2
 '@T6G_MB_LIB.T6G(SCH_1):PAGE409_I17@PURE_QUANTA.PT5161LRS(CHIPS)':
 'GND30': CDS_PINID='GND30';
NODE_NAME     U6011 BE34
 '@T6G_MB_LIB.T6G(SCH_1):PAGE409_I17@PURE_QUANTA.PT5161LRS(CHIPS)':
 'GND31': CDS_PINID='GND31';
NODE_NAME     U6011 BF1
 '@T6G_MB_LIB.T6G(SCH_1):PAGE409_I17@PURE_QUANTA.PT5161LRS(CHIPS)':
 'GND32': CDS_PINID='GND32';
NODE_NAME     U6011 BF35
 '@T6G_MB_LIB.T6G(SCH_1):PAGE409_I17@PURE_QUANTA.PT5161LRS(CHIPS)':
 'GND33': CDS_PINID='GND33';
NODE_NAME     U6011 BL13
 '@T6G_MB_LIB.T6G(SCH_1):PAGE409_I17@PURE_QUANTA.PT5161LRS(CHIPS)':
 'GND34': CDS_PINID='GND34';
NODE_NAME     U6011 BL22
 '@T6G_MB_LIB.T6G(SCH_1):PAGE409_I17@PURE_QUANTA.PT5161LRS(CHIPS)':
 'GND35': CDS_PINID='GND35';
NODE_NAME     U6011 BL32
 '@T6G_MB_LIB.T6G(SCH_1):PAGE409_I17@PURE_QUANTA.PT5161LRS(CHIPS)':
 'GND36': CDS_PINID='GND36';
NODE_NAME     U6011 BL4
 '@T6G_MB_LIB.T6G(SCH_1):PAGE409_I17@PURE_QUANTA.PT5161LRS(CHIPS)':
 'GND37': CDS_PINID='GND37';
NODE_NAME     U6011 BM2
 '@T6G_MB_LIB.T6G(SCH_1):PAGE409_I17@PURE_QUANTA.PT5161LRS(CHIPS)':
 'GND38': CDS_PINID='GND38';
NODE_NAME     U6011 BM34
 '@T6G_MB_LIB.T6G(SCH_1):PAGE409_I17@PURE_QUANTA.PT5161LRS(CHIPS)':
 'GND39': CDS_PINID='GND39';
NODE_NAME     U6011 BN1
 '@T6G_MB_LIB.T6G(SCH_1):PAGE409_I17@PURE_QUANTA.PT5161LRS(CHIPS)':
 'GND40': CDS_PINID='GND40';
NODE_NAME     U6011 BN35
 '@T6G_MB_LIB.T6G(SCH_1):PAGE409_I17@PURE_QUANTA.PT5161LRS(CHIPS)':
 'GND41': CDS_PINID='GND41';
NODE_NAME     U6011 BV13
 '@T6G_MB_LIB.T6G(SCH_1):PAGE409_I17@PURE_QUANTA.PT5161LRS(CHIPS)':
 'GND42': CDS_PINID='GND42';
NODE_NAME     U6011 BV22
 '@T6G_MB_LIB.T6G(SCH_1):PAGE409_I17@PURE_QUANTA.PT5161LRS(CHIPS)':
 'GND43': CDS_PINID='GND43';
NODE_NAME     U6011 BV32
 '@T6G_MB_LIB.T6G(SCH_1):PAGE409_I17@PURE_QUANTA.PT5161LRS(CHIPS)':
 'GND44': CDS_PINID='GND44';
NODE_NAME     U6011 BV4
 '@T6G_MB_LIB.T6G(SCH_1):PAGE409_I17@PURE_QUANTA.PT5161LRS(CHIPS)':
 'GND45': CDS_PINID='GND45';
NODE_NAME     U6011 BW2
 '@T6G_MB_LIB.T6G(SCH_1):PAGE409_I17@PURE_QUANTA.PT5161LRS(CHIPS)':
 'GND46': CDS_PINID='GND46';
NODE_NAME     U6011 BW34
 '@T6G_MB_LIB.T6G(SCH_1):PAGE409_I17@PURE_QUANTA.PT5161LRS(CHIPS)':
 'GND47': CDS_PINID='GND47';
NODE_NAME     U6011 BY1
 '@T6G_MB_LIB.T6G(SCH_1):PAGE409_I17@PURE_QUANTA.PT5161LRS(CHIPS)':
 'GND48': CDS_PINID='GND48';
NODE_NAME     U6011 BY35
 '@T6G_MB_LIB.T6G(SCH_1):PAGE409_I17@PURE_QUANTA.PT5161LRS(CHIPS)':
 'GND49': CDS_PINID='GND49';
NODE_NAME     U6011 CE13
 '@T6G_MB_LIB.T6G(SCH_1):PAGE409_I17@PURE_QUANTA.PT5161LRS(CHIPS)':
 'GND50': CDS_PINID='GND50';
NODE_NAME     U6011 CE22
 '@T6G_MB_LIB.T6G(SCH_1):PAGE409_I17@PURE_QUANTA.PT5161LRS(CHIPS)':
 'GND51': CDS_PINID='GND51';
NODE_NAME     U6011 CE32
 '@T6G_MB_LIB.T6G(SCH_1):PAGE409_I17@PURE_QUANTA.PT5161LRS(CHIPS)':
 'GND52': CDS_PINID='GND52';
NODE_NAME     U6011 CE4
 '@T6G_MB_LIB.T6G(SCH_1):PAGE409_I17@PURE_QUANTA.PT5161LRS(CHIPS)':
 'GND53': CDS_PINID='GND53';
NODE_NAME     U6011 CF2
 '@T6G_MB_LIB.T6G(SCH_1):PAGE409_I17@PURE_QUANTA.PT5161LRS(CHIPS)':
 'GND54': CDS_PINID='GND54';
NODE_NAME     U6011 CF34
 '@T6G_MB_LIB.T6G(SCH_1):PAGE409_I17@PURE_QUANTA.PT5161LRS(CHIPS)':
 'GND55': CDS_PINID='GND55';
NODE_NAME     U6011 CG1
 '@T6G_MB_LIB.T6G(SCH_1):PAGE409_I17@PURE_QUANTA.PT5161LRS(CHIPS)':
 'GND56': CDS_PINID='GND56';
NODE_NAME     U6011 CG35
 '@T6G_MB_LIB.T6G(SCH_1):PAGE409_I17@PURE_QUANTA.PT5161LRS(CHIPS)':
 'GND57': CDS_PINID='GND57';
NODE_NAME     U6011 CM13
 '@T6G_MB_LIB.T6G(SCH_1):PAGE409_I17@PURE_QUANTA.PT5161LRS(CHIPS)':
 'GND58': CDS_PINID='GND58';
NODE_NAME     U6011 CM22
 '@T6G_MB_LIB.T6G(SCH_1):PAGE409_I17@PURE_QUANTA.PT5161LRS(CHIPS)':
 'GND59': CDS_PINID='GND59';
NODE_NAME     U6011 CM32
 '@T6G_MB_LIB.T6G(SCH_1):PAGE409_I17@PURE_QUANTA.PT5161LRS(CHIPS)':
 'GND60': CDS_PINID='GND60';
NODE_NAME     U6011 CM4
 '@T6G_MB_LIB.T6G(SCH_1):PAGE409_I17@PURE_QUANTA.PT5161LRS(CHIPS)':
 'GND61': CDS_PINID='GND61';
NODE_NAME     U6011 CN2
 '@T6G_MB_LIB.T6G(SCH_1):PAGE409_I17@PURE_QUANTA.PT5161LRS(CHIPS)':
 'GND62': CDS_PINID='GND62';
NODE_NAME     U6011 CN34
 '@T6G_MB_LIB.T6G(SCH_1):PAGE409_I17@PURE_QUANTA.PT5161LRS(CHIPS)':
 'GND63': CDS_PINID='GND63';
NODE_NAME     U6011 CP1
 '@T6G_MB_LIB.T6G(SCH_1):PAGE409_I17@PURE_QUANTA.PT5161LRS(CHIPS)':
 'GND64': CDS_PINID='GND64';
NODE_NAME     U6011 CP35
 '@T6G_MB_LIB.T6G(SCH_1):PAGE409_I17@PURE_QUANTA.PT5161LRS(CHIPS)':
 'GND65': CDS_PINID='GND65';
NODE_NAME     U6011 CW13
 '@T6G_MB_LIB.T6G(SCH_1):PAGE409_I17@PURE_QUANTA.PT5161LRS(CHIPS)':
 'GND66': CDS_PINID='GND66';
NODE_NAME     U6011 CW22
 '@T6G_MB_LIB.T6G(SCH_1):PAGE409_I17@PURE_QUANTA.PT5161LRS(CHIPS)':
 'GND67': CDS_PINID='GND67';
NODE_NAME     U6011 CW32
 '@T6G_MB_LIB.T6G(SCH_1):PAGE409_I17@PURE_QUANTA.PT5161LRS(CHIPS)':
 'GND68': CDS_PINID='GND68';
NODE_NAME     U6011 CW4
 '@T6G_MB_LIB.T6G(SCH_1):PAGE409_I17@PURE_QUANTA.PT5161LRS(CHIPS)':
 'GND69': CDS_PINID='GND69';
NODE_NAME     U6011 CY2
 '@T6G_MB_LIB.T6G(SCH_1):PAGE409_I17@PURE_QUANTA.PT5161LRS(CHIPS)':
 'GND70': CDS_PINID='GND70';
NODE_NAME     U6011 CY34
 '@T6G_MB_LIB.T6G(SCH_1):PAGE409_I17@PURE_QUANTA.PT5161LRS(CHIPS)':
 'GND71': CDS_PINID='GND71';
NODE_NAME     U6011 DA1
 '@T6G_MB_LIB.T6G(SCH_1):PAGE409_I17@PURE_QUANTA.PT5161LRS(CHIPS)':
 'GND72': CDS_PINID='GND72';
NODE_NAME     U6011 DA35
 '@T6G_MB_LIB.T6G(SCH_1):PAGE409_I17@PURE_QUANTA.PT5161LRS(CHIPS)':
 'GND73': CDS_PINID='GND73';
NODE_NAME     U6011 DF13
 '@T6G_MB_LIB.T6G(SCH_1):PAGE409_I17@PURE_QUANTA.PT5161LRS(CHIPS)':
 'GND74': CDS_PINID='GND74';
NODE_NAME     U6011 DF22
 '@T6G_MB_LIB.T6G(SCH_1):PAGE409_I17@PURE_QUANTA.PT5161LRS(CHIPS)':
 'GND75': CDS_PINID='GND75';
NODE_NAME     U6011 DF32
 '@T6G_MB_LIB.T6G(SCH_1):PAGE409_I17@PURE_QUANTA.PT5161LRS(CHIPS)':
 'GND76': CDS_PINID='GND76';
NODE_NAME     U6011 DF4
 '@T6G_MB_LIB.T6G(SCH_1):PAGE409_I17@PURE_QUANTA.PT5161LRS(CHIPS)':
 'GND77': CDS_PINID='GND77';
NODE_NAME     U6011 DG2
 '@T6G_MB_LIB.T6G(SCH_1):PAGE409_I17@PURE_QUANTA.PT5161LRS(CHIPS)':
 'GND78': CDS_PINID='GND78';
NODE_NAME     U6011 DG34
 '@T6G_MB_LIB.T6G(SCH_1):PAGE409_I17@PURE_QUANTA.PT5161LRS(CHIPS)':
 'GND79': CDS_PINID='GND79';
NODE_NAME     U6011 DH1
 '@T6G_MB_LIB.T6G(SCH_1):PAGE409_I17@PURE_QUANTA.PT5161LRS(CHIPS)':
 'GND80': CDS_PINID='GND80';
NODE_NAME     U6011 DH35
 '@T6G_MB_LIB.T6G(SCH_1):PAGE409_I17@PURE_QUANTA.PT5161LRS(CHIPS)':
 'GND81': CDS_PINID='GND81';
NODE_NAME     U6011 DN13
 '@T6G_MB_LIB.T6G(SCH_1):PAGE409_I17@PURE_QUANTA.PT5161LRS(CHIPS)':
 'GND82': CDS_PINID='GND82';
NODE_NAME     U6011 DN22
 '@T6G_MB_LIB.T6G(SCH_1):PAGE409_I17@PURE_QUANTA.PT5161LRS(CHIPS)':
 'GND83': CDS_PINID='GND83';
NODE_NAME     U6011 DN32
 '@T6G_MB_LIB.T6G(SCH_1):PAGE409_I17@PURE_QUANTA.PT5161LRS(CHIPS)':
 'GND84': CDS_PINID='GND84';
NODE_NAME     U6011 DN4
 '@T6G_MB_LIB.T6G(SCH_1):PAGE409_I17@PURE_QUANTA.PT5161LRS(CHIPS)':
 'GND85': CDS_PINID='GND85';
NODE_NAME     U6011 DP2
 '@T6G_MB_LIB.T6G(SCH_1):PAGE409_I17@PURE_QUANTA.PT5161LRS(CHIPS)':
 'GND86': CDS_PINID='GND86';
NODE_NAME     U6011 DP34
 '@T6G_MB_LIB.T6G(SCH_1):PAGE409_I17@PURE_QUANTA.PT5161LRS(CHIPS)':
 'GND87': CDS_PINID='GND87';
NODE_NAME     U6011 DR1
 '@T6G_MB_LIB.T6G(SCH_1):PAGE409_I17@PURE_QUANTA.PT5161LRS(CHIPS)':
 'GND88': CDS_PINID='GND88';
NODE_NAME     U6011 DR35
 '@T6G_MB_LIB.T6G(SCH_1):PAGE409_I17@PURE_QUANTA.PT5161LRS(CHIPS)':
 'GND89': CDS_PINID='GND89';
NODE_NAME     U6011 DY13
 '@T6G_MB_LIB.T6G(SCH_1):PAGE409_I17@PURE_QUANTA.PT5161LRS(CHIPS)':
 'GND90': CDS_PINID='GND90';
NODE_NAME     U6011 DY22
 '@T6G_MB_LIB.T6G(SCH_1):PAGE409_I17@PURE_QUANTA.PT5161LRS(CHIPS)':
 'GND91': CDS_PINID='GND91';
NODE_NAME     U6011 DY32
 '@T6G_MB_LIB.T6G(SCH_1):PAGE409_I17@PURE_QUANTA.PT5161LRS(CHIPS)':
 'GND92': CDS_PINID='GND92';
NODE_NAME     U6011 DY4
 '@T6G_MB_LIB.T6G(SCH_1):PAGE409_I17@PURE_QUANTA.PT5161LRS(CHIPS)':
 'GND93': CDS_PINID='GND93';
NODE_NAME     U6011 E14
 '@T6G_MB_LIB.T6G(SCH_1):PAGE409_I17@PURE_QUANTA.PT5161LRS(CHIPS)':
 'GND94': CDS_PINID='GND94';
NODE_NAME     U6011 E27
 '@T6G_MB_LIB.T6G(SCH_1):PAGE409_I17@PURE_QUANTA.PT5161LRS(CHIPS)':
 'GND95': CDS_PINID='GND95';
NODE_NAME     U6011 E33
 '@T6G_MB_LIB.T6G(SCH_1):PAGE409_I17@PURE_QUANTA.PT5161LRS(CHIPS)':
 'GND96': CDS_PINID='GND96';
NODE_NAME     U6011 EA2
 '@T6G_MB_LIB.T6G(SCH_1):PAGE409_I17@PURE_QUANTA.PT5161LRS(CHIPS)':
 'GND97': CDS_PINID='GND97';
NODE_NAME     U6011 EA34
 '@T6G_MB_LIB.T6G(SCH_1):PAGE409_I17@PURE_QUANTA.PT5161LRS(CHIPS)':
 'GND98': CDS_PINID='GND98';
NODE_NAME     U6011 EB1
 '@T6G_MB_LIB.T6G(SCH_1):PAGE409_I17@PURE_QUANTA.PT5161LRS(CHIPS)':
 'GND99': CDS_PINID='GND99';
NODE_NAME     U6011 EB35
 '@T6G_MB_LIB.T6G(SCH_1):PAGE409_I17@PURE_QUANTA.PT5161LRS(CHIPS)':
 'GND100': CDS_PINID='GND100';
NODE_NAME     U6011 EG13
 '@T6G_MB_LIB.T6G(SCH_1):PAGE409_I17@PURE_QUANTA.PT5161LRS(CHIPS)':
 'GND101': CDS_PINID='GND101';
NODE_NAME     U6011 EG22
 '@T6G_MB_LIB.T6G(SCH_1):PAGE409_I17@PURE_QUANTA.PT5161LRS(CHIPS)':
 'GND102': CDS_PINID='GND102';
NODE_NAME     U6011 EG32
 '@T6G_MB_LIB.T6G(SCH_1):PAGE409_I17@PURE_QUANTA.PT5161LRS(CHIPS)':
 'GND103': CDS_PINID='GND103';
NODE_NAME     U6011 EG4
 '@T6G_MB_LIB.T6G(SCH_1):PAGE409_I17@PURE_QUANTA.PT5161LRS(CHIPS)':
 'GND104': CDS_PINID='GND104';
NODE_NAME     U6011 EH2
 '@T6G_MB_LIB.T6G(SCH_1):PAGE409_I17@PURE_QUANTA.PT5161LRS(CHIPS)':
 'GND105': CDS_PINID='GND105';
NODE_NAME     U6011 EH34
 '@T6G_MB_LIB.T6G(SCH_1):PAGE409_I17@PURE_QUANTA.PT5161LRS(CHIPS)':
 'GND106': CDS_PINID='GND106';
NODE_NAME     U6011 EJ1
 '@T6G_MB_LIB.T6G(SCH_1):PAGE409_I17@PURE_QUANTA.PT5161LRS(CHIPS)':
 'GND107': CDS_PINID='GND107';
NODE_NAME     U6011 EJ35
 '@T6G_MB_LIB.T6G(SCH_1):PAGE409_I17@PURE_QUANTA.PT5161LRS(CHIPS)':
 'GND108': CDS_PINID='GND108';
NODE_NAME     U6011 EP13
 '@T6G_MB_LIB.T6G(SCH_1):PAGE409_I17@PURE_QUANTA.PT5161LRS(CHIPS)':
 'GND109': CDS_PINID='GND109';
NODE_NAME     U6011 EP22
 '@T6G_MB_LIB.T6G(SCH_1):PAGE409_I17@PURE_QUANTA.PT5161LRS(CHIPS)':
 'GND110': CDS_PINID='GND110';
NODE_NAME     U6011 EP32
 '@T6G_MB_LIB.T6G(SCH_1):PAGE409_I17@PURE_QUANTA.PT5161LRS(CHIPS)':
 'GND111': CDS_PINID='GND111';
NODE_NAME     U6011 EP4
 '@T6G_MB_LIB.T6G(SCH_1):PAGE409_I17@PURE_QUANTA.PT5161LRS(CHIPS)':
 'GND112': CDS_PINID='GND112';
NODE_NAME     U6011 ER2
 '@T6G_MB_LIB.T6G(SCH_1):PAGE409_I17@PURE_QUANTA.PT5161LRS(CHIPS)':
 'GND113': CDS_PINID='GND113';
NODE_NAME     U6011 ER34
 '@T6G_MB_LIB.T6G(SCH_1):PAGE409_I17@PURE_QUANTA.PT5161LRS(CHIPS)':
 'GND114': CDS_PINID='GND114';
NODE_NAME     U6011 ET1
 '@T6G_MB_LIB.T6G(SCH_1):PAGE409_I17@PURE_QUANTA.PT5161LRS(CHIPS)':
 'GND115': CDS_PINID='GND115';
NODE_NAME     U6011 ET35
 '@T6G_MB_LIB.T6G(SCH_1):PAGE409_I17@PURE_QUANTA.PT5161LRS(CHIPS)':
 'GND116': CDS_PINID='GND116';
NODE_NAME     U6011 FA15
 '@T6G_MB_LIB.T6G(SCH_1):PAGE409_I17@PURE_QUANTA.PT5161LRS(CHIPS)':
 'GND117': CDS_PINID='GND117';
NODE_NAME     U6011 FA32
 '@T6G_MB_LIB.T6G(SCH_1):PAGE409_I17@PURE_QUANTA.PT5161LRS(CHIPS)':
 'GND118': CDS_PINID='GND118';
NODE_NAME     U6011 FB2
 '@T6G_MB_LIB.T6G(SCH_1):PAGE409_I17@PURE_QUANTA.PT5161LRS(CHIPS)':
 'GND119': CDS_PINID='GND119';
NODE_NAME     U6011 FB34
 '@T6G_MB_LIB.T6G(SCH_1):PAGE409_I17@PURE_QUANTA.PT5161LRS(CHIPS)':
 'GND120': CDS_PINID='GND120';
NODE_NAME     U6011 FC19
 '@T6G_MB_LIB.T6G(SCH_1):PAGE409_I17@PURE_QUANTA.PT5161LRS(CHIPS)':
 'GND121': CDS_PINID='GND121';
NODE_NAME     U6011 FC23
 '@T6G_MB_LIB.T6G(SCH_1):PAGE409_I17@PURE_QUANTA.PT5161LRS(CHIPS)':
 'GND122': CDS_PINID='GND122';
NODE_NAME     U6011 FC25
 '@T6G_MB_LIB.T6G(SCH_1):PAGE409_I17@PURE_QUANTA.PT5161LRS(CHIPS)':
 'GND123': CDS_PINID='GND123';
NODE_NAME     U6011 FC28
 '@T6G_MB_LIB.T6G(SCH_1):PAGE409_I17@PURE_QUANTA.PT5161LRS(CHIPS)':
 'GND124': CDS_PINID='GND124';
NODE_NAME     U6011 FC3
 '@T6G_MB_LIB.T6G(SCH_1):PAGE409_I17@PURE_QUANTA.PT5161LRS(CHIPS)':
 'GND125': CDS_PINID='GND125';
NODE_NAME     U6011 FC6
 '@T6G_MB_LIB.T6G(SCH_1):PAGE409_I17@PURE_QUANTA.PT5161LRS(CHIPS)':
 'GND126': CDS_PINID='GND126';
NODE_NAME     U6011 FC9
 '@T6G_MB_LIB.T6G(SCH_1):PAGE409_I17@PURE_QUANTA.PT5161LRS(CHIPS)':
 'GND127': CDS_PINID='GND127';
NODE_NAME     U6011 FD1
 '@T6G_MB_LIB.T6G(SCH_1):PAGE409_I17@PURE_QUANTA.PT5161LRS(CHIPS)':
 'GND128': CDS_PINID='GND128';
NODE_NAME     U6011 FD35
 '@T6G_MB_LIB.T6G(SCH_1):PAGE409_I17@PURE_QUANTA.PT5161LRS(CHIPS)':
 'GND129': CDS_PINID='GND129';
NODE_NAME     U6011 FF14
 '@T6G_MB_LIB.T6G(SCH_1):PAGE409_I17@PURE_QUANTA.PT5161LRS(CHIPS)':
 'GND130': CDS_PINID='GND130';
NODE_NAME     U6011 FF21
 '@T6G_MB_LIB.T6G(SCH_1):PAGE409_I17@PURE_QUANTA.PT5161LRS(CHIPS)':
 'GND131': CDS_PINID='GND131';
NODE_NAME     U6011 FJ12
 '@T6G_MB_LIB.T6G(SCH_1):PAGE409_I17@PURE_QUANTA.PT5161LRS(CHIPS)':
 'GND132': CDS_PINID='GND132';
NODE_NAME     U6011 FJ19
 '@T6G_MB_LIB.T6G(SCH_1):PAGE409_I17@PURE_QUANTA.PT5161LRS(CHIPS)':
 'GND133': CDS_PINID='GND133';
NODE_NAME     U6011 H12
 '@T6G_MB_LIB.T6G(SCH_1):PAGE409_I17@PURE_QUANTA.PT5161LRS(CHIPS)':
 'GND134': CDS_PINID='GND134';
NODE_NAME     U6011 H16
 '@T6G_MB_LIB.T6G(SCH_1):PAGE409_I17@PURE_QUANTA.PT5161LRS(CHIPS)':
 'GND135': CDS_PINID='GND135';
NODE_NAME     U6011 H19
 '@T6G_MB_LIB.T6G(SCH_1):PAGE409_I17@PURE_QUANTA.PT5161LRS(CHIPS)':
 'GND136': CDS_PINID='GND136';
NODE_NAME     U6011 H31
 '@T6G_MB_LIB.T6G(SCH_1):PAGE409_I17@PURE_QUANTA.PT5161LRS(CHIPS)':
 'GND137': CDS_PINID='GND137';
NODE_NAME     U6011 J22
 '@T6G_MB_LIB.T6G(SCH_1):PAGE409_I17@PURE_QUANTA.PT5161LRS(CHIPS)':
 'GND138': CDS_PINID='GND138';
NODE_NAME     U6011 J4
 '@T6G_MB_LIB.T6G(SCH_1):PAGE409_I17@PURE_QUANTA.PT5161LRS(CHIPS)':
 'GND139': CDS_PINID='GND139';
NODE_NAME     U6011 K2
 '@T6G_MB_LIB.T6G(SCH_1):PAGE409_I17@PURE_QUANTA.PT5161LRS(CHIPS)':
 'GND140': CDS_PINID='GND140';
NODE_NAME     U6011 K34
 '@T6G_MB_LIB.T6G(SCH_1):PAGE409_I17@PURE_QUANTA.PT5161LRS(CHIPS)':
 'GND141': CDS_PINID='GND141';
NODE_NAME     U6011 L1
 '@T6G_MB_LIB.T6G(SCH_1):PAGE409_I17@PURE_QUANTA.PT5161LRS(CHIPS)':
 'GND142': CDS_PINID='GND142';
NODE_NAME     U6011 L35
 '@T6G_MB_LIB.T6G(SCH_1):PAGE409_I17@PURE_QUANTA.PT5161LRS(CHIPS)':
 'GND143': CDS_PINID='GND143';
NODE_NAME     U6011 T13
 '@T6G_MB_LIB.T6G(SCH_1):PAGE409_I17@PURE_QUANTA.PT5161LRS(CHIPS)':
 'GND144': CDS_PINID='GND144';
NODE_NAME     U6011 T22
 '@T6G_MB_LIB.T6G(SCH_1):PAGE409_I17@PURE_QUANTA.PT5161LRS(CHIPS)':
 'GND145': CDS_PINID='GND145';
NODE_NAME     U6011 T32
 '@T6G_MB_LIB.T6G(SCH_1):PAGE409_I17@PURE_QUANTA.PT5161LRS(CHIPS)':
 'GND146': CDS_PINID='GND146';
NODE_NAME     U6011 T4
 '@T6G_MB_LIB.T6G(SCH_1):PAGE409_I17@PURE_QUANTA.PT5161LRS(CHIPS)':
 'GND147': CDS_PINID='GND147';
NODE_NAME     U6011 U2
 '@T6G_MB_LIB.T6G(SCH_1):PAGE409_I17@PURE_QUANTA.PT5161LRS(CHIPS)':
 'GND148': CDS_PINID='GND148';
NODE_NAME     U6011 U34
 '@T6G_MB_LIB.T6G(SCH_1):PAGE409_I17@PURE_QUANTA.PT5161LRS(CHIPS)':
 'GND149': CDS_PINID='GND149';
NODE_NAME     U6011 V1
 '@T6G_MB_LIB.T6G(SCH_1):PAGE409_I17@PURE_QUANTA.PT5161LRS(CHIPS)':
 'GND150': CDS_PINID='GND150';
NODE_NAME     U6011 V35
 '@T6G_MB_LIB.T6G(SCH_1):PAGE409_I17@PURE_QUANTA.PT5161LRS(CHIPS)':
 'GND151': CDS_PINID='GND151';
NODE_NAME     R1044 2
 '@T6G_MB_LIB.T6G(SCH_1):PAGE410_I20@PURE_QUANTA.Q_RES(CHIPS)':
 'B': CDS_PINID='B';
NODE_NAME     C664 2
 '@T6G_MB_LIB.T6G(SCH_1):PAGE410_I24@PURE_QUANTA.Q_CAP(CHIPS)':
 'B': CDS_PINID='B';
NODE_NAME     C598 2
 '@T6G_MB_LIB.T6G(SCH_1):PAGE411_I5@PURE_QUANTA.Q_CAP(CHIPS)':
 'B': CDS_PINID='B';
NODE_NAME     C601 2
 '@T6G_MB_LIB.T6G(SCH_1):PAGE411_I7@PURE_QUANTA.Q_CAP(CHIPS)':
 'B': CDS_PINID='B';
NODE_NAME     C588 2
 '@T6G_MB_LIB.T6G(SCH_1):PAGE411_I12@PURE_QUANTA.Q_CAP(CHIPS)':
 'B': CDS_PINID='B';
NODE_NAME     C590 2
 '@T6G_MB_LIB.T6G(SCH_1):PAGE411_I15@PURE_QUANTA.Q_CAP(CHIPS)':
 'B': CDS_PINID='B';
NODE_NAME     C595 2
 '@T6G_MB_LIB.T6G(SCH_1):PAGE411_I16@PURE_QUANTA.Q_CAP(CHIPS)':
 'B': CDS_PINID='B';
NODE_NAME     C587 2
 '@T6G_MB_LIB.T6G(SCH_1):PAGE411_I17@PURE_QUANTA.Q_CAP(CHIPS)':
 'B': CDS_PINID='B';
NODE_NAME     C589 2
 '@T6G_MB_LIB.T6G(SCH_1):PAGE411_I18@PURE_QUANTA.Q_CAP(CHIPS)':
 'B': CDS_PINID='B';
NODE_NAME     C594 2
 '@T6G_MB_LIB.T6G(SCH_1):PAGE411_I19@PURE_QUANTA.Q_CAP(CHIPS)':
 'B': CDS_PINID='B';
NODE_NAME     C597 2
 '@T6G_MB_LIB.T6G(SCH_1):PAGE411_I20@PURE_QUANTA.Q_CAP(CHIPS)':
 'B': CDS_PINID='B';
NODE_NAME     C599 2
 '@T6G_MB_LIB.T6G(SCH_1):PAGE411_I21@PURE_QUANTA.Q_CAP(CHIPS)':
 'B': CDS_PINID='B';
NODE_NAME     C591 2
 '@T6G_MB_LIB.T6G(SCH_1):PAGE411_I22@PURE_QUANTA.Q_CAP(CHIPS)':
 'B': CDS_PINID='B';
NODE_NAME     C596 2
 '@T6G_MB_LIB.T6G(SCH_1):PAGE411_I24@PURE_QUANTA.Q_CAP(CHIPS)':
 'B': CDS_PINID='B';
NODE_NAME     C600 2
 '@T6G_MB_LIB.T6G(SCH_1):PAGE411_I25@PURE_QUANTA.Q_CAP(CHIPS)':
 'B': CDS_PINID='B';
NODE_NAME     C602 2
 '@T6G_MB_LIB.T6G(SCH_1):PAGE411_I26@PURE_QUANTA.Q_CAP(CHIPS)':
 'B': CDS_PINID='B';
NODE_NAME     C603 2
 '@T6G_MB_LIB.T6G(SCH_1):PAGE411_I27@PURE_QUANTA.Q_CAP(CHIPS)':
 'B': CDS_PINID='B';
NODE_NAME     C606 2
 '@T6G_MB_LIB.T6G(SCH_1):PAGE411_I28@PURE_QUANTA.Q_CAP(CHIPS)':
 'B': CDS_PINID='B';
NODE_NAME     C617 2
 '@T6G_MB_LIB.T6G(SCH_1):PAGE411_I32@PURE_QUANTA.Q_CAP(CHIPS)':
 'B': CDS_PINID='B';
NODE_NAME     C623 2
 '@T6G_MB_LIB.T6G(SCH_1):PAGE411_I34@PURE_QUANTA.Q_CAP(CHIPS)':
 'B': CDS_PINID='B';
NODE_NAME     C662 2
 '@T6G_MB_LIB.T6G(SCH_1):PAGE411_I37@PURE_QUANTA.Q_CAP(CHIPS)':
 'B': CDS_PINID='B';
NODE_NAME     C609 2
 '@T6G_MB_LIB.T6G(SCH_1):PAGE411_I38@PURE_QUANTA.Q_CAP(CHIPS)':
 'B': CDS_PINID='B';
NODE_NAME     C618 2
 '@T6G_MB_LIB.T6G(SCH_1):PAGE411_I39@PURE_QUANTA.Q_CAP(CHIPS)':
 'B': CDS_PINID='B';
NODE_NAME     C626 2
 '@T6G_MB_LIB.T6G(SCH_1):PAGE411_I40@PURE_QUANTA.Q_CAP(CHIPS)':
 'B': CDS_PINID='B';
NODE_NAME     C645 2
 '@T6G_MB_LIB.T6G(SCH_1):PAGE411_I41@PURE_QUANTA.Q_CAP(CHIPS)':
 'B': CDS_PINID='B';
NODE_NAME     C616 2
 '@T6G_MB_LIB.T6G(SCH_1):PAGE411_I42@PURE_QUANTA.Q_CAP(CHIPS)':
 'B': CDS_PINID='B';
NODE_NAME     C657 2
 '@T6G_MB_LIB.T6G(SCH_1):PAGE411_I43@PURE_QUANTA.Q_CAP(CHIPS)':
 'B': CDS_PINID='B';
NODE_NAME     C607 2
 '@T6G_MB_LIB.T6G(SCH_1):PAGE411_I44@PURE_QUANTA.Q_CAP(CHIPS)':
 'B': CDS_PINID='B';
NODE_NAME     C643 2
 '@T6G_MB_LIB.T6G(SCH_1):PAGE411_I45@PURE_QUANTA.Q_CAP(CHIPS)':
 'B': CDS_PINID='B';
NODE_NAME     C635 2
 '@T6G_MB_LIB.T6G(SCH_1):PAGE411_I46@PURE_QUANTA.Q_CAP(CHIPS)':
 'B': CDS_PINID='B';
NODE_NAME     C627 2
 '@T6G_MB_LIB.T6G(SCH_1):PAGE411_I47@PURE_QUANTA.Q_CAP(CHIPS)':
 'B': CDS_PINID='B';
NODE_NAME     C647 2
 '@T6G_MB_LIB.T6G(SCH_1):PAGE411_I48@PURE_QUANTA.Q_CAP(CHIPS)':
 'B': CDS_PINID='B';
NODE_NAME     C654 2
 '@T6G_MB_LIB.T6G(SCH_1):PAGE411_I49@PURE_QUANTA.Q_CAP(CHIPS)':
 'B': CDS_PINID='B';
NODE_NAME     C644 2
 '@T6G_MB_LIB.T6G(SCH_1):PAGE411_I50@PURE_QUANTA.Q_CAP(CHIPS)':
 'B': CDS_PINID='B';
NODE_NAME     C638 2
 '@T6G_MB_LIB.T6G(SCH_1):PAGE411_I51@PURE_QUANTA.Q_CAP(CHIPS)':
 'B': CDS_PINID='B';
NODE_NAME     C649 2
 '@T6G_MB_LIB.T6G(SCH_1):PAGE411_I52@PURE_QUANTA.Q_CAP(CHIPS)':
 'B': CDS_PINID='B';
NODE_NAME     C653 2
 '@T6G_MB_LIB.T6G(SCH_1):PAGE411_I53@PURE_QUANTA.Q_CAP(CHIPS)':
 'B': CDS_PINID='B';
NODE_NAME     C631 2
 '@T6G_MB_LIB.T6G(SCH_1):PAGE411_I55@PURE_QUANTA.Q_CAP(CHIPS)':
 'B': CDS_PINID='B';
NODE_NAME     C650 2
 '@T6G_MB_LIB.T6G(SCH_1):PAGE411_I58@PURE_QUANTA.Q_CAP(CHIPS)':
 'B': CDS_PINID='B';
NODE_NAME     C620 2
 '@T6G_MB_LIB.T6G(SCH_1):PAGE411_I59@PURE_QUANTA.Q_CAP(CHIPS)':
 'B': CDS_PINID='B';
NODE_NAME     C613 2
 '@T6G_MB_LIB.T6G(SCH_1):PAGE411_I61@PURE_QUANTA.Q_CAP(CHIPS)':
 'B': CDS_PINID='B';
NODE_NAME     C625 2
 '@T6G_MB_LIB.T6G(SCH_1):PAGE411_I64@PURE_QUANTA.Q_CAP(CHIPS)':
 'B': CDS_PINID='B';
NODE_NAME     C628 2
 '@T6G_MB_LIB.T6G(SCH_1):PAGE411_I65@PURE_QUANTA.Q_CAP(CHIPS)':
 'B': CDS_PINID='B';
NODE_NAME     C632 2
 '@T6G_MB_LIB.T6G(SCH_1):PAGE411_I67@PURE_QUANTA.Q_CAP(CHIPS)':
 'B': CDS_PINID='B';
NODE_NAME     C636 2
 '@T6G_MB_LIB.T6G(SCH_1):PAGE411_I68@PURE_QUANTA.Q_CAP(CHIPS)':
 'B': CDS_PINID='B';
NODE_NAME     C633 2
 '@T6G_MB_LIB.T6G(SCH_1):PAGE411_I69@PURE_QUANTA.Q_CAP(CHIPS)':
 'B': CDS_PINID='B';
NODE_NAME     C637 2
 '@T6G_MB_LIB.T6G(SCH_1):PAGE411_I70@PURE_QUANTA.Q_CAP(CHIPS)':
 'B': CDS_PINID='B';
NODE_NAME     C634 2
 '@T6G_MB_LIB.T6G(SCH_1):PAGE411_I71@PURE_QUANTA.Q_CAP(CHIPS)':
 'B': CDS_PINID='B';
NODE_NAME     C663 2
 '@T6G_MB_LIB.T6G(SCH_1):PAGE411_I72@PURE_QUANTA.Q_CAP(CHIPS)':
 'B': CDS_PINID='B';
NODE_NAME     C630 2
 '@T6G_MB_LIB.T6G(SCH_1):PAGE411_I73@PURE_QUANTA.Q_CAP(CHIPS)':
 'B': CDS_PINID='B';
NODE_NAME     C646 2
 '@T6G_MB_LIB.T6G(SCH_1):PAGE411_I74@PURE_QUANTA.Q_CAP(CHIPS)':
 'B': CDS_PINID='B';
NODE_NAME     C651 2
 '@T6G_MB_LIB.T6G(SCH_1):PAGE411_I75@PURE_QUANTA.Q_CAP(CHIPS)':
 'B': CDS_PINID='B';
NODE_NAME     C655 2
 '@T6G_MB_LIB.T6G(SCH_1):PAGE411_I76@PURE_QUANTA.Q_CAP(CHIPS)':
 'B': CDS_PINID='B';
NODE_NAME     C656 2
 '@T6G_MB_LIB.T6G(SCH_1):PAGE411_I77@PURE_QUANTA.Q_CAP(CHIPS)':
 'B': CDS_PINID='B';
NODE_NAME     C661 2
 '@T6G_MB_LIB.T6G(SCH_1):PAGE411_I78@PURE_QUANTA.Q_CAP(CHIPS)':
 'B': CDS_PINID='B';
NODE_NAME     C648 2
 '@T6G_MB_LIB.T6G(SCH_1):PAGE411_I79@PURE_QUANTA.Q_CAP(CHIPS)':
 'B': CDS_PINID='B';
NODE_NAME     C608 2
 '@T6G_MB_LIB.T6G(SCH_1):PAGE411_I81@PURE_QUANTA.Q_CAP(CHIPS)':
 'B': CDS_PINID='B';
NODE_NAME     C610 2
 '@T6G_MB_LIB.T6G(SCH_1):PAGE411_I82@PURE_QUANTA.Q_CAP(CHIPS)':
 'B': CDS_PINID='B';
NODE_NAME     C615 2
 '@T6G_MB_LIB.T6G(SCH_1):PAGE411_I83@PURE_QUANTA.Q_CAP(CHIPS)':
 'B': CDS_PINID='B';
NODE_NAME     C619 2
 '@T6G_MB_LIB.T6G(SCH_1):PAGE411_I84@PURE_QUANTA.Q_CAP(CHIPS)':
 'B': CDS_PINID='B';
NODE_NAME     C614 2
 '@T6G_MB_LIB.T6G(SCH_1):PAGE411_I85@PURE_QUANTA.Q_CAP(CHIPS)':
 'B': CDS_PINID='B';
NODE_NAME     C622 2
 '@T6G_MB_LIB.T6G(SCH_1):PAGE411_I86@PURE_QUANTA.Q_CAP(CHIPS)':
 'B': CDS_PINID='B';
NODE_NAME     C652 2
 '@T6G_MB_LIB.T6G(SCH_1):PAGE411_I87@PURE_QUANTA.Q_CAP(CHIPS)':
 'B': CDS_PINID='B';
NODE_NAME     R1072 2
 '@T6G_MB_LIB.T6G(SCH_1):PAGE419_I8@PURE_QUANTA.Q_RES(CHIPS)':
 'B': CDS_PINID='B';
NODE_NAME     R631 2
 '@T6G_MB_LIB.T6G(SCH_1):PAGE419_I17@PURE_QUANTA.Q_RES(CHIPS)':
 'B': CDS_PINID='B';
NODE_NAME     R634 2
 '@T6G_MB_LIB.T6G(SCH_1):PAGE419_I18@PURE_QUANTA.Q_RES(CHIPS)':
 'B': CDS_PINID='B';
NODE_NAME     R1076 2
 '@T6G_MB_LIB.T6G(SCH_1):PAGE419_I36@PURE_QUANTA.Q_RES(CHIPS)':
 'B': CDS_PINID='B';
NODE_NAME     R1078 2
 '@T6G_MB_LIB.T6G(SCH_1):PAGE419_I37@PURE_QUANTA.Q_RES(CHIPS)':
 'B': CDS_PINID='B';
NODE_NAME     R1079 2
 '@T6G_MB_LIB.T6G(SCH_1):PAGE419_I39@PURE_QUANTA.Q_RES(CHIPS)':
 'B': CDS_PINID='B';
NODE_NAME     R1048 2
 '@T6G_MB_LIB.T6G(SCH_1):PAGE419_I50@PURE_QUANTA.Q_RES(CHIPS)':
 'B': CDS_PINID='B';
NODE_NAME     R1056 2
 '@T6G_MB_LIB.T6G(SCH_1):PAGE419_I65@PURE_QUANTA.Q_RES(CHIPS)':
 'B': CDS_PINID='B';
NODE_NAME     R1058 2
 '@T6G_MB_LIB.T6G(SCH_1):PAGE419_I66@PURE_QUANTA.Q_RES(CHIPS)':
 'B': CDS_PINID='B';
NODE_NAME     R1060 2
 '@T6G_MB_LIB.T6G(SCH_1):PAGE419_I69@PURE_QUANTA.Q_RES(CHIPS)':
 'B': CDS_PINID='B';
NODE_NAME     R1062 2
 '@T6G_MB_LIB.T6G(SCH_1):PAGE419_I76@PURE_QUANTA.Q_RES(CHIPS)':
 'B': CDS_PINID='B';
NODE_NAME     R1061 2
 '@T6G_MB_LIB.T6G(SCH_1):PAGE419_I77@PURE_QUANTA.Q_RES(CHIPS)':
 'B': CDS_PINID='B';
NODE_NAME     U6012 E30
 '@T6G_MB_LIB.T6G(SCH_1):PAGE419_I83@PURE_QUANTA.PT5161LRS(CHIPS)':
 'T_SENSE': CDS_PINID='T_SENSE';
NODE_NAME     R1083 2
 '@T6G_MB_LIB.T6G(SCH_1):PAGE420_I13@PURE_QUANTA.Q_RES(CHIPS)':
 'B': CDS_PINID='B';
NODE_NAME     R1084 2
 '@T6G_MB_LIB.T6G(SCH_1):PAGE420_I14@PURE_QUANTA.Q_RES(CHIPS)':
 'B': CDS_PINID='B';
NODE_NAME     U6012 AC13
 '@T6G_MB_LIB.T6G(SCH_1):PAGE420_I17@PURE_QUANTA.PT5161LRS(CHIPS)':
 'GND1': CDS_PINID='GND1';
NODE_NAME     U6012 AC22
 '@T6G_MB_LIB.T6G(SCH_1):PAGE420_I17@PURE_QUANTA.PT5161LRS(CHIPS)':
 'GND2': CDS_PINID='GND2';
NODE_NAME     U6012 AC32
 '@T6G_MB_LIB.T6G(SCH_1):PAGE420_I17@PURE_QUANTA.PT5161LRS(CHIPS)':
 'GND3': CDS_PINID='GND3';
NODE_NAME     U6012 AC4
 '@T6G_MB_LIB.T6G(SCH_1):PAGE420_I17@PURE_QUANTA.PT5161LRS(CHIPS)':
 'GND4': CDS_PINID='GND4';
NODE_NAME     U6012 AD2
 '@T6G_MB_LIB.T6G(SCH_1):PAGE420_I17@PURE_QUANTA.PT5161LRS(CHIPS)':
 'GND5': CDS_PINID='GND5';
NODE_NAME     U6012 AD34
 '@T6G_MB_LIB.T6G(SCH_1):PAGE420_I17@PURE_QUANTA.PT5161LRS(CHIPS)':
 'GND6': CDS_PINID='GND6';
NODE_NAME     U6012 AE1
 '@T6G_MB_LIB.T6G(SCH_1):PAGE420_I17@PURE_QUANTA.PT5161LRS(CHIPS)':
 'GND7': CDS_PINID='GND7';
NODE_NAME     U6012 AE35
 '@T6G_MB_LIB.T6G(SCH_1):PAGE420_I17@PURE_QUANTA.PT5161LRS(CHIPS)':
 'GND8': CDS_PINID='GND8';
NODE_NAME     U6012 AK13
 '@T6G_MB_LIB.T6G(SCH_1):PAGE420_I17@PURE_QUANTA.PT5161LRS(CHIPS)':
 'GND9': CDS_PINID='GND9';
NODE_NAME     U6012 AK22
 '@T6G_MB_LIB.T6G(SCH_1):PAGE420_I17@PURE_QUANTA.PT5161LRS(CHIPS)':
 'GND10': CDS_PINID='GND10';
NODE_NAME     U6012 AK32
 '@T6G_MB_LIB.T6G(SCH_1):PAGE420_I17@PURE_QUANTA.PT5161LRS(CHIPS)':
 'GND11': CDS_PINID='GND11';
NODE_NAME     U6012 AK4
 '@T6G_MB_LIB.T6G(SCH_1):PAGE420_I17@PURE_QUANTA.PT5161LRS(CHIPS)':
 'GND12': CDS_PINID='GND12';
NODE_NAME     U6012 AL2
 '@T6G_MB_LIB.T6G(SCH_1):PAGE420_I17@PURE_QUANTA.PT5161LRS(CHIPS)':
 'GND13': CDS_PINID='GND13';
NODE_NAME     U6012 AL34
 '@T6G_MB_LIB.T6G(SCH_1):PAGE420_I17@PURE_QUANTA.PT5161LRS(CHIPS)':
 'GND14': CDS_PINID='GND14';
NODE_NAME     U6012 AM1
 '@T6G_MB_LIB.T6G(SCH_1):PAGE420_I17@PURE_QUANTA.PT5161LRS(CHIPS)':
 'GND15': CDS_PINID='GND15';
NODE_NAME     U6012 AM35
 '@T6G_MB_LIB.T6G(SCH_1):PAGE420_I17@PURE_QUANTA.PT5161LRS(CHIPS)':
 'GND16': CDS_PINID='GND16';
NODE_NAME     U6012 AU13
 '@T6G_MB_LIB.T6G(SCH_1):PAGE420_I17@PURE_QUANTA.PT5161LRS(CHIPS)':
 'GND17': CDS_PINID='GND17';
NODE_NAME     U6012 AU22
 '@T6G_MB_LIB.T6G(SCH_1):PAGE420_I17@PURE_QUANTA.PT5161LRS(CHIPS)':
 'GND18': CDS_PINID='GND18';
NODE_NAME     U6012 AU32
 '@T6G_MB_LIB.T6G(SCH_1):PAGE420_I17@PURE_QUANTA.PT5161LRS(CHIPS)':
 'GND19': CDS_PINID='GND19';
NODE_NAME     U6012 AU4
 '@T6G_MB_LIB.T6G(SCH_1):PAGE420_I17@PURE_QUANTA.PT5161LRS(CHIPS)':
 'GND20': CDS_PINID='GND20';
NODE_NAME     U6012 AV2
 '@T6G_MB_LIB.T6G(SCH_1):PAGE420_I17@PURE_QUANTA.PT5161LRS(CHIPS)':
 'GND21': CDS_PINID='GND21';
NODE_NAME     U6012 AV34
 '@T6G_MB_LIB.T6G(SCH_1):PAGE420_I17@PURE_QUANTA.PT5161LRS(CHIPS)':
 'GND22': CDS_PINID='GND22';
NODE_NAME     U6012 AW1
 '@T6G_MB_LIB.T6G(SCH_1):PAGE420_I17@PURE_QUANTA.PT5161LRS(CHIPS)':
 'GND23': CDS_PINID='GND23';
NODE_NAME     U6012 AW35
 '@T6G_MB_LIB.T6G(SCH_1):PAGE420_I17@PURE_QUANTA.PT5161LRS(CHIPS)':
 'GND24': CDS_PINID='GND24';
NODE_NAME     U6012 B19
 '@T6G_MB_LIB.T6G(SCH_1):PAGE420_I17@PURE_QUANTA.PT5161LRS(CHIPS)':
 'GND25': CDS_PINID='GND25';
NODE_NAME     U6012 BD13
 '@T6G_MB_LIB.T6G(SCH_1):PAGE420_I17@PURE_QUANTA.PT5161LRS(CHIPS)':
 'GND26': CDS_PINID='GND26';
NODE_NAME     U6012 BD22
 '@T6G_MB_LIB.T6G(SCH_1):PAGE420_I17@PURE_QUANTA.PT5161LRS(CHIPS)':
 'GND27': CDS_PINID='GND27';
NODE_NAME     U6012 BD32
 '@T6G_MB_LIB.T6G(SCH_1):PAGE420_I17@PURE_QUANTA.PT5161LRS(CHIPS)':
 'GND28': CDS_PINID='GND28';
NODE_NAME     U6012 BD4
 '@T6G_MB_LIB.T6G(SCH_1):PAGE420_I17@PURE_QUANTA.PT5161LRS(CHIPS)':
 'GND29': CDS_PINID='GND29';
NODE_NAME     U6012 BE2
 '@T6G_MB_LIB.T6G(SCH_1):PAGE420_I17@PURE_QUANTA.PT5161LRS(CHIPS)':
 'GND30': CDS_PINID='GND30';
NODE_NAME     U6012 BE34
 '@T6G_MB_LIB.T6G(SCH_1):PAGE420_I17@PURE_QUANTA.PT5161LRS(CHIPS)':
 'GND31': CDS_PINID='GND31';
NODE_NAME     U6012 BF1
 '@T6G_MB_LIB.T6G(SCH_1):PAGE420_I17@PURE_QUANTA.PT5161LRS(CHIPS)':
 'GND32': CDS_PINID='GND32';
NODE_NAME     U6012 BF35
 '@T6G_MB_LIB.T6G(SCH_1):PAGE420_I17@PURE_QUANTA.PT5161LRS(CHIPS)':
 'GND33': CDS_PINID='GND33';
NODE_NAME     U6012 BL13
 '@T6G_MB_LIB.T6G(SCH_1):PAGE420_I17@PURE_QUANTA.PT5161LRS(CHIPS)':
 'GND34': CDS_PINID='GND34';
NODE_NAME     U6012 BL22
 '@T6G_MB_LIB.T6G(SCH_1):PAGE420_I17@PURE_QUANTA.PT5161LRS(CHIPS)':
 'GND35': CDS_PINID='GND35';
NODE_NAME     U6012 BL32
 '@T6G_MB_LIB.T6G(SCH_1):PAGE420_I17@PURE_QUANTA.PT5161LRS(CHIPS)':
 'GND36': CDS_PINID='GND36';
NODE_NAME     U6012 BL4
 '@T6G_MB_LIB.T6G(SCH_1):PAGE420_I17@PURE_QUANTA.PT5161LRS(CHIPS)':
 'GND37': CDS_PINID='GND37';
NODE_NAME     U6012 BM2
 '@T6G_MB_LIB.T6G(SCH_1):PAGE420_I17@PURE_QUANTA.PT5161LRS(CHIPS)':
 'GND38': CDS_PINID='GND38';
NODE_NAME     U6012 BM34
 '@T6G_MB_LIB.T6G(SCH_1):PAGE420_I17@PURE_QUANTA.PT5161LRS(CHIPS)':
 'GND39': CDS_PINID='GND39';
NODE_NAME     U6012 BN1
 '@T6G_MB_LIB.T6G(SCH_1):PAGE420_I17@PURE_QUANTA.PT5161LRS(CHIPS)':
 'GND40': CDS_PINID='GND40';
NODE_NAME     U6012 BN35
 '@T6G_MB_LIB.T6G(SCH_1):PAGE420_I17@PURE_QUANTA.PT5161LRS(CHIPS)':
 'GND41': CDS_PINID='GND41';
NODE_NAME     U6012 BV13
 '@T6G_MB_LIB.T6G(SCH_1):PAGE420_I17@PURE_QUANTA.PT5161LRS(CHIPS)':
 'GND42': CDS_PINID='GND42';
NODE_NAME     U6012 BV22
 '@T6G_MB_LIB.T6G(SCH_1):PAGE420_I17@PURE_QUANTA.PT5161LRS(CHIPS)':
 'GND43': CDS_PINID='GND43';
NODE_NAME     U6012 BV32
 '@T6G_MB_LIB.T6G(SCH_1):PAGE420_I17@PURE_QUANTA.PT5161LRS(CHIPS)':
 'GND44': CDS_PINID='GND44';
NODE_NAME     U6012 BV4
 '@T6G_MB_LIB.T6G(SCH_1):PAGE420_I17@PURE_QUANTA.PT5161LRS(CHIPS)':
 'GND45': CDS_PINID='GND45';
NODE_NAME     U6012 BW2
 '@T6G_MB_LIB.T6G(SCH_1):PAGE420_I17@PURE_QUANTA.PT5161LRS(CHIPS)':
 'GND46': CDS_PINID='GND46';
NODE_NAME     U6012 BW34
 '@T6G_MB_LIB.T6G(SCH_1):PAGE420_I17@PURE_QUANTA.PT5161LRS(CHIPS)':
 'GND47': CDS_PINID='GND47';
NODE_NAME     U6012 BY1
 '@T6G_MB_LIB.T6G(SCH_1):PAGE420_I17@PURE_QUANTA.PT5161LRS(CHIPS)':
 'GND48': CDS_PINID='GND48';
NODE_NAME     U6012 BY35
 '@T6G_MB_LIB.T6G(SCH_1):PAGE420_I17@PURE_QUANTA.PT5161LRS(CHIPS)':
 'GND49': CDS_PINID='GND49';
NODE_NAME     U6012 CE13
 '@T6G_MB_LIB.T6G(SCH_1):PAGE420_I17@PURE_QUANTA.PT5161LRS(CHIPS)':
 'GND50': CDS_PINID='GND50';
NODE_NAME     U6012 CE22
 '@T6G_MB_LIB.T6G(SCH_1):PAGE420_I17@PURE_QUANTA.PT5161LRS(CHIPS)':
 'GND51': CDS_PINID='GND51';
NODE_NAME     U6012 CE32
 '@T6G_MB_LIB.T6G(SCH_1):PAGE420_I17@PURE_QUANTA.PT5161LRS(CHIPS)':
 'GND52': CDS_PINID='GND52';
NODE_NAME     U6012 CE4
 '@T6G_MB_LIB.T6G(SCH_1):PAGE420_I17@PURE_QUANTA.PT5161LRS(CHIPS)':
 'GND53': CDS_PINID='GND53';
NODE_NAME     U6012 CF2
 '@T6G_MB_LIB.T6G(SCH_1):PAGE420_I17@PURE_QUANTA.PT5161LRS(CHIPS)':
 'GND54': CDS_PINID='GND54';
NODE_NAME     U6012 CF34
 '@T6G_MB_LIB.T6G(SCH_1):PAGE420_I17@PURE_QUANTA.PT5161LRS(CHIPS)':
 'GND55': CDS_PINID='GND55';
NODE_NAME     U6012 CG1
 '@T6G_MB_LIB.T6G(SCH_1):PAGE420_I17@PURE_QUANTA.PT5161LRS(CHIPS)':
 'GND56': CDS_PINID='GND56';
NODE_NAME     U6012 CG35
 '@T6G_MB_LIB.T6G(SCH_1):PAGE420_I17@PURE_QUANTA.PT5161LRS(CHIPS)':
 'GND57': CDS_PINID='GND57';
NODE_NAME     U6012 CM13
 '@T6G_MB_LIB.T6G(SCH_1):PAGE420_I17@PURE_QUANTA.PT5161LRS(CHIPS)':
 'GND58': CDS_PINID='GND58';
NODE_NAME     U6012 CM22
 '@T6G_MB_LIB.T6G(SCH_1):PAGE420_I17@PURE_QUANTA.PT5161LRS(CHIPS)':
 'GND59': CDS_PINID='GND59';
NODE_NAME     U6012 CM32
 '@T6G_MB_LIB.T6G(SCH_1):PAGE420_I17@PURE_QUANTA.PT5161LRS(CHIPS)':
 'GND60': CDS_PINID='GND60';
NODE_NAME     U6012 CM4
 '@T6G_MB_LIB.T6G(SCH_1):PAGE420_I17@PURE_QUANTA.PT5161LRS(CHIPS)':
 'GND61': CDS_PINID='GND61';
NODE_NAME     U6012 CN2
 '@T6G_MB_LIB.T6G(SCH_1):PAGE420_I17@PURE_QUANTA.PT5161LRS(CHIPS)':
 'GND62': CDS_PINID='GND62';
NODE_NAME     U6012 CN34
 '@T6G_MB_LIB.T6G(SCH_1):PAGE420_I17@PURE_QUANTA.PT5161LRS(CHIPS)':
 'GND63': CDS_PINID='GND63';
NODE_NAME     U6012 CP1
 '@T6G_MB_LIB.T6G(SCH_1):PAGE420_I17@PURE_QUANTA.PT5161LRS(CHIPS)':
 'GND64': CDS_PINID='GND64';
NODE_NAME     U6012 CP35
 '@T6G_MB_LIB.T6G(SCH_1):PAGE420_I17@PURE_QUANTA.PT5161LRS(CHIPS)':
 'GND65': CDS_PINID='GND65';
NODE_NAME     U6012 CW13
 '@T6G_MB_LIB.T6G(SCH_1):PAGE420_I17@PURE_QUANTA.PT5161LRS(CHIPS)':
 'GND66': CDS_PINID='GND66';
NODE_NAME     U6012 CW22
 '@T6G_MB_LIB.T6G(SCH_1):PAGE420_I17@PURE_QUANTA.PT5161LRS(CHIPS)':
 'GND67': CDS_PINID='GND67';
NODE_NAME     U6012 CW32
 '@T6G_MB_LIB.T6G(SCH_1):PAGE420_I17@PURE_QUANTA.PT5161LRS(CHIPS)':
 'GND68': CDS_PINID='GND68';
NODE_NAME     U6012 CW4
 '@T6G_MB_LIB.T6G(SCH_1):PAGE420_I17@PURE_QUANTA.PT5161LRS(CHIPS)':
 'GND69': CDS_PINID='GND69';
NODE_NAME     U6012 CY2
 '@T6G_MB_LIB.T6G(SCH_1):PAGE420_I17@PURE_QUANTA.PT5161LRS(CHIPS)':
 'GND70': CDS_PINID='GND70';
NODE_NAME     U6012 CY34
 '@T6G_MB_LIB.T6G(SCH_1):PAGE420_I17@PURE_QUANTA.PT5161LRS(CHIPS)':
 'GND71': CDS_PINID='GND71';
NODE_NAME     U6012 DA1
 '@T6G_MB_LIB.T6G(SCH_1):PAGE420_I17@PURE_QUANTA.PT5161LRS(CHIPS)':
 'GND72': CDS_PINID='GND72';
NODE_NAME     U6012 DA35
 '@T6G_MB_LIB.T6G(SCH_1):PAGE420_I17@PURE_QUANTA.PT5161LRS(CHIPS)':
 'GND73': CDS_PINID='GND73';
NODE_NAME     U6012 DF13
 '@T6G_MB_LIB.T6G(SCH_1):PAGE420_I17@PURE_QUANTA.PT5161LRS(CHIPS)':
 'GND74': CDS_PINID='GND74';
NODE_NAME     U6012 DF22
 '@T6G_MB_LIB.T6G(SCH_1):PAGE420_I17@PURE_QUANTA.PT5161LRS(CHIPS)':
 'GND75': CDS_PINID='GND75';
NODE_NAME     U6012 DF32
 '@T6G_MB_LIB.T6G(SCH_1):PAGE420_I17@PURE_QUANTA.PT5161LRS(CHIPS)':
 'GND76': CDS_PINID='GND76';
NODE_NAME     U6012 DF4
 '@T6G_MB_LIB.T6G(SCH_1):PAGE420_I17@PURE_QUANTA.PT5161LRS(CHIPS)':
 'GND77': CDS_PINID='GND77';
NODE_NAME     U6012 DG2
 '@T6G_MB_LIB.T6G(SCH_1):PAGE420_I17@PURE_QUANTA.PT5161LRS(CHIPS)':
 'GND78': CDS_PINID='GND78';
NODE_NAME     U6012 DG34
 '@T6G_MB_LIB.T6G(SCH_1):PAGE420_I17@PURE_QUANTA.PT5161LRS(CHIPS)':
 'GND79': CDS_PINID='GND79';
NODE_NAME     U6012 DH1
 '@T6G_MB_LIB.T6G(SCH_1):PAGE420_I17@PURE_QUANTA.PT5161LRS(CHIPS)':
 'GND80': CDS_PINID='GND80';
NODE_NAME     U6012 DH35
 '@T6G_MB_LIB.T6G(SCH_1):PAGE420_I17@PURE_QUANTA.PT5161LRS(CHIPS)':
 'GND81': CDS_PINID='GND81';
NODE_NAME     U6012 DN13
 '@T6G_MB_LIB.T6G(SCH_1):PAGE420_I17@PURE_QUANTA.PT5161LRS(CHIPS)':
 'GND82': CDS_PINID='GND82';
NODE_NAME     U6012 DN22
 '@T6G_MB_LIB.T6G(SCH_1):PAGE420_I17@PURE_QUANTA.PT5161LRS(CHIPS)':
 'GND83': CDS_PINID='GND83';
NODE_NAME     U6012 DN32
 '@T6G_MB_LIB.T6G(SCH_1):PAGE420_I17@PURE_QUANTA.PT5161LRS(CHIPS)':
 'GND84': CDS_PINID='GND84';
NODE_NAME     U6012 DN4
 '@T6G_MB_LIB.T6G(SCH_1):PAGE420_I17@PURE_QUANTA.PT5161LRS(CHIPS)':
 'GND85': CDS_PINID='GND85';
NODE_NAME     U6012 DP2
 '@T6G_MB_LIB.T6G(SCH_1):PAGE420_I17@PURE_QUANTA.PT5161LRS(CHIPS)':
 'GND86': CDS_PINID='GND86';
NODE_NAME     U6012 DP34
 '@T6G_MB_LIB.T6G(SCH_1):PAGE420_I17@PURE_QUANTA.PT5161LRS(CHIPS)':
 'GND87': CDS_PINID='GND87';
NODE_NAME     U6012 DR1
 '@T6G_MB_LIB.T6G(SCH_1):PAGE420_I17@PURE_QUANTA.PT5161LRS(CHIPS)':
 'GND88': CDS_PINID='GND88';
NODE_NAME     U6012 DR35
 '@T6G_MB_LIB.T6G(SCH_1):PAGE420_I17@PURE_QUANTA.PT5161LRS(CHIPS)':
 'GND89': CDS_PINID='GND89';
NODE_NAME     U6012 DY13
 '@T6G_MB_LIB.T6G(SCH_1):PAGE420_I17@PURE_QUANTA.PT5161LRS(CHIPS)':
 'GND90': CDS_PINID='GND90';
NODE_NAME     U6012 DY22
 '@T6G_MB_LIB.T6G(SCH_1):PAGE420_I17@PURE_QUANTA.PT5161LRS(CHIPS)':
 'GND91': CDS_PINID='GND91';
NODE_NAME     U6012 DY32
 '@T6G_MB_LIB.T6G(SCH_1):PAGE420_I17@PURE_QUANTA.PT5161LRS(CHIPS)':
 'GND92': CDS_PINID='GND92';
NODE_NAME     U6012 DY4
 '@T6G_MB_LIB.T6G(SCH_1):PAGE420_I17@PURE_QUANTA.PT5161LRS(CHIPS)':
 'GND93': CDS_PINID='GND93';
NODE_NAME     U6012 E14
 '@T6G_MB_LIB.T6G(SCH_1):PAGE420_I17@PURE_QUANTA.PT5161LRS(CHIPS)':
 'GND94': CDS_PINID='GND94';
NODE_NAME     U6012 E27
 '@T6G_MB_LIB.T6G(SCH_1):PAGE420_I17@PURE_QUANTA.PT5161LRS(CHIPS)':
 'GND95': CDS_PINID='GND95';
NODE_NAME     U6012 E33
 '@T6G_MB_LIB.T6G(SCH_1):PAGE420_I17@PURE_QUANTA.PT5161LRS(CHIPS)':
 'GND96': CDS_PINID='GND96';
NODE_NAME     U6012 EA2
 '@T6G_MB_LIB.T6G(SCH_1):PAGE420_I17@PURE_QUANTA.PT5161LRS(CHIPS)':
 'GND97': CDS_PINID='GND97';
NODE_NAME     U6012 EA34
 '@T6G_MB_LIB.T6G(SCH_1):PAGE420_I17@PURE_QUANTA.PT5161LRS(CHIPS)':
 'GND98': CDS_PINID='GND98';
NODE_NAME     U6012 EB1
 '@T6G_MB_LIB.T6G(SCH_1):PAGE420_I17@PURE_QUANTA.PT5161LRS(CHIPS)':
 'GND99': CDS_PINID='GND99';
NODE_NAME     U6012 EB35
 '@T6G_MB_LIB.T6G(SCH_1):PAGE420_I17@PURE_QUANTA.PT5161LRS(CHIPS)':
 'GND100': CDS_PINID='GND100';
NODE_NAME     U6012 EG13
 '@T6G_MB_LIB.T6G(SCH_1):PAGE420_I17@PURE_QUANTA.PT5161LRS(CHIPS)':
 'GND101': CDS_PINID='GND101';
NODE_NAME     U6012 EG22
 '@T6G_MB_LIB.T6G(SCH_1):PAGE420_I17@PURE_QUANTA.PT5161LRS(CHIPS)':
 'GND102': CDS_PINID='GND102';
NODE_NAME     U6012 EG32
 '@T6G_MB_LIB.T6G(SCH_1):PAGE420_I17@PURE_QUANTA.PT5161LRS(CHIPS)':
 'GND103': CDS_PINID='GND103';
NODE_NAME     U6012 EG4
 '@T6G_MB_LIB.T6G(SCH_1):PAGE420_I17@PURE_QUANTA.PT5161LRS(CHIPS)':
 'GND104': CDS_PINID='GND104';
NODE_NAME     U6012 EH2
 '@T6G_MB_LIB.T6G(SCH_1):PAGE420_I17@PURE_QUANTA.PT5161LRS(CHIPS)':
 'GND105': CDS_PINID='GND105';
NODE_NAME     U6012 EH34
 '@T6G_MB_LIB.T6G(SCH_1):PAGE420_I17@PURE_QUANTA.PT5161LRS(CHIPS)':
 'GND106': CDS_PINID='GND106';
NODE_NAME     U6012 EJ1
 '@T6G_MB_LIB.T6G(SCH_1):PAGE420_I17@PURE_QUANTA.PT5161LRS(CHIPS)':
 'GND107': CDS_PINID='GND107';
NODE_NAME     U6012 EJ35
 '@T6G_MB_LIB.T6G(SCH_1):PAGE420_I17@PURE_QUANTA.PT5161LRS(CHIPS)':
 'GND108': CDS_PINID='GND108';
NODE_NAME     U6012 EP13
 '@T6G_MB_LIB.T6G(SCH_1):PAGE420_I17@PURE_QUANTA.PT5161LRS(CHIPS)':
 'GND109': CDS_PINID='GND109';
NODE_NAME     U6012 EP22
 '@T6G_MB_LIB.T6G(SCH_1):PAGE420_I17@PURE_QUANTA.PT5161LRS(CHIPS)':
 'GND110': CDS_PINID='GND110';
NODE_NAME     U6012 EP32
 '@T6G_MB_LIB.T6G(SCH_1):PAGE420_I17@PURE_QUANTA.PT5161LRS(CHIPS)':
 'GND111': CDS_PINID='GND111';
NODE_NAME     U6012 EP4
 '@T6G_MB_LIB.T6G(SCH_1):PAGE420_I17@PURE_QUANTA.PT5161LRS(CHIPS)':
 'GND112': CDS_PINID='GND112';
NODE_NAME     U6012 ER2
 '@T6G_MB_LIB.T6G(SCH_1):PAGE420_I17@PURE_QUANTA.PT5161LRS(CHIPS)':
 'GND113': CDS_PINID='GND113';
NODE_NAME     U6012 ER34
 '@T6G_MB_LIB.T6G(SCH_1):PAGE420_I17@PURE_QUANTA.PT5161LRS(CHIPS)':
 'GND114': CDS_PINID='GND114';
NODE_NAME     U6012 ET1
 '@T6G_MB_LIB.T6G(SCH_1):PAGE420_I17@PURE_QUANTA.PT5161LRS(CHIPS)':
 'GND115': CDS_PINID='GND115';
NODE_NAME     U6012 ET35
 '@T6G_MB_LIB.T6G(SCH_1):PAGE420_I17@PURE_QUANTA.PT5161LRS(CHIPS)':
 'GND116': CDS_PINID='GND116';
NODE_NAME     U6012 FA15
 '@T6G_MB_LIB.T6G(SCH_1):PAGE420_I17@PURE_QUANTA.PT5161LRS(CHIPS)':
 'GND117': CDS_PINID='GND117';
NODE_NAME     U6012 FA32
 '@T6G_MB_LIB.T6G(SCH_1):PAGE420_I17@PURE_QUANTA.PT5161LRS(CHIPS)':
 'GND118': CDS_PINID='GND118';
NODE_NAME     U6012 FB2
 '@T6G_MB_LIB.T6G(SCH_1):PAGE420_I17@PURE_QUANTA.PT5161LRS(CHIPS)':
 'GND119': CDS_PINID='GND119';
NODE_NAME     U6012 FB34
 '@T6G_MB_LIB.T6G(SCH_1):PAGE420_I17@PURE_QUANTA.PT5161LRS(CHIPS)':
 'GND120': CDS_PINID='GND120';
NODE_NAME     U6012 FC19
 '@T6G_MB_LIB.T6G(SCH_1):PAGE420_I17@PURE_QUANTA.PT5161LRS(CHIPS)':
 'GND121': CDS_PINID='GND121';
NODE_NAME     U6012 FC23
 '@T6G_MB_LIB.T6G(SCH_1):PAGE420_I17@PURE_QUANTA.PT5161LRS(CHIPS)':
 'GND122': CDS_PINID='GND122';
NODE_NAME     U6012 FC25
 '@T6G_MB_LIB.T6G(SCH_1):PAGE420_I17@PURE_QUANTA.PT5161LRS(CHIPS)':
 'GND123': CDS_PINID='GND123';
NODE_NAME     U6012 FC28
 '@T6G_MB_LIB.T6G(SCH_1):PAGE420_I17@PURE_QUANTA.PT5161LRS(CHIPS)':
 'GND124': CDS_PINID='GND124';
NODE_NAME     U6012 FC3
 '@T6G_MB_LIB.T6G(SCH_1):PAGE420_I17@PURE_QUANTA.PT5161LRS(CHIPS)':
 'GND125': CDS_PINID='GND125';
NODE_NAME     U6012 FC6
 '@T6G_MB_LIB.T6G(SCH_1):PAGE420_I17@PURE_QUANTA.PT5161LRS(CHIPS)':
 'GND126': CDS_PINID='GND126';
NODE_NAME     U6012 FC9
 '@T6G_MB_LIB.T6G(SCH_1):PAGE420_I17@PURE_QUANTA.PT5161LRS(CHIPS)':
 'GND127': CDS_PINID='GND127';
NODE_NAME     U6012 FD1
 '@T6G_MB_LIB.T6G(SCH_1):PAGE420_I17@PURE_QUANTA.PT5161LRS(CHIPS)':
 'GND128': CDS_PINID='GND128';
NODE_NAME     U6012 FD35
 '@T6G_MB_LIB.T6G(SCH_1):PAGE420_I17@PURE_QUANTA.PT5161LRS(CHIPS)':
 'GND129': CDS_PINID='GND129';
NODE_NAME     U6012 FF14
 '@T6G_MB_LIB.T6G(SCH_1):PAGE420_I17@PURE_QUANTA.PT5161LRS(CHIPS)':
 'GND130': CDS_PINID='GND130';
NODE_NAME     U6012 FF21
 '@T6G_MB_LIB.T6G(SCH_1):PAGE420_I17@PURE_QUANTA.PT5161LRS(CHIPS)':
 'GND131': CDS_PINID='GND131';
NODE_NAME     U6012 FJ12
 '@T6G_MB_LIB.T6G(SCH_1):PAGE420_I17@PURE_QUANTA.PT5161LRS(CHIPS)':
 'GND132': CDS_PINID='GND132';
NODE_NAME     U6012 FJ19
 '@T6G_MB_LIB.T6G(SCH_1):PAGE420_I17@PURE_QUANTA.PT5161LRS(CHIPS)':
 'GND133': CDS_PINID='GND133';
NODE_NAME     U6012 H12
 '@T6G_MB_LIB.T6G(SCH_1):PAGE420_I17@PURE_QUANTA.PT5161LRS(CHIPS)':
 'GND134': CDS_PINID='GND134';
NODE_NAME     U6012 H16
 '@T6G_MB_LIB.T6G(SCH_1):PAGE420_I17@PURE_QUANTA.PT5161LRS(CHIPS)':
 'GND135': CDS_PINID='GND135';
NODE_NAME     U6012 H19
 '@T6G_MB_LIB.T6G(SCH_1):PAGE420_I17@PURE_QUANTA.PT5161LRS(CHIPS)':
 'GND136': CDS_PINID='GND136';
NODE_NAME     U6012 H31
 '@T6G_MB_LIB.T6G(SCH_1):PAGE420_I17@PURE_QUANTA.PT5161LRS(CHIPS)':
 'GND137': CDS_PINID='GND137';
NODE_NAME     U6012 J22
 '@T6G_MB_LIB.T6G(SCH_1):PAGE420_I17@PURE_QUANTA.PT5161LRS(CHIPS)':
 'GND138': CDS_PINID='GND138';
NODE_NAME     U6012 J4
 '@T6G_MB_LIB.T6G(SCH_1):PAGE420_I17@PURE_QUANTA.PT5161LRS(CHIPS)':
 'GND139': CDS_PINID='GND139';
NODE_NAME     U6012 K2
 '@T6G_MB_LIB.T6G(SCH_1):PAGE420_I17@PURE_QUANTA.PT5161LRS(CHIPS)':
 'GND140': CDS_PINID='GND140';
NODE_NAME     U6012 K34
 '@T6G_MB_LIB.T6G(SCH_1):PAGE420_I17@PURE_QUANTA.PT5161LRS(CHIPS)':
 'GND141': CDS_PINID='GND141';
NODE_NAME     U6012 L1
 '@T6G_MB_LIB.T6G(SCH_1):PAGE420_I17@PURE_QUANTA.PT5161LRS(CHIPS)':
 'GND142': CDS_PINID='GND142';
NODE_NAME     U6012 L35
 '@T6G_MB_LIB.T6G(SCH_1):PAGE420_I17@PURE_QUANTA.PT5161LRS(CHIPS)':
 'GND143': CDS_PINID='GND143';
NODE_NAME     U6012 T13
 '@T6G_MB_LIB.T6G(SCH_1):PAGE420_I17@PURE_QUANTA.PT5161LRS(CHIPS)':
 'GND144': CDS_PINID='GND144';
NODE_NAME     U6012 T22
 '@T6G_MB_LIB.T6G(SCH_1):PAGE420_I17@PURE_QUANTA.PT5161LRS(CHIPS)':
 'GND145': CDS_PINID='GND145';
NODE_NAME     U6012 T32
 '@T6G_MB_LIB.T6G(SCH_1):PAGE420_I17@PURE_QUANTA.PT5161LRS(CHIPS)':
 'GND146': CDS_PINID='GND146';
NODE_NAME     U6012 T4
 '@T6G_MB_LIB.T6G(SCH_1):PAGE420_I17@PURE_QUANTA.PT5161LRS(CHIPS)':
 'GND147': CDS_PINID='GND147';
NODE_NAME     U6012 U2
 '@T6G_MB_LIB.T6G(SCH_1):PAGE420_I17@PURE_QUANTA.PT5161LRS(CHIPS)':
 'GND148': CDS_PINID='GND148';
NODE_NAME     U6012 U34
 '@T6G_MB_LIB.T6G(SCH_1):PAGE420_I17@PURE_QUANTA.PT5161LRS(CHIPS)':
 'GND149': CDS_PINID='GND149';
NODE_NAME     U6012 V1
 '@T6G_MB_LIB.T6G(SCH_1):PAGE420_I17@PURE_QUANTA.PT5161LRS(CHIPS)':
 'GND150': CDS_PINID='GND150';
NODE_NAME     U6012 V35
 '@T6G_MB_LIB.T6G(SCH_1):PAGE420_I17@PURE_QUANTA.PT5161LRS(CHIPS)':
 'GND151': CDS_PINID='GND151';
NODE_NAME     R1085 2
 '@T6G_MB_LIB.T6G(SCH_1):PAGE421_I18@PURE_QUANTA.Q_RES(CHIPS)':
 'B': CDS_PINID='B';
NODE_NAME     C989 2
 '@T6G_MB_LIB.T6G(SCH_1):PAGE421_I23@PURE_QUANTA.Q_CAP(CHIPS)':
 'B': CDS_PINID='B';
NODE_NAME     C666 2
 '@T6G_MB_LIB.T6G(SCH_1):PAGE422_I6@PURE_QUANTA.Q_CAP(CHIPS)':
 'B': CDS_PINID='B';
NODE_NAME     C668 2
 '@T6G_MB_LIB.T6G(SCH_1):PAGE422_I7@PURE_QUANTA.Q_CAP(CHIPS)':
 'B': CDS_PINID='B';
NODE_NAME     C676 2
 '@T6G_MB_LIB.T6G(SCH_1):PAGE422_I9@PURE_QUANTA.Q_CAP(CHIPS)':
 'B': CDS_PINID='B';
NODE_NAME     C775 2
 '@T6G_MB_LIB.T6G(SCH_1):PAGE422_I10@PURE_QUANTA.Q_CAP(CHIPS)':
 'B': CDS_PINID='B';
NODE_NAME     C671 2
 '@T6G_MB_LIB.T6G(SCH_1):PAGE422_I12@PURE_QUANTA.Q_CAP(CHIPS)':
 'B': CDS_PINID='B';
NODE_NAME     C670 2
 '@T6G_MB_LIB.T6G(SCH_1):PAGE422_I13@PURE_QUANTA.Q_CAP(CHIPS)':
 'B': CDS_PINID='B';
NODE_NAME     C673 2
 '@T6G_MB_LIB.T6G(SCH_1):PAGE422_I15@PURE_QUANTA.Q_CAP(CHIPS)':
 'B': CDS_PINID='B';
NODE_NAME     C677 2
 '@T6G_MB_LIB.T6G(SCH_1):PAGE422_I16@PURE_QUANTA.Q_CAP(CHIPS)':
 'B': CDS_PINID='B';
NODE_NAME     C774 2
 '@T6G_MB_LIB.T6G(SCH_1):PAGE422_I17@PURE_QUANTA.Q_CAP(CHIPS)':
 'B': CDS_PINID='B';
NODE_NAME     C776 2
 '@T6G_MB_LIB.T6G(SCH_1):PAGE422_I18@PURE_QUANTA.Q_CAP(CHIPS)':
 'B': CDS_PINID='B';
NODE_NAME     C777 2
 '@T6G_MB_LIB.T6G(SCH_1):PAGE422_I19@PURE_QUANTA.Q_CAP(CHIPS)':
 'B': CDS_PINID='B';
NODE_NAME     C778 2
 '@T6G_MB_LIB.T6G(SCH_1):PAGE422_I20@PURE_QUANTA.Q_CAP(CHIPS)':
 'B': CDS_PINID='B';
NODE_NAME     C665 2
 '@T6G_MB_LIB.T6G(SCH_1):PAGE422_I25@PURE_QUANTA.Q_CAP(CHIPS)':
 'B': CDS_PINID='B';
NODE_NAME     C669 2
 '@T6G_MB_LIB.T6G(SCH_1):PAGE422_I26@PURE_QUANTA.Q_CAP(CHIPS)':
 'B': CDS_PINID='B';
NODE_NAME     C667 2
 '@T6G_MB_LIB.T6G(SCH_1):PAGE422_I27@PURE_QUANTA.Q_CAP(CHIPS)':
 'B': CDS_PINID='B';
NODE_NAME     C672 2
 '@T6G_MB_LIB.T6G(SCH_1):PAGE422_I29@PURE_QUANTA.Q_CAP(CHIPS)':
 'B': CDS_PINID='B';
NODE_NAME     C982 2
 '@T6G_MB_LIB.T6G(SCH_1):PAGE422_I34@PURE_QUANTA.Q_CAP(CHIPS)':
 'B': CDS_PINID='B';
NODE_NAME     C984 2
 '@T6G_MB_LIB.T6G(SCH_1):PAGE422_I35@PURE_QUANTA.Q_CAP(CHIPS)':
 'B': CDS_PINID='B';
NODE_NAME     C791 2
 '@T6G_MB_LIB.T6G(SCH_1):PAGE422_I36@PURE_QUANTA.Q_CAP(CHIPS)':
 'B': CDS_PINID='B';
NODE_NAME     C794 2
 '@T6G_MB_LIB.T6G(SCH_1):PAGE422_I39@PURE_QUANTA.Q_CAP(CHIPS)':
 'B': CDS_PINID='B';
NODE_NAME     C790 2
 '@T6G_MB_LIB.T6G(SCH_1):PAGE422_I40@PURE_QUANTA.Q_CAP(CHIPS)':
 'B': CDS_PINID='B';
NODE_NAME     C987 2
 '@T6G_MB_LIB.T6G(SCH_1):PAGE422_I41@PURE_QUANTA.Q_CAP(CHIPS)':
 'B': CDS_PINID='B';
NODE_NAME     C800 2
 '@T6G_MB_LIB.T6G(SCH_1):PAGE422_I42@PURE_QUANTA.Q_CAP(CHIPS)':
 'B': CDS_PINID='B';
NODE_NAME     C784 2
 '@T6G_MB_LIB.T6G(SCH_1):PAGE422_I43@PURE_QUANTA.Q_CAP(CHIPS)':
 'B': CDS_PINID='B';
NODE_NAME     C797 2
 '@T6G_MB_LIB.T6G(SCH_1):PAGE422_I44@PURE_QUANTA.Q_CAP(CHIPS)':
 'B': CDS_PINID='B';
NODE_NAME     C781 2
 '@T6G_MB_LIB.T6G(SCH_1):PAGE422_I45@PURE_QUANTA.Q_CAP(CHIPS)':
 'B': CDS_PINID='B';
NODE_NAME     C788 2
 '@T6G_MB_LIB.T6G(SCH_1):PAGE422_I46@PURE_QUANTA.Q_CAP(CHIPS)':
 'B': CDS_PINID='B';
NODE_NAME     C796 2
 '@T6G_MB_LIB.T6G(SCH_1):PAGE422_I47@PURE_QUANTA.Q_CAP(CHIPS)':
 'B': CDS_PINID='B';
NODE_NAME     C795 2
 '@T6G_MB_LIB.T6G(SCH_1):PAGE422_I48@PURE_QUANTA.Q_CAP(CHIPS)':
 'B': CDS_PINID='B';
NODE_NAME     C981 2
 '@T6G_MB_LIB.T6G(SCH_1):PAGE422_I49@PURE_QUANTA.Q_CAP(CHIPS)':
 'B': CDS_PINID='B';
NODE_NAME     C798 2
 '@T6G_MB_LIB.T6G(SCH_1):PAGE422_I50@PURE_QUANTA.Q_CAP(CHIPS)':
 'B': CDS_PINID='B';
NODE_NAME     C802 2
 '@T6G_MB_LIB.T6G(SCH_1):PAGE422_I51@PURE_QUANTA.Q_CAP(CHIPS)':
 'B': CDS_PINID='B';
NODE_NAME     C792 2
 '@T6G_MB_LIB.T6G(SCH_1):PAGE422_I52@PURE_QUANTA.Q_CAP(CHIPS)':
 'B': CDS_PINID='B';
NODE_NAME     C975 2
 '@T6G_MB_LIB.T6G(SCH_1):PAGE422_I54@PURE_QUANTA.Q_CAP(CHIPS)':
 'B': CDS_PINID='B';
NODE_NAME     C979 2
 '@T6G_MB_LIB.T6G(SCH_1):PAGE422_I55@PURE_QUANTA.Q_CAP(CHIPS)':
 'B': CDS_PINID='B';
NODE_NAME     C967 2
 '@T6G_MB_LIB.T6G(SCH_1):PAGE422_I56@PURE_QUANTA.Q_CAP(CHIPS)':
 'B': CDS_PINID='B';
NODE_NAME     C970 2
 '@T6G_MB_LIB.T6G(SCH_1):PAGE422_I57@PURE_QUANTA.Q_CAP(CHIPS)':
 'B': CDS_PINID='B';
NODE_NAME     C966 2
 '@T6G_MB_LIB.T6G(SCH_1):PAGE422_I58@PURE_QUANTA.Q_CAP(CHIPS)':
 'B': CDS_PINID='B';
NODE_NAME     C969 2
 '@T6G_MB_LIB.T6G(SCH_1):PAGE422_I59@PURE_QUANTA.Q_CAP(CHIPS)':
 'B': CDS_PINID='B';
NODE_NAME     C977 2
 '@T6G_MB_LIB.T6G(SCH_1):PAGE422_I60@PURE_QUANTA.Q_CAP(CHIPS)':
 'B': CDS_PINID='B';
NODE_NAME     C978 2
 '@T6G_MB_LIB.T6G(SCH_1):PAGE422_I61@PURE_QUANTA.Q_CAP(CHIPS)':
 'B': CDS_PINID='B';
NODE_NAME     C783 2
 '@T6G_MB_LIB.T6G(SCH_1):PAGE422_I62@PURE_QUANTA.Q_CAP(CHIPS)':
 'B': CDS_PINID='B';
NODE_NAME     C988 2
 '@T6G_MB_LIB.T6G(SCH_1):PAGE422_I63@PURE_QUANTA.Q_CAP(CHIPS)':
 'B': CDS_PINID='B';
NODE_NAME     C974 2
 '@T6G_MB_LIB.T6G(SCH_1):PAGE422_I64@PURE_QUANTA.Q_CAP(CHIPS)':
 'B': CDS_PINID='B';
NODE_NAME     C799 2
 '@T6G_MB_LIB.T6G(SCH_1):PAGE422_I65@PURE_QUANTA.Q_CAP(CHIPS)':
 'B': CDS_PINID='B';
NODE_NAME     C983 2
 '@T6G_MB_LIB.T6G(SCH_1):PAGE422_I66@PURE_QUANTA.Q_CAP(CHIPS)':
 'B': CDS_PINID='B';
NODE_NAME     C804 2
 '@T6G_MB_LIB.T6G(SCH_1):PAGE422_I68@PURE_QUANTA.Q_CAP(CHIPS)':
 'B': CDS_PINID='B';
NODE_NAME     C968 2
 '@T6G_MB_LIB.T6G(SCH_1):PAGE422_I69@PURE_QUANTA.Q_CAP(CHIPS)':
 'B': CDS_PINID='B';
NODE_NAME     C786 2
 '@T6G_MB_LIB.T6G(SCH_1):PAGE422_I72@PURE_QUANTA.Q_CAP(CHIPS)':
 'B': CDS_PINID='B';
NODE_NAME     C779 2
 '@T6G_MB_LIB.T6G(SCH_1):PAGE422_I73@PURE_QUANTA.Q_CAP(CHIPS)':
 'B': CDS_PINID='B';
NODE_NAME     C986 2
 '@T6G_MB_LIB.T6G(SCH_1):PAGE422_I74@PURE_QUANTA.Q_CAP(CHIPS)':
 'B': CDS_PINID='B';
NODE_NAME     C973 2
 '@T6G_MB_LIB.T6G(SCH_1):PAGE422_I75@PURE_QUANTA.Q_CAP(CHIPS)':
 'B': CDS_PINID='B';
NODE_NAME     C801 2
 '@T6G_MB_LIB.T6G(SCH_1):PAGE422_I77@PURE_QUANTA.Q_CAP(CHIPS)':
 'B': CDS_PINID='B';
NODE_NAME     C805 2
 '@T6G_MB_LIB.T6G(SCH_1):PAGE422_I78@PURE_QUANTA.Q_CAP(CHIPS)':
 'B': CDS_PINID='B';
NODE_NAME     C971 2
 '@T6G_MB_LIB.T6G(SCH_1):PAGE422_I79@PURE_QUANTA.Q_CAP(CHIPS)':
 'B': CDS_PINID='B';
NODE_NAME     C976 2
 '@T6G_MB_LIB.T6G(SCH_1):PAGE422_I80@PURE_QUANTA.Q_CAP(CHIPS)':
 'B': CDS_PINID='B';
NODE_NAME     C980 2
 '@T6G_MB_LIB.T6G(SCH_1):PAGE422_I81@PURE_QUANTA.Q_CAP(CHIPS)':
 'B': CDS_PINID='B';
NODE_NAME     C780 2
 '@T6G_MB_LIB.T6G(SCH_1):PAGE422_I82@PURE_QUANTA.Q_CAP(CHIPS)':
 'B': CDS_PINID='B';
NODE_NAME     C782 2
 '@T6G_MB_LIB.T6G(SCH_1):PAGE422_I83@PURE_QUANTA.Q_CAP(CHIPS)':
 'B': CDS_PINID='B';
NODE_NAME     C785 2
 '@T6G_MB_LIB.T6G(SCH_1):PAGE422_I84@PURE_QUANTA.Q_CAP(CHIPS)':
 'B': CDS_PINID='B';
NODE_NAME     C789 2
 '@T6G_MB_LIB.T6G(SCH_1):PAGE422_I86@PURE_QUANTA.Q_CAP(CHIPS)':
 'B': CDS_PINID='B';
NODE_NAME     C803 2
 '@T6G_MB_LIB.T6G(SCH_1):PAGE422_I87@PURE_QUANTA.Q_CAP(CHIPS)':
 'B': CDS_PINID='B';
NODE_NAME     R635 2
 '@T6G_MB_LIB.T6G(SCH_1):PAGE430_I18@PURE_QUANTA.Q_RES(CHIPS)':
 'B': CDS_PINID='B';
NODE_NAME     R636 2
 '@T6G_MB_LIB.T6G(SCH_1):PAGE430_I19@PURE_QUANTA.Q_RES(CHIPS)':
 'B': CDS_PINID='B';
NODE_NAME     R1118 2
 '@T6G_MB_LIB.T6G(SCH_1):PAGE430_I36@PURE_QUANTA.Q_RES(CHIPS)':
 'B': CDS_PINID='B';
NODE_NAME     R1120 2
 '@T6G_MB_LIB.T6G(SCH_1):PAGE430_I37@PURE_QUANTA.Q_RES(CHIPS)':
 'B': CDS_PINID='B';
NODE_NAME     R1121 2
 '@T6G_MB_LIB.T6G(SCH_1):PAGE430_I39@PURE_QUANTA.Q_RES(CHIPS)':
 'B': CDS_PINID='B';
NODE_NAME     R1091 2
 '@T6G_MB_LIB.T6G(SCH_1):PAGE430_I50@PURE_QUANTA.Q_RES(CHIPS)':
 'B': CDS_PINID='B';
NODE_NAME     R1098 2
 '@T6G_MB_LIB.T6G(SCH_1):PAGE430_I65@PURE_QUANTA.Q_RES(CHIPS)':
 'B': CDS_PINID='B';
NODE_NAME     R1100 2
 '@T6G_MB_LIB.T6G(SCH_1):PAGE430_I66@PURE_QUANTA.Q_RES(CHIPS)':
 'B': CDS_PINID='B';
NODE_NAME     R1102 2
 '@T6G_MB_LIB.T6G(SCH_1):PAGE430_I69@PURE_QUANTA.Q_RES(CHIPS)':
 'B': CDS_PINID='B';
NODE_NAME     R1103 2
 '@T6G_MB_LIB.T6G(SCH_1):PAGE430_I74@PURE_QUANTA.Q_RES(CHIPS)':
 'B': CDS_PINID='B';
NODE_NAME     R1104 2
 '@T6G_MB_LIB.T6G(SCH_1):PAGE430_I75@PURE_QUANTA.Q_RES(CHIPS)':
 'B': CDS_PINID='B';
NODE_NAME     U6013 E30
 '@T6G_MB_LIB.T6G(SCH_1):PAGE430_I83@PURE_QUANTA.PT5161LRS(CHIPS)':
 'T_SENSE': CDS_PINID='T_SENSE';
NODE_NAME     R1125 2
 '@T6G_MB_LIB.T6G(SCH_1):PAGE431_I13@PURE_QUANTA.Q_RES(CHIPS)':
 'B': CDS_PINID='B';
NODE_NAME     R1126 2
 '@T6G_MB_LIB.T6G(SCH_1):PAGE431_I14@PURE_QUANTA.Q_RES(CHIPS)':
 'B': CDS_PINID='B';
NODE_NAME     U6013 AC13
 '@T6G_MB_LIB.T6G(SCH_1):PAGE431_I17@PURE_QUANTA.PT5161LRS(CHIPS)':
 'GND1': CDS_PINID='GND1';
NODE_NAME     U6013 AC22
 '@T6G_MB_LIB.T6G(SCH_1):PAGE431_I17@PURE_QUANTA.PT5161LRS(CHIPS)':
 'GND2': CDS_PINID='GND2';
NODE_NAME     U6013 AC32
 '@T6G_MB_LIB.T6G(SCH_1):PAGE431_I17@PURE_QUANTA.PT5161LRS(CHIPS)':
 'GND3': CDS_PINID='GND3';
NODE_NAME     U6013 AC4
 '@T6G_MB_LIB.T6G(SCH_1):PAGE431_I17@PURE_QUANTA.PT5161LRS(CHIPS)':
 'GND4': CDS_PINID='GND4';
NODE_NAME     U6013 AD2
 '@T6G_MB_LIB.T6G(SCH_1):PAGE431_I17@PURE_QUANTA.PT5161LRS(CHIPS)':
 'GND5': CDS_PINID='GND5';
NODE_NAME     U6013 AD34
 '@T6G_MB_LIB.T6G(SCH_1):PAGE431_I17@PURE_QUANTA.PT5161LRS(CHIPS)':
 'GND6': CDS_PINID='GND6';
NODE_NAME     U6013 AE1
 '@T6G_MB_LIB.T6G(SCH_1):PAGE431_I17@PURE_QUANTA.PT5161LRS(CHIPS)':
 'GND7': CDS_PINID='GND7';
NODE_NAME     U6013 AE35
 '@T6G_MB_LIB.T6G(SCH_1):PAGE431_I17@PURE_QUANTA.PT5161LRS(CHIPS)':
 'GND8': CDS_PINID='GND8';
NODE_NAME     U6013 AK13
 '@T6G_MB_LIB.T6G(SCH_1):PAGE431_I17@PURE_QUANTA.PT5161LRS(CHIPS)':
 'GND9': CDS_PINID='GND9';
NODE_NAME     U6013 AK22
 '@T6G_MB_LIB.T6G(SCH_1):PAGE431_I17@PURE_QUANTA.PT5161LRS(CHIPS)':
 'GND10': CDS_PINID='GND10';
NODE_NAME     U6013 AK32
 '@T6G_MB_LIB.T6G(SCH_1):PAGE431_I17@PURE_QUANTA.PT5161LRS(CHIPS)':
 'GND11': CDS_PINID='GND11';
NODE_NAME     U6013 AK4
 '@T6G_MB_LIB.T6G(SCH_1):PAGE431_I17@PURE_QUANTA.PT5161LRS(CHIPS)':
 'GND12': CDS_PINID='GND12';
NODE_NAME     U6013 AL2
 '@T6G_MB_LIB.T6G(SCH_1):PAGE431_I17@PURE_QUANTA.PT5161LRS(CHIPS)':
 'GND13': CDS_PINID='GND13';
NODE_NAME     U6013 AL34
 '@T6G_MB_LIB.T6G(SCH_1):PAGE431_I17@PURE_QUANTA.PT5161LRS(CHIPS)':
 'GND14': CDS_PINID='GND14';
NODE_NAME     U6013 AM1
 '@T6G_MB_LIB.T6G(SCH_1):PAGE431_I17@PURE_QUANTA.PT5161LRS(CHIPS)':
 'GND15': CDS_PINID='GND15';
NODE_NAME     U6013 AM35
 '@T6G_MB_LIB.T6G(SCH_1):PAGE431_I17@PURE_QUANTA.PT5161LRS(CHIPS)':
 'GND16': CDS_PINID='GND16';
NODE_NAME     U6013 AU13
 '@T6G_MB_LIB.T6G(SCH_1):PAGE431_I17@PURE_QUANTA.PT5161LRS(CHIPS)':
 'GND17': CDS_PINID='GND17';
NODE_NAME     U6013 AU22
 '@T6G_MB_LIB.T6G(SCH_1):PAGE431_I17@PURE_QUANTA.PT5161LRS(CHIPS)':
 'GND18': CDS_PINID='GND18';
NODE_NAME     U6013 AU32
 '@T6G_MB_LIB.T6G(SCH_1):PAGE431_I17@PURE_QUANTA.PT5161LRS(CHIPS)':
 'GND19': CDS_PINID='GND19';
NODE_NAME     U6013 AU4
 '@T6G_MB_LIB.T6G(SCH_1):PAGE431_I17@PURE_QUANTA.PT5161LRS(CHIPS)':
 'GND20': CDS_PINID='GND20';
NODE_NAME     U6013 AV2
 '@T6G_MB_LIB.T6G(SCH_1):PAGE431_I17@PURE_QUANTA.PT5161LRS(CHIPS)':
 'GND21': CDS_PINID='GND21';
NODE_NAME     U6013 AV34
 '@T6G_MB_LIB.T6G(SCH_1):PAGE431_I17@PURE_QUANTA.PT5161LRS(CHIPS)':
 'GND22': CDS_PINID='GND22';
NODE_NAME     U6013 AW1
 '@T6G_MB_LIB.T6G(SCH_1):PAGE431_I17@PURE_QUANTA.PT5161LRS(CHIPS)':
 'GND23': CDS_PINID='GND23';
NODE_NAME     U6013 AW35
 '@T6G_MB_LIB.T6G(SCH_1):PAGE431_I17@PURE_QUANTA.PT5161LRS(CHIPS)':
 'GND24': CDS_PINID='GND24';
NODE_NAME     U6013 B19
 '@T6G_MB_LIB.T6G(SCH_1):PAGE431_I17@PURE_QUANTA.PT5161LRS(CHIPS)':
 'GND25': CDS_PINID='GND25';
NODE_NAME     U6013 BD13
 '@T6G_MB_LIB.T6G(SCH_1):PAGE431_I17@PURE_QUANTA.PT5161LRS(CHIPS)':
 'GND26': CDS_PINID='GND26';
NODE_NAME     U6013 BD22
 '@T6G_MB_LIB.T6G(SCH_1):PAGE431_I17@PURE_QUANTA.PT5161LRS(CHIPS)':
 'GND27': CDS_PINID='GND27';
NODE_NAME     U6013 BD32
 '@T6G_MB_LIB.T6G(SCH_1):PAGE431_I17@PURE_QUANTA.PT5161LRS(CHIPS)':
 'GND28': CDS_PINID='GND28';
NODE_NAME     U6013 BD4
 '@T6G_MB_LIB.T6G(SCH_1):PAGE431_I17@PURE_QUANTA.PT5161LRS(CHIPS)':
 'GND29': CDS_PINID='GND29';
NODE_NAME     U6013 BE2
 '@T6G_MB_LIB.T6G(SCH_1):PAGE431_I17@PURE_QUANTA.PT5161LRS(CHIPS)':
 'GND30': CDS_PINID='GND30';
NODE_NAME     U6013 BE34
 '@T6G_MB_LIB.T6G(SCH_1):PAGE431_I17@PURE_QUANTA.PT5161LRS(CHIPS)':
 'GND31': CDS_PINID='GND31';
NODE_NAME     U6013 BF1
 '@T6G_MB_LIB.T6G(SCH_1):PAGE431_I17@PURE_QUANTA.PT5161LRS(CHIPS)':
 'GND32': CDS_PINID='GND32';
NODE_NAME     U6013 BF35
 '@T6G_MB_LIB.T6G(SCH_1):PAGE431_I17@PURE_QUANTA.PT5161LRS(CHIPS)':
 'GND33': CDS_PINID='GND33';
NODE_NAME     U6013 BL13
 '@T6G_MB_LIB.T6G(SCH_1):PAGE431_I17@PURE_QUANTA.PT5161LRS(CHIPS)':
 'GND34': CDS_PINID='GND34';
NODE_NAME     U6013 BL22
 '@T6G_MB_LIB.T6G(SCH_1):PAGE431_I17@PURE_QUANTA.PT5161LRS(CHIPS)':
 'GND35': CDS_PINID='GND35';
NODE_NAME     U6013 BL32
 '@T6G_MB_LIB.T6G(SCH_1):PAGE431_I17@PURE_QUANTA.PT5161LRS(CHIPS)':
 'GND36': CDS_PINID='GND36';
NODE_NAME     U6013 BL4
 '@T6G_MB_LIB.T6G(SCH_1):PAGE431_I17@PURE_QUANTA.PT5161LRS(CHIPS)':
 'GND37': CDS_PINID='GND37';
NODE_NAME     U6013 BM2
 '@T6G_MB_LIB.T6G(SCH_1):PAGE431_I17@PURE_QUANTA.PT5161LRS(CHIPS)':
 'GND38': CDS_PINID='GND38';
NODE_NAME     U6013 BM34
 '@T6G_MB_LIB.T6G(SCH_1):PAGE431_I17@PURE_QUANTA.PT5161LRS(CHIPS)':
 'GND39': CDS_PINID='GND39';
NODE_NAME     U6013 BN1
 '@T6G_MB_LIB.T6G(SCH_1):PAGE431_I17@PURE_QUANTA.PT5161LRS(CHIPS)':
 'GND40': CDS_PINID='GND40';
NODE_NAME     U6013 BN35
 '@T6G_MB_LIB.T6G(SCH_1):PAGE431_I17@PURE_QUANTA.PT5161LRS(CHIPS)':
 'GND41': CDS_PINID='GND41';
NODE_NAME     U6013 BV13
 '@T6G_MB_LIB.T6G(SCH_1):PAGE431_I17@PURE_QUANTA.PT5161LRS(CHIPS)':
 'GND42': CDS_PINID='GND42';
NODE_NAME     U6013 BV22
 '@T6G_MB_LIB.T6G(SCH_1):PAGE431_I17@PURE_QUANTA.PT5161LRS(CHIPS)':
 'GND43': CDS_PINID='GND43';
NODE_NAME     U6013 BV32
 '@T6G_MB_LIB.T6G(SCH_1):PAGE431_I17@PURE_QUANTA.PT5161LRS(CHIPS)':
 'GND44': CDS_PINID='GND44';
NODE_NAME     U6013 BV4
 '@T6G_MB_LIB.T6G(SCH_1):PAGE431_I17@PURE_QUANTA.PT5161LRS(CHIPS)':
 'GND45': CDS_PINID='GND45';
NODE_NAME     U6013 BW2
 '@T6G_MB_LIB.T6G(SCH_1):PAGE431_I17@PURE_QUANTA.PT5161LRS(CHIPS)':
 'GND46': CDS_PINID='GND46';
NODE_NAME     U6013 BW34
 '@T6G_MB_LIB.T6G(SCH_1):PAGE431_I17@PURE_QUANTA.PT5161LRS(CHIPS)':
 'GND47': CDS_PINID='GND47';
NODE_NAME     U6013 BY1
 '@T6G_MB_LIB.T6G(SCH_1):PAGE431_I17@PURE_QUANTA.PT5161LRS(CHIPS)':
 'GND48': CDS_PINID='GND48';
NODE_NAME     U6013 BY35
 '@T6G_MB_LIB.T6G(SCH_1):PAGE431_I17@PURE_QUANTA.PT5161LRS(CHIPS)':
 'GND49': CDS_PINID='GND49';
NODE_NAME     U6013 CE13
 '@T6G_MB_LIB.T6G(SCH_1):PAGE431_I17@PURE_QUANTA.PT5161LRS(CHIPS)':
 'GND50': CDS_PINID='GND50';
NODE_NAME     U6013 CE22
 '@T6G_MB_LIB.T6G(SCH_1):PAGE431_I17@PURE_QUANTA.PT5161LRS(CHIPS)':
 'GND51': CDS_PINID='GND51';
NODE_NAME     U6013 CE32
 '@T6G_MB_LIB.T6G(SCH_1):PAGE431_I17@PURE_QUANTA.PT5161LRS(CHIPS)':
 'GND52': CDS_PINID='GND52';
NODE_NAME     U6013 CE4
 '@T6G_MB_LIB.T6G(SCH_1):PAGE431_I17@PURE_QUANTA.PT5161LRS(CHIPS)':
 'GND53': CDS_PINID='GND53';
NODE_NAME     U6013 CF2
 '@T6G_MB_LIB.T6G(SCH_1):PAGE431_I17@PURE_QUANTA.PT5161LRS(CHIPS)':
 'GND54': CDS_PINID='GND54';
NODE_NAME     U6013 CF34
 '@T6G_MB_LIB.T6G(SCH_1):PAGE431_I17@PURE_QUANTA.PT5161LRS(CHIPS)':
 'GND55': CDS_PINID='GND55';
NODE_NAME     U6013 CG1
 '@T6G_MB_LIB.T6G(SCH_1):PAGE431_I17@PURE_QUANTA.PT5161LRS(CHIPS)':
 'GND56': CDS_PINID='GND56';
NODE_NAME     U6013 CG35
 '@T6G_MB_LIB.T6G(SCH_1):PAGE431_I17@PURE_QUANTA.PT5161LRS(CHIPS)':
 'GND57': CDS_PINID='GND57';
NODE_NAME     U6013 CM13
 '@T6G_MB_LIB.T6G(SCH_1):PAGE431_I17@PURE_QUANTA.PT5161LRS(CHIPS)':
 'GND58': CDS_PINID='GND58';
NODE_NAME     U6013 CM22
 '@T6G_MB_LIB.T6G(SCH_1):PAGE431_I17@PURE_QUANTA.PT5161LRS(CHIPS)':
 'GND59': CDS_PINID='GND59';
NODE_NAME     U6013 CM32
 '@T6G_MB_LIB.T6G(SCH_1):PAGE431_I17@PURE_QUANTA.PT5161LRS(CHIPS)':
 'GND60': CDS_PINID='GND60';
NODE_NAME     U6013 CM4
 '@T6G_MB_LIB.T6G(SCH_1):PAGE431_I17@PURE_QUANTA.PT5161LRS(CHIPS)':
 'GND61': CDS_PINID='GND61';
NODE_NAME     U6013 CN2
 '@T6G_MB_LIB.T6G(SCH_1):PAGE431_I17@PURE_QUANTA.PT5161LRS(CHIPS)':
 'GND62': CDS_PINID='GND62';
NODE_NAME     U6013 CN34
 '@T6G_MB_LIB.T6G(SCH_1):PAGE431_I17@PURE_QUANTA.PT5161LRS(CHIPS)':
 'GND63': CDS_PINID='GND63';
NODE_NAME     U6013 CP1
 '@T6G_MB_LIB.T6G(SCH_1):PAGE431_I17@PURE_QUANTA.PT5161LRS(CHIPS)':
 'GND64': CDS_PINID='GND64';
NODE_NAME     U6013 CP35
 '@T6G_MB_LIB.T6G(SCH_1):PAGE431_I17@PURE_QUANTA.PT5161LRS(CHIPS)':
 'GND65': CDS_PINID='GND65';
NODE_NAME     U6013 CW13
 '@T6G_MB_LIB.T6G(SCH_1):PAGE431_I17@PURE_QUANTA.PT5161LRS(CHIPS)':
 'GND66': CDS_PINID='GND66';
NODE_NAME     U6013 CW22
 '@T6G_MB_LIB.T6G(SCH_1):PAGE431_I17@PURE_QUANTA.PT5161LRS(CHIPS)':
 'GND67': CDS_PINID='GND67';
NODE_NAME     U6013 CW32
 '@T6G_MB_LIB.T6G(SCH_1):PAGE431_I17@PURE_QUANTA.PT5161LRS(CHIPS)':
 'GND68': CDS_PINID='GND68';
NODE_NAME     U6013 CW4
 '@T6G_MB_LIB.T6G(SCH_1):PAGE431_I17@PURE_QUANTA.PT5161LRS(CHIPS)':
 'GND69': CDS_PINID='GND69';
NODE_NAME     U6013 CY2
 '@T6G_MB_LIB.T6G(SCH_1):PAGE431_I17@PURE_QUANTA.PT5161LRS(CHIPS)':
 'GND70': CDS_PINID='GND70';
NODE_NAME     U6013 CY34
 '@T6G_MB_LIB.T6G(SCH_1):PAGE431_I17@PURE_QUANTA.PT5161LRS(CHIPS)':
 'GND71': CDS_PINID='GND71';
NODE_NAME     U6013 DA1
 '@T6G_MB_LIB.T6G(SCH_1):PAGE431_I17@PURE_QUANTA.PT5161LRS(CHIPS)':
 'GND72': CDS_PINID='GND72';
NODE_NAME     U6013 DA35
 '@T6G_MB_LIB.T6G(SCH_1):PAGE431_I17@PURE_QUANTA.PT5161LRS(CHIPS)':
 'GND73': CDS_PINID='GND73';
NODE_NAME     U6013 DF13
 '@T6G_MB_LIB.T6G(SCH_1):PAGE431_I17@PURE_QUANTA.PT5161LRS(CHIPS)':
 'GND74': CDS_PINID='GND74';
NODE_NAME     U6013 DF22
 '@T6G_MB_LIB.T6G(SCH_1):PAGE431_I17@PURE_QUANTA.PT5161LRS(CHIPS)':
 'GND75': CDS_PINID='GND75';
NODE_NAME     U6013 DF32
 '@T6G_MB_LIB.T6G(SCH_1):PAGE431_I17@PURE_QUANTA.PT5161LRS(CHIPS)':
 'GND76': CDS_PINID='GND76';
NODE_NAME     U6013 DF4
 '@T6G_MB_LIB.T6G(SCH_1):PAGE431_I17@PURE_QUANTA.PT5161LRS(CHIPS)':
 'GND77': CDS_PINID='GND77';
NODE_NAME     U6013 DG2
 '@T6G_MB_LIB.T6G(SCH_1):PAGE431_I17@PURE_QUANTA.PT5161LRS(CHIPS)':
 'GND78': CDS_PINID='GND78';
NODE_NAME     U6013 DG34
 '@T6G_MB_LIB.T6G(SCH_1):PAGE431_I17@PURE_QUANTA.PT5161LRS(CHIPS)':
 'GND79': CDS_PINID='GND79';
NODE_NAME     U6013 DH1
 '@T6G_MB_LIB.T6G(SCH_1):PAGE431_I17@PURE_QUANTA.PT5161LRS(CHIPS)':
 'GND80': CDS_PINID='GND80';
NODE_NAME     U6013 DH35
 '@T6G_MB_LIB.T6G(SCH_1):PAGE431_I17@PURE_QUANTA.PT5161LRS(CHIPS)':
 'GND81': CDS_PINID='GND81';
NODE_NAME     U6013 DN13
 '@T6G_MB_LIB.T6G(SCH_1):PAGE431_I17@PURE_QUANTA.PT5161LRS(CHIPS)':
 'GND82': CDS_PINID='GND82';
NODE_NAME     U6013 DN22
 '@T6G_MB_LIB.T6G(SCH_1):PAGE431_I17@PURE_QUANTA.PT5161LRS(CHIPS)':
 'GND83': CDS_PINID='GND83';
NODE_NAME     U6013 DN32
 '@T6G_MB_LIB.T6G(SCH_1):PAGE431_I17@PURE_QUANTA.PT5161LRS(CHIPS)':
 'GND84': CDS_PINID='GND84';
NODE_NAME     U6013 DN4
 '@T6G_MB_LIB.T6G(SCH_1):PAGE431_I17@PURE_QUANTA.PT5161LRS(CHIPS)':
 'GND85': CDS_PINID='GND85';
NODE_NAME     U6013 DP2
 '@T6G_MB_LIB.T6G(SCH_1):PAGE431_I17@PURE_QUANTA.PT5161LRS(CHIPS)':
 'GND86': CDS_PINID='GND86';
NODE_NAME     U6013 DP34
 '@T6G_MB_LIB.T6G(SCH_1):PAGE431_I17@PURE_QUANTA.PT5161LRS(CHIPS)':
 'GND87': CDS_PINID='GND87';
NODE_NAME     U6013 DR1
 '@T6G_MB_LIB.T6G(SCH_1):PAGE431_I17@PURE_QUANTA.PT5161LRS(CHIPS)':
 'GND88': CDS_PINID='GND88';
NODE_NAME     U6013 DR35
 '@T6G_MB_LIB.T6G(SCH_1):PAGE431_I17@PURE_QUANTA.PT5161LRS(CHIPS)':
 'GND89': CDS_PINID='GND89';
NODE_NAME     U6013 DY13
 '@T6G_MB_LIB.T6G(SCH_1):PAGE431_I17@PURE_QUANTA.PT5161LRS(CHIPS)':
 'GND90': CDS_PINID='GND90';
NODE_NAME     U6013 DY22
 '@T6G_MB_LIB.T6G(SCH_1):PAGE431_I17@PURE_QUANTA.PT5161LRS(CHIPS)':
 'GND91': CDS_PINID='GND91';
NODE_NAME     U6013 DY32
 '@T6G_MB_LIB.T6G(SCH_1):PAGE431_I17@PURE_QUANTA.PT5161LRS(CHIPS)':
 'GND92': CDS_PINID='GND92';
NODE_NAME     U6013 DY4
 '@T6G_MB_LIB.T6G(SCH_1):PAGE431_I17@PURE_QUANTA.PT5161LRS(CHIPS)':
 'GND93': CDS_PINID='GND93';
NODE_NAME     U6013 E14
 '@T6G_MB_LIB.T6G(SCH_1):PAGE431_I17@PURE_QUANTA.PT5161LRS(CHIPS)':
 'GND94': CDS_PINID='GND94';
NODE_NAME     U6013 E27
 '@T6G_MB_LIB.T6G(SCH_1):PAGE431_I17@PURE_QUANTA.PT5161LRS(CHIPS)':
 'GND95': CDS_PINID='GND95';
NODE_NAME     U6013 E33
 '@T6G_MB_LIB.T6G(SCH_1):PAGE431_I17@PURE_QUANTA.PT5161LRS(CHIPS)':
 'GND96': CDS_PINID='GND96';
NODE_NAME     U6013 EA2
 '@T6G_MB_LIB.T6G(SCH_1):PAGE431_I17@PURE_QUANTA.PT5161LRS(CHIPS)':
 'GND97': CDS_PINID='GND97';
NODE_NAME     U6013 EA34
 '@T6G_MB_LIB.T6G(SCH_1):PAGE431_I17@PURE_QUANTA.PT5161LRS(CHIPS)':
 'GND98': CDS_PINID='GND98';
NODE_NAME     U6013 EB1
 '@T6G_MB_LIB.T6G(SCH_1):PAGE431_I17@PURE_QUANTA.PT5161LRS(CHIPS)':
 'GND99': CDS_PINID='GND99';
NODE_NAME     U6013 EB35
 '@T6G_MB_LIB.T6G(SCH_1):PAGE431_I17@PURE_QUANTA.PT5161LRS(CHIPS)':
 'GND100': CDS_PINID='GND100';
NODE_NAME     U6013 EG13
 '@T6G_MB_LIB.T6G(SCH_1):PAGE431_I17@PURE_QUANTA.PT5161LRS(CHIPS)':
 'GND101': CDS_PINID='GND101';
NODE_NAME     U6013 EG22
 '@T6G_MB_LIB.T6G(SCH_1):PAGE431_I17@PURE_QUANTA.PT5161LRS(CHIPS)':
 'GND102': CDS_PINID='GND102';
NODE_NAME     U6013 EG32
 '@T6G_MB_LIB.T6G(SCH_1):PAGE431_I17@PURE_QUANTA.PT5161LRS(CHIPS)':
 'GND103': CDS_PINID='GND103';
NODE_NAME     U6013 EG4
 '@T6G_MB_LIB.T6G(SCH_1):PAGE431_I17@PURE_QUANTA.PT5161LRS(CHIPS)':
 'GND104': CDS_PINID='GND104';
NODE_NAME     U6013 EH2
 '@T6G_MB_LIB.T6G(SCH_1):PAGE431_I17@PURE_QUANTA.PT5161LRS(CHIPS)':
 'GND105': CDS_PINID='GND105';
NODE_NAME     U6013 EH34
 '@T6G_MB_LIB.T6G(SCH_1):PAGE431_I17@PURE_QUANTA.PT5161LRS(CHIPS)':
 'GND106': CDS_PINID='GND106';
NODE_NAME     U6013 EJ1
 '@T6G_MB_LIB.T6G(SCH_1):PAGE431_I17@PURE_QUANTA.PT5161LRS(CHIPS)':
 'GND107': CDS_PINID='GND107';
NODE_NAME     U6013 EJ35
 '@T6G_MB_LIB.T6G(SCH_1):PAGE431_I17@PURE_QUANTA.PT5161LRS(CHIPS)':
 'GND108': CDS_PINID='GND108';
NODE_NAME     U6013 EP13
 '@T6G_MB_LIB.T6G(SCH_1):PAGE431_I17@PURE_QUANTA.PT5161LRS(CHIPS)':
 'GND109': CDS_PINID='GND109';
NODE_NAME     U6013 EP22
 '@T6G_MB_LIB.T6G(SCH_1):PAGE431_I17@PURE_QUANTA.PT5161LRS(CHIPS)':
 'GND110': CDS_PINID='GND110';
NODE_NAME     U6013 EP32
 '@T6G_MB_LIB.T6G(SCH_1):PAGE431_I17@PURE_QUANTA.PT5161LRS(CHIPS)':
 'GND111': CDS_PINID='GND111';
NODE_NAME     U6013 EP4
 '@T6G_MB_LIB.T6G(SCH_1):PAGE431_I17@PURE_QUANTA.PT5161LRS(CHIPS)':
 'GND112': CDS_PINID='GND112';
NODE_NAME     U6013 ER2
 '@T6G_MB_LIB.T6G(SCH_1):PAGE431_I17@PURE_QUANTA.PT5161LRS(CHIPS)':
 'GND113': CDS_PINID='GND113';
NODE_NAME     U6013 ER34
 '@T6G_MB_LIB.T6G(SCH_1):PAGE431_I17@PURE_QUANTA.PT5161LRS(CHIPS)':
 'GND114': CDS_PINID='GND114';
NODE_NAME     U6013 ET1
 '@T6G_MB_LIB.T6G(SCH_1):PAGE431_I17@PURE_QUANTA.PT5161LRS(CHIPS)':
 'GND115': CDS_PINID='GND115';
NODE_NAME     U6013 ET35
 '@T6G_MB_LIB.T6G(SCH_1):PAGE431_I17@PURE_QUANTA.PT5161LRS(CHIPS)':
 'GND116': CDS_PINID='GND116';
NODE_NAME     U6013 FA15
 '@T6G_MB_LIB.T6G(SCH_1):PAGE431_I17@PURE_QUANTA.PT5161LRS(CHIPS)':
 'GND117': CDS_PINID='GND117';
NODE_NAME     U6013 FA32
 '@T6G_MB_LIB.T6G(SCH_1):PAGE431_I17@PURE_QUANTA.PT5161LRS(CHIPS)':
 'GND118': CDS_PINID='GND118';
NODE_NAME     U6013 FB2
 '@T6G_MB_LIB.T6G(SCH_1):PAGE431_I17@PURE_QUANTA.PT5161LRS(CHIPS)':
 'GND119': CDS_PINID='GND119';
NODE_NAME     U6013 FB34
 '@T6G_MB_LIB.T6G(SCH_1):PAGE431_I17@PURE_QUANTA.PT5161LRS(CHIPS)':
 'GND120': CDS_PINID='GND120';
NODE_NAME     U6013 FC19
 '@T6G_MB_LIB.T6G(SCH_1):PAGE431_I17@PURE_QUANTA.PT5161LRS(CHIPS)':
 'GND121': CDS_PINID='GND121';
NODE_NAME     U6013 FC23
 '@T6G_MB_LIB.T6G(SCH_1):PAGE431_I17@PURE_QUANTA.PT5161LRS(CHIPS)':
 'GND122': CDS_PINID='GND122';
NODE_NAME     U6013 FC25
 '@T6G_MB_LIB.T6G(SCH_1):PAGE431_I17@PURE_QUANTA.PT5161LRS(CHIPS)':
 'GND123': CDS_PINID='GND123';
NODE_NAME     U6013 FC28
 '@T6G_MB_LIB.T6G(SCH_1):PAGE431_I17@PURE_QUANTA.PT5161LRS(CHIPS)':
 'GND124': CDS_PINID='GND124';
NODE_NAME     U6013 FC3
 '@T6G_MB_LIB.T6G(SCH_1):PAGE431_I17@PURE_QUANTA.PT5161LRS(CHIPS)':
 'GND125': CDS_PINID='GND125';
NODE_NAME     U6013 FC6
 '@T6G_MB_LIB.T6G(SCH_1):PAGE431_I17@PURE_QUANTA.PT5161LRS(CHIPS)':
 'GND126': CDS_PINID='GND126';
NODE_NAME     U6013 FC9
 '@T6G_MB_LIB.T6G(SCH_1):PAGE431_I17@PURE_QUANTA.PT5161LRS(CHIPS)':
 'GND127': CDS_PINID='GND127';
NODE_NAME     U6013 FD1
 '@T6G_MB_LIB.T6G(SCH_1):PAGE431_I17@PURE_QUANTA.PT5161LRS(CHIPS)':
 'GND128': CDS_PINID='GND128';
NODE_NAME     U6013 FD35
 '@T6G_MB_LIB.T6G(SCH_1):PAGE431_I17@PURE_QUANTA.PT5161LRS(CHIPS)':
 'GND129': CDS_PINID='GND129';
NODE_NAME     U6013 FF14
 '@T6G_MB_LIB.T6G(SCH_1):PAGE431_I17@PURE_QUANTA.PT5161LRS(CHIPS)':
 'GND130': CDS_PINID='GND130';
NODE_NAME     U6013 FF21
 '@T6G_MB_LIB.T6G(SCH_1):PAGE431_I17@PURE_QUANTA.PT5161LRS(CHIPS)':
 'GND131': CDS_PINID='GND131';
NODE_NAME     U6013 FJ12
 '@T6G_MB_LIB.T6G(SCH_1):PAGE431_I17@PURE_QUANTA.PT5161LRS(CHIPS)':
 'GND132': CDS_PINID='GND132';
NODE_NAME     U6013 FJ19
 '@T6G_MB_LIB.T6G(SCH_1):PAGE431_I17@PURE_QUANTA.PT5161LRS(CHIPS)':
 'GND133': CDS_PINID='GND133';
NODE_NAME     U6013 H12
 '@T6G_MB_LIB.T6G(SCH_1):PAGE431_I17@PURE_QUANTA.PT5161LRS(CHIPS)':
 'GND134': CDS_PINID='GND134';
NODE_NAME     U6013 H16
 '@T6G_MB_LIB.T6G(SCH_1):PAGE431_I17@PURE_QUANTA.PT5161LRS(CHIPS)':
 'GND135': CDS_PINID='GND135';
NODE_NAME     U6013 H19
 '@T6G_MB_LIB.T6G(SCH_1):PAGE431_I17@PURE_QUANTA.PT5161LRS(CHIPS)':
 'GND136': CDS_PINID='GND136';
NODE_NAME     U6013 H31
 '@T6G_MB_LIB.T6G(SCH_1):PAGE431_I17@PURE_QUANTA.PT5161LRS(CHIPS)':
 'GND137': CDS_PINID='GND137';
NODE_NAME     U6013 J22
 '@T6G_MB_LIB.T6G(SCH_1):PAGE431_I17@PURE_QUANTA.PT5161LRS(CHIPS)':
 'GND138': CDS_PINID='GND138';
NODE_NAME     U6013 J4
 '@T6G_MB_LIB.T6G(SCH_1):PAGE431_I17@PURE_QUANTA.PT5161LRS(CHIPS)':
 'GND139': CDS_PINID='GND139';
NODE_NAME     U6013 K2
 '@T6G_MB_LIB.T6G(SCH_1):PAGE431_I17@PURE_QUANTA.PT5161LRS(CHIPS)':
 'GND140': CDS_PINID='GND140';
NODE_NAME     U6013 K34
 '@T6G_MB_LIB.T6G(SCH_1):PAGE431_I17@PURE_QUANTA.PT5161LRS(CHIPS)':
 'GND141': CDS_PINID='GND141';
NODE_NAME     U6013 L1
 '@T6G_MB_LIB.T6G(SCH_1):PAGE431_I17@PURE_QUANTA.PT5161LRS(CHIPS)':
 'GND142': CDS_PINID='GND142';
NODE_NAME     U6013 L35
 '@T6G_MB_LIB.T6G(SCH_1):PAGE431_I17@PURE_QUANTA.PT5161LRS(CHIPS)':
 'GND143': CDS_PINID='GND143';
NODE_NAME     U6013 T13
 '@T6G_MB_LIB.T6G(SCH_1):PAGE431_I17@PURE_QUANTA.PT5161LRS(CHIPS)':
 'GND144': CDS_PINID='GND144';
NODE_NAME     U6013 T22
 '@T6G_MB_LIB.T6G(SCH_1):PAGE431_I17@PURE_QUANTA.PT5161LRS(CHIPS)':
 'GND145': CDS_PINID='GND145';
NODE_NAME     U6013 T32
 '@T6G_MB_LIB.T6G(SCH_1):PAGE431_I17@PURE_QUANTA.PT5161LRS(CHIPS)':
 'GND146': CDS_PINID='GND146';
NODE_NAME     U6013 T4
 '@T6G_MB_LIB.T6G(SCH_1):PAGE431_I17@PURE_QUANTA.PT5161LRS(CHIPS)':
 'GND147': CDS_PINID='GND147';
NODE_NAME     U6013 U2
 '@T6G_MB_LIB.T6G(SCH_1):PAGE431_I17@PURE_QUANTA.PT5161LRS(CHIPS)':
 'GND148': CDS_PINID='GND148';
NODE_NAME     U6013 U34
 '@T6G_MB_LIB.T6G(SCH_1):PAGE431_I17@PURE_QUANTA.PT5161LRS(CHIPS)':
 'GND149': CDS_PINID='GND149';
NODE_NAME     U6013 V1
 '@T6G_MB_LIB.T6G(SCH_1):PAGE431_I17@PURE_QUANTA.PT5161LRS(CHIPS)':
 'GND150': CDS_PINID='GND150';
NODE_NAME     U6013 V35
 '@T6G_MB_LIB.T6G(SCH_1):PAGE431_I17@PURE_QUANTA.PT5161LRS(CHIPS)':
 'GND151': CDS_PINID='GND151';
NODE_NAME     R1127 2
 '@T6G_MB_LIB.T6G(SCH_1):PAGE432_I18@PURE_QUANTA.Q_RES(CHIPS)':
 'B': CDS_PINID='B';
NODE_NAME     C1057 2
 '@T6G_MB_LIB.T6G(SCH_1):PAGE432_I23@PURE_QUANTA.Q_CAP(CHIPS)':
 'B': CDS_PINID='B';
NODE_NAME     C999 2
 '@T6G_MB_LIB.T6G(SCH_1):PAGE433_I5@PURE_QUANTA.Q_CAP(CHIPS)':
 'B': CDS_PINID='B';
NODE_NAME     C1002 2
 '@T6G_MB_LIB.T6G(SCH_1):PAGE433_I6@PURE_QUANTA.Q_CAP(CHIPS)':
 'B': CDS_PINID='B';
NODE_NAME     C991 2
 '@T6G_MB_LIB.T6G(SCH_1):PAGE433_I12@PURE_QUANTA.Q_CAP(CHIPS)':
 'B': CDS_PINID='B';
NODE_NAME     C993 2
 '@T6G_MB_LIB.T6G(SCH_1):PAGE433_I13@PURE_QUANTA.Q_CAP(CHIPS)':
 'B': CDS_PINID='B';
NODE_NAME     C995 2
 '@T6G_MB_LIB.T6G(SCH_1):PAGE433_I15@PURE_QUANTA.Q_CAP(CHIPS)':
 'B': CDS_PINID='B';
NODE_NAME     C996 2
 '@T6G_MB_LIB.T6G(SCH_1):PAGE433_I16@PURE_QUANTA.Q_CAP(CHIPS)':
 'B': CDS_PINID='B';
NODE_NAME     C998 2
 '@T6G_MB_LIB.T6G(SCH_1):PAGE433_I17@PURE_QUANTA.Q_CAP(CHIPS)':
 'B': CDS_PINID='B';
NODE_NAME     C990 2
 '@T6G_MB_LIB.T6G(SCH_1):PAGE433_I19@PURE_QUANTA.Q_CAP(CHIPS)':
 'B': CDS_PINID='B';
NODE_NAME     C992 2
 '@T6G_MB_LIB.T6G(SCH_1):PAGE433_I20@PURE_QUANTA.Q_CAP(CHIPS)':
 'B': CDS_PINID='B';
NODE_NAME     C994 2
 '@T6G_MB_LIB.T6G(SCH_1):PAGE433_I21@PURE_QUANTA.Q_CAP(CHIPS)':
 'B': CDS_PINID='B';
NODE_NAME     C997 2
 '@T6G_MB_LIB.T6G(SCH_1):PAGE433_I22@PURE_QUANTA.Q_CAP(CHIPS)':
 'B': CDS_PINID='B';
NODE_NAME     C1000 2
 '@T6G_MB_LIB.T6G(SCH_1):PAGE433_I24@PURE_QUANTA.Q_CAP(CHIPS)':
 'B': CDS_PINID='B';
NODE_NAME     C1001 2
 '@T6G_MB_LIB.T6G(SCH_1):PAGE433_I25@PURE_QUANTA.Q_CAP(CHIPS)':
 'B': CDS_PINID='B';
NODE_NAME     C1003 2
 '@T6G_MB_LIB.T6G(SCH_1):PAGE433_I26@PURE_QUANTA.Q_CAP(CHIPS)':
 'B': CDS_PINID='B';
NODE_NAME     C1004 2
 '@T6G_MB_LIB.T6G(SCH_1):PAGE433_I27@PURE_QUANTA.Q_CAP(CHIPS)':
 'B': CDS_PINID='B';
NODE_NAME     C1005 2
 '@T6G_MB_LIB.T6G(SCH_1):PAGE433_I28@PURE_QUANTA.Q_CAP(CHIPS)':
 'B': CDS_PINID='B';
NODE_NAME     C1014 2
 '@T6G_MB_LIB.T6G(SCH_1):PAGE433_I30@PURE_QUANTA.Q_CAP(CHIPS)':
 'B': CDS_PINID='B';
NODE_NAME     C1021 2
 '@T6G_MB_LIB.T6G(SCH_1):PAGE433_I35@PURE_QUANTA.Q_CAP(CHIPS)':
 'B': CDS_PINID='B';
NODE_NAME     C1024 2
 '@T6G_MB_LIB.T6G(SCH_1):PAGE433_I37@PURE_QUANTA.Q_CAP(CHIPS)':
 'B': CDS_PINID='B';
NODE_NAME     C1027 2
 '@T6G_MB_LIB.T6G(SCH_1):PAGE433_I38@PURE_QUANTA.Q_CAP(CHIPS)':
 'B': CDS_PINID='B';
NODE_NAME     C1023 2
 '@T6G_MB_LIB.T6G(SCH_1):PAGE433_I39@PURE_QUANTA.Q_CAP(CHIPS)':
 'B': CDS_PINID='B';
NODE_NAME     C1036 2
 '@T6G_MB_LIB.T6G(SCH_1):PAGE433_I40@PURE_QUANTA.Q_CAP(CHIPS)':
 'B': CDS_PINID='B';
NODE_NAME     C1010 2
 '@T6G_MB_LIB.T6G(SCH_1):PAGE433_I41@PURE_QUANTA.Q_CAP(CHIPS)':
 'B': CDS_PINID='B';
NODE_NAME     C1052 2
 '@T6G_MB_LIB.T6G(SCH_1):PAGE433_I42@PURE_QUANTA.Q_CAP(CHIPS)':
 'B': CDS_PINID='B';
NODE_NAME     C1055 2
 '@T6G_MB_LIB.T6G(SCH_1):PAGE433_I43@PURE_QUANTA.Q_CAP(CHIPS)':
 'B': CDS_PINID='B';
NODE_NAME     C1035 2
 '@T6G_MB_LIB.T6G(SCH_1):PAGE433_I44@PURE_QUANTA.Q_CAP(CHIPS)':
 'B': CDS_PINID='B';
NODE_NAME     C1031 2
 '@T6G_MB_LIB.T6G(SCH_1):PAGE433_I45@PURE_QUANTA.Q_CAP(CHIPS)':
 'B': CDS_PINID='B';
NODE_NAME     C1006 2
 '@T6G_MB_LIB.T6G(SCH_1):PAGE433_I46@PURE_QUANTA.Q_CAP(CHIPS)':
 'B': CDS_PINID='B';
NODE_NAME     C1034 2
 '@T6G_MB_LIB.T6G(SCH_1):PAGE433_I47@PURE_QUANTA.Q_CAP(CHIPS)':
 'B': CDS_PINID='B';
NODE_NAME     C1039 2
 '@T6G_MB_LIB.T6G(SCH_1):PAGE433_I48@PURE_QUANTA.Q_CAP(CHIPS)':
 'B': CDS_PINID='B';
NODE_NAME     C1015 2
 '@T6G_MB_LIB.T6G(SCH_1):PAGE433_I49@PURE_QUANTA.Q_CAP(CHIPS)':
 'B': CDS_PINID='B';
NODE_NAME     C1054 2
 '@T6G_MB_LIB.T6G(SCH_1):PAGE433_I50@PURE_QUANTA.Q_CAP(CHIPS)':
 'B': CDS_PINID='B';
NODE_NAME     C1056 2
 '@T6G_MB_LIB.T6G(SCH_1):PAGE433_I51@PURE_QUANTA.Q_CAP(CHIPS)':
 'B': CDS_PINID='B';
NODE_NAME     C1008 2
 '@T6G_MB_LIB.T6G(SCH_1):PAGE433_I52@PURE_QUANTA.Q_CAP(CHIPS)':
 'B': CDS_PINID='B';
NODE_NAME     C1011 2
 '@T6G_MB_LIB.T6G(SCH_1):PAGE433_I53@PURE_QUANTA.Q_CAP(CHIPS)':
 'B': CDS_PINID='B';
NODE_NAME     C1043 2
 '@T6G_MB_LIB.T6G(SCH_1):PAGE433_I54@PURE_QUANTA.Q_CAP(CHIPS)':
 'B': CDS_PINID='B';
NODE_NAME     C1047 2
 '@T6G_MB_LIB.T6G(SCH_1):PAGE433_I56@PURE_QUANTA.Q_CAP(CHIPS)':
 'B': CDS_PINID='B';
NODE_NAME     C1019 2
 '@T6G_MB_LIB.T6G(SCH_1):PAGE433_I57@PURE_QUANTA.Q_CAP(CHIPS)':
 'B': CDS_PINID='B';
NODE_NAME     C1046 2
 '@T6G_MB_LIB.T6G(SCH_1):PAGE433_I59@PURE_QUANTA.Q_CAP(CHIPS)':
 'B': CDS_PINID='B';
NODE_NAME     C1050 2
 '@T6G_MB_LIB.T6G(SCH_1):PAGE433_I60@PURE_QUANTA.Q_CAP(CHIPS)':
 'B': CDS_PINID='B';
NODE_NAME     C1013 2
 '@T6G_MB_LIB.T6G(SCH_1):PAGE433_I62@PURE_QUANTA.Q_CAP(CHIPS)':
 'B': CDS_PINID='B';
NODE_NAME     C1017 2
 '@T6G_MB_LIB.T6G(SCH_1):PAGE433_I63@PURE_QUANTA.Q_CAP(CHIPS)':
 'B': CDS_PINID='B';
NODE_NAME     C1022 2
 '@T6G_MB_LIB.T6G(SCH_1):PAGE433_I66@PURE_QUANTA.Q_CAP(CHIPS)':
 'B': CDS_PINID='B';
NODE_NAME     C1025 2
 '@T6G_MB_LIB.T6G(SCH_1):PAGE433_I67@PURE_QUANTA.Q_CAP(CHIPS)':
 'B': CDS_PINID='B';
NODE_NAME     C1028 2
 '@T6G_MB_LIB.T6G(SCH_1):PAGE433_I69@PURE_QUANTA.Q_CAP(CHIPS)':
 'B': CDS_PINID='B';
NODE_NAME     C1029 2
 '@T6G_MB_LIB.T6G(SCH_1):PAGE433_I70@PURE_QUANTA.Q_CAP(CHIPS)':
 'B': CDS_PINID='B';
NODE_NAME     C1033 2
 '@T6G_MB_LIB.T6G(SCH_1):PAGE433_I71@PURE_QUANTA.Q_CAP(CHIPS)':
 'B': CDS_PINID='B';
NODE_NAME     C1026 2
 '@T6G_MB_LIB.T6G(SCH_1):PAGE433_I72@PURE_QUANTA.Q_CAP(CHIPS)':
 'B': CDS_PINID='B';
NODE_NAME     C1044 2
 '@T6G_MB_LIB.T6G(SCH_1):PAGE433_I73@PURE_QUANTA.Q_CAP(CHIPS)':
 'B': CDS_PINID='B';
NODE_NAME     C1032 2
 '@T6G_MB_LIB.T6G(SCH_1):PAGE433_I74@PURE_QUANTA.Q_CAP(CHIPS)':
 'B': CDS_PINID='B';
NODE_NAME     C1038 2
 '@T6G_MB_LIB.T6G(SCH_1):PAGE433_I75@PURE_QUANTA.Q_CAP(CHIPS)':
 'B': CDS_PINID='B';
NODE_NAME     C1016 2
 '@T6G_MB_LIB.T6G(SCH_1):PAGE433_I76@PURE_QUANTA.Q_CAP(CHIPS)':
 'B': CDS_PINID='B';
NODE_NAME     C1030 2
 '@T6G_MB_LIB.T6G(SCH_1):PAGE433_I77@PURE_QUANTA.Q_CAP(CHIPS)':
 'B': CDS_PINID='B';
NODE_NAME     C1041 2
 '@T6G_MB_LIB.T6G(SCH_1):PAGE433_I78@PURE_QUANTA.Q_CAP(CHIPS)':
 'B': CDS_PINID='B';
NODE_NAME     C1037 2
 '@T6G_MB_LIB.T6G(SCH_1):PAGE433_I79@PURE_QUANTA.Q_CAP(CHIPS)':
 'B': CDS_PINID='B';
NODE_NAME     C1049 2
 '@T6G_MB_LIB.T6G(SCH_1):PAGE433_I80@PURE_QUANTA.Q_CAP(CHIPS)':
 'B': CDS_PINID='B';
NODE_NAME     C1007 2
 '@T6G_MB_LIB.T6G(SCH_1):PAGE433_I81@PURE_QUANTA.Q_CAP(CHIPS)':
 'B': CDS_PINID='B';
NODE_NAME     C1009 2
 '@T6G_MB_LIB.T6G(SCH_1):PAGE433_I82@PURE_QUANTA.Q_CAP(CHIPS)':
 'B': CDS_PINID='B';
NODE_NAME     C1012 2
 '@T6G_MB_LIB.T6G(SCH_1):PAGE433_I84@PURE_QUANTA.Q_CAP(CHIPS)':
 'B': CDS_PINID='B';
NODE_NAME     C1048 2
 '@T6G_MB_LIB.T6G(SCH_1):PAGE433_I85@PURE_QUANTA.Q_CAP(CHIPS)':
 'B': CDS_PINID='B';
NODE_NAME     C1040 2
 '@T6G_MB_LIB.T6G(SCH_1):PAGE433_I86@PURE_QUANTA.Q_CAP(CHIPS)':
 'B': CDS_PINID='B';
NODE_NAME     C1045 2
 '@T6G_MB_LIB.T6G(SCH_1):PAGE433_I87@PURE_QUANTA.Q_CAP(CHIPS)':
 'B': CDS_PINID='B';
NODE_NAME     PR883 2
 '@T6G_MB_LIB.T6G(SCH_1):PAGE475_I210@PURE_QUANTA.Q_RES(CHIPS)':
 'B': CDS_PINID='B';
NODE_NAME     R9025 2
 '@T6G_MB_LIB.T6G(SCH_1):PAGE84_I106@PURE_QUANTA.Q_RES(CHIPS)':
 'B': CDS_PINID='B';
NODE_NAME     Q9003 1
 '@T6G_MB_LIB.T6G(SCH_1):PAGE84_I111@PURE_QUANTA.MOSFET_NCH_DUAL(CHIPS)':
 'S1': CDS_PINID='S1';
NODE_NAME     C9005 2
 '@T6G_MB_LIB.T6G(SCH_1):PAGE84_I116@PURE_QUANTA.Q_CAP(CHIPS)':
 'B': CDS_PINID='B';
NODE_NAME     Q9003 4
 '@T6G_MB_LIB.T6G(SCH_1):PAGE84_I121@PURE_QUANTA.MOSFET_NCH_DUAL(CHIPS)':
 'S2': CDS_PINID='S2';
NODE_NAME     C2515 2
 '@T6G_MB_LIB.T6G(SCH_1):PAGE70_I25@PURE_QUANTA.Q_CAP(CHIPS)':
 'B': CDS_PINID='B';
NODE_NAME     C2512 2
 '@T6G_MB_LIB.T6G(SCH_1):PAGE70_I26@PURE_QUANTA.Q_CAP(CHIPS)':
 'B': CDS_PINID='B';
NODE_NAME     C2662 2
 '@T6G_MB_LIB.T6G(SCH_1):PAGE74_I25@PURE_QUANTA.Q_CAP(CHIPS)':
 'B': CDS_PINID='B';
NODE_NAME     C2659 2
 '@T6G_MB_LIB.T6G(SCH_1):PAGE74_I26@PURE_QUANTA.Q_CAP(CHIPS)':
 'B': CDS_PINID='B';
NODE_NAME     R3471 2
 '@T6G_MB_LIB.T6G(SCH_1):PAGE299_I187@PURE_QUANTA.Q_RES(CHIPS)':
 'B': CDS_PINID='B';
NODE_NAME     R3472 1
 '@T6G_MB_LIB.T6G(SCH_1):PAGE299_I198@PURE_QUANTA.Q_RES(CHIPS)':
 'A': CDS_PINID='A';
NODE_NAME     Q106 4
 '@T6G_MB_LIB.T6G(SCH_1):PAGE299_I200@PURE_QUANTA.MOSFET_NCH_DUAL(CHIPS)':
 'S2': CDS_PINID='S2';
NODE_NAME     Q106 1
 '@T6G_MB_LIB.T6G(SCH_1):PAGE299_I201@PURE_QUANTA.MOSFET_NCH_DUAL(CHIPS)':
 'S1': CDS_PINID='S1';
NODE_NAME     U9001 3
 '@T6G_MB_LIB.T6G(SCH_1):PAGE340_I25@PURE_QUANTA.74LVC1G08W57(CHIPS)':
 'GND': CDS_PINID='GND';
NODE_NAME     C9007 2
 '@T6G_MB_LIB.T6G(SCH_1):PAGE340_I27@PURE_QUANTA.Q_CAP(CHIPS)':
 'B': CDS_PINID='B';
NODE_NAME     U24 S
 '@T6G_MB_LIB.T6G(SCH_1):PAGE340_I31@PURE_QUANTA.MOSFET_N(CHIPS)':
 'SOURCE': CDS_PINID='SOURCE';
NODE_NAME     U23 3
 '@T6G_MB_LIB.T6G(SCH_1):PAGE340_I36@PURE_QUANTA.74LVC1G08W57(CHIPS)':
 'GND': CDS_PINID='GND';
NODE_NAME     C1059 2
 '@T6G_MB_LIB.T6G(SCH_1):PAGE340_I40@PURE_QUANTA.Q_CAP(CHIPS)':
 'B': CDS_PINID='B';
NODE_NAME     U28 3
 '@T6G_MB_LIB.T6G(SCH_1):PAGE340_I51@PURE_QUANTA.SN74LVC1G07DBVR(CHIPS)':
 'GND': CDS_PINID='GND';
NODE_NAME     C1058 2
 '@T6G_MB_LIB.T6G(SCH_1):PAGE340_I53@PURE_QUANTA.Q_CAP(CHIPS)':
 'B': CDS_PINID='B';
NODE_NAME     R4069 2
 '@T6G_MB_LIB.T6G(SCH_1):PAGE338_I127@PURE_QUANTA.Q_RES(CHIPS)':
 'B': CDS_PINID='B';
NODE_NAME     R6045 2
 '@T6G_MB_LIB.T6G(SCH_1):PAGE338_I130@PURE_QUANTA.Q_RES(CHIPS)':
 'B': CDS_PINID='B';
NODE_NAME     U30 3
 '@T6G_MB_LIB.T6G(SCH_1):PAGE340_I66@PURE_QUANTA.SN74LVC1G07DBVR(CHIPS)':
 'GND': CDS_PINID='GND';
NODE_NAME     C1060 2
 '@T6G_MB_LIB.T6G(SCH_1):PAGE340_I69@PURE_QUANTA.Q_CAP(CHIPS)':
 'B': CDS_PINID='B';
NODE_NAME     U9002 3
 '@T6G_MB_LIB.T6G(SCH_1):PAGE340_I74@PURE_QUANTA.74LVC1G32GW(CHIPS)':
 'GND': CDS_PINID='GND';
NODE_NAME     C9008 2
 '@T6G_MB_LIB.T6G(SCH_1):PAGE340_I75@PURE_QUANTA.Q_CAP(CHIPS)':
 'B': CDS_PINID='B';
NODE_NAME     C1061 2
 '@T6G_MB_LIB.T6G(SCH_1):PAGE257_I5@PURE_QUANTA.Q_CAP(CHIPS)':
 'B': CDS_PINID='B';
NODE_NAME     C1065 2
 '@T6G_MB_LIB.T6G(SCH_1):PAGE257_I14@PURE_QUANTA.Q_CAP(CHIPS)':
 'B': CDS_PINID='B';
NODE_NAME     U32 S
 '@T6G_MB_LIB.T6G(SCH_1):PAGE257_I24@PURE_QUANTA.MOSFET_N(CHIPS)':
 'SOURCE': CDS_PINID='SOURCE';
NODE_NAME     U31 3
 '@T6G_MB_LIB.T6G(SCH_1):PAGE257_I31@PURE_QUANTA.74LVC1G08W57(CHIPS)':
 'GND': CDS_PINID='GND';
NODE_NAME     C1062 2
 '@T6G_MB_LIB.T6G(SCH_1):PAGE257_I36@PURE_QUANTA.Q_CAP(CHIPS)':
 'B': CDS_PINID='B';
NODE_NAME     U37 3
 '@T6G_MB_LIB.T6G(SCH_1):PAGE257_I40@PURE_QUANTA.74LVC1G32GW(CHIPS)':
 'GND': CDS_PINID='GND';
NODE_NAME     U34 3
 '@T6G_MB_LIB.T6G(SCH_1):PAGE257_I45@PURE_QUANTA.SN74LVC1G07DBVR(CHIPS)':
 'GND': CDS_PINID='GND';
NODE_NAME     C1064 2
 '@T6G_MB_LIB.T6G(SCH_1):PAGE257_I46@PURE_QUANTA.Q_CAP(CHIPS)':
 'B': CDS_PINID='B';
NODE_NAME     C1063 2
 '@T6G_MB_LIB.T6G(SCH_1):PAGE257_I55@PURE_QUANTA.Q_CAP(CHIPS)':
 'B': CDS_PINID='B';
NODE_NAME     U35 3
 '@T6G_MB_LIB.T6G(SCH_1):PAGE257_I63@PURE_QUANTA.74LVC1G08W57(CHIPS)':
 'GND': CDS_PINID='GND';
NODE_NAME     U33 3
 '@T6G_MB_LIB.T6G(SCH_1):PAGE257_I64@PURE_QUANTA.SN74LVC1G07DBVR(CHIPS)':
 'GND': CDS_PINID='GND';
NODE_NAME     R6060 2
 '@T6G_MB_LIB.T6G(SCH_1):PAGE343_I120@PURE_QUANTA.Q_RES(CHIPS)':
 'B': CDS_PINID='B';
NODE_NAME     R4066 2
 '@T6G_MB_LIB.T6G(SCH_1):PAGE343_I121@PURE_QUANTA.Q_RES(CHIPS)':
 'B': CDS_PINID='B';
NODE_NAME     U45 5
 '@T6G_MB_LIB.T6G(SCH_1):PAGE376_I22@PURE_QUANTA.PI3CSW12ZUAEX(CHIPS)':
 'GND': CDS_PINID='GND';
NODE_NAME     C1069 2
 '@T6G_MB_LIB.T6G(SCH_1):PAGE376_I24@PURE_QUANTA.Q_CAP(CHIPS)':
 'B': CDS_PINID='B';
NODE_NAME     R1215 1
 '@T6G_MB_LIB.T6G(SCH_1):PAGE376_I28@PURE_QUANTA.Q_RES(CHIPS)':
 'A': CDS_PINID='A';
NODE_NAME     U42 5
 '@T6G_MB_LIB.T6G(SCH_1):PAGE376_I31@PURE_QUANTA.PI3CSW12ZUAEX(CHIPS)':
 'GND': CDS_PINID='GND';
NODE_NAME     C1067 2
 '@T6G_MB_LIB.T6G(SCH_1):PAGE376_I37@PURE_QUANTA.Q_CAP(CHIPS)':
 'B': CDS_PINID='B';
NODE_NAME     R1213 1
 '@T6G_MB_LIB.T6G(SCH_1):PAGE376_I41@PURE_QUANTA.Q_RES(CHIPS)':
 'A': CDS_PINID='A';
NODE_NAME     U41 5
 '@T6G_MB_LIB.T6G(SCH_1):PAGE376_I46@PURE_QUANTA.PI3CSW12ZUAEX(CHIPS)':
 'GND': CDS_PINID='GND';
NODE_NAME     C1066 2
 '@T6G_MB_LIB.T6G(SCH_1):PAGE376_I48@PURE_QUANTA.Q_CAP(CHIPS)':
 'B': CDS_PINID='B';
NODE_NAME     R1212 1
 '@T6G_MB_LIB.T6G(SCH_1):PAGE376_I54@PURE_QUANTA.Q_RES(CHIPS)':
 'A': CDS_PINID='A';
NODE_NAME     U43 5
 '@T6G_MB_LIB.T6G(SCH_1):PAGE376_I61@PURE_QUANTA.PI3CSW12ZUAEX(CHIPS)':
 'GND': CDS_PINID='GND';
NODE_NAME     C1068 2
 '@T6G_MB_LIB.T6G(SCH_1):PAGE376_I65@PURE_QUANTA.Q_CAP(CHIPS)':
 'B': CDS_PINID='B';
NODE_NAME     R1214 1
 '@T6G_MB_LIB.T6G(SCH_1):PAGE376_I69@PURE_QUANTA.Q_RES(CHIPS)':
 'A': CDS_PINID='A';
NODE_NAME     U48 5
 '@T6G_MB_LIB.T6G(SCH_1):PAGE376_I76@PURE_QUANTA.PI3CSW12ZUAEX(CHIPS)':
 'GND': CDS_PINID='GND';
NODE_NAME     C1073 2
 '@T6G_MB_LIB.T6G(SCH_1):PAGE376_I80@PURE_QUANTA.Q_CAP(CHIPS)':
 'B': CDS_PINID='B';
NODE_NAME     C1072 2
 '@T6G_MB_LIB.T6G(SCH_1):PAGE376_I84@PURE_QUANTA.Q_CAP(CHIPS)':
 'B': CDS_PINID='B';
NODE_NAME     U49 5
 '@T6G_MB_LIB.T6G(SCH_1):PAGE376_I85@PURE_QUANTA.PI3CSW12ZUAEX(CHIPS)':
 'GND': CDS_PINID='GND';
NODE_NAME     R1219 1
 '@T6G_MB_LIB.T6G(SCH_1):PAGE376_I87@PURE_QUANTA.Q_RES(CHIPS)':
 'A': CDS_PINID='A';
NODE_NAME     C1070 2
 '@T6G_MB_LIB.T6G(SCH_1):PAGE376_I99@PURE_QUANTA.Q_CAP(CHIPS)':
 'B': CDS_PINID='B';
NODE_NAME     C1071 2
 '@T6G_MB_LIB.T6G(SCH_1):PAGE376_I105@PURE_QUANTA.Q_CAP(CHIPS)':
 'B': CDS_PINID='B';
NODE_NAME     U46 5
 '@T6G_MB_LIB.T6G(SCH_1):PAGE376_I108@PURE_QUANTA.PI3CSW12ZUAEX(CHIPS)':
 'GND': CDS_PINID='GND';
NODE_NAME     R1218 1
 '@T6G_MB_LIB.T6G(SCH_1):PAGE376_I110@PURE_QUANTA.Q_RES(CHIPS)':
 'A': CDS_PINID='A';
NODE_NAME     R1216 1
 '@T6G_MB_LIB.T6G(SCH_1):PAGE376_I116@PURE_QUANTA.Q_RES(CHIPS)':
 'A': CDS_PINID='A';
NODE_NAME     U47 5
 '@T6G_MB_LIB.T6G(SCH_1):PAGE376_I121@PURE_QUANTA.PI3CSW12ZUAEX(CHIPS)':
 'GND': CDS_PINID='GND';
NODE_NAME     R1217 1
 '@T6G_MB_LIB.T6G(SCH_1):PAGE376_I122@PURE_QUANTA.Q_RES(CHIPS)':
 'A': CDS_PINID='A';
NODE_NAME     R1226 2
 '@T6G_MB_LIB.T6G(SCH_1):PAGE263_I12@PURE_QUANTA.Q_RES(CHIPS)':
 'B': CDS_PINID='B';
NODE_NAME     C1093 2
 '@T6G_MB_LIB.T6G(SCH_1):PAGE263_I43@PURE_QUANTA.Q_CAP(CHIPS)':
 'B': CDS_PINID='B';
NODE_NAME     C1085 2
 '@T6G_MB_LIB.T6G(SCH_1):PAGE263_I45@PURE_QUANTA.Q_CAP(CHIPS)':
 'B': CDS_PINID='B';
NODE_NAME     R1240 2
 '@T6G_MB_LIB.T6G(SCH_1):PAGE263_I57@PURE_QUANTA.Q_RES(CHIPS)':
 'B': CDS_PINID='B';
NODE_NAME     R1242 2
 '@T6G_MB_LIB.T6G(SCH_1):PAGE263_I58@PURE_QUANTA.Q_RES(CHIPS)':
 'B': CDS_PINID='B';
NODE_NAME     C1094 2
 '@T6G_MB_LIB.T6G(SCH_1):PAGE263_I68@PURE_QUANTA.Q_CAP(CHIPS)':
 'B': CDS_PINID='B';
NODE_NAME     C1092 2
 '@T6G_MB_LIB.T6G(SCH_1):PAGE263_I76@PURE_QUANTA.Q_CAP(CHIPS)':
 'B': CDS_PINID='B';
NODE_NAME     C1084 2
 '@T6G_MB_LIB.T6G(SCH_1):PAGE263_I77@PURE_QUANTA.Q_CAP(CHIPS)':
 'B': CDS_PINID='B';
NODE_NAME     C1074 2
 '@T6G_MB_LIB.T6G(SCH_1):PAGE263_I115@PURE_QUANTA.Q_CAP(CHIPS)':
 'B': CDS_PINID='B';
NODE_NAME     R1268 2
 '@T6G_MB_LIB.T6G(SCH_1):PAGE263_I119@PURE_QUANTA.Q_RES(CHIPS)':
 'B': CDS_PINID='B';
NODE_NAME     C1095 2
 '@T6G_MB_LIB.T6G(SCH_1):PAGE263_I130@PURE_QUANTA.Q_CAP(CHIPS)':
 'B': CDS_PINID='B';
NODE_NAME     U51 4
 '@T6G_MB_LIB.T6G(SCH_1):PAGE263_I142@PURE_QUANTA.ADC128D818CIMTXNOPB(CHIPS)':
 'GND': CDS_PINID='GND';
NODE_NAME     C1076 2
 '@T6G_MB_LIB.T6G(SCH_1):PAGE263_I152@PURE_QUANTA.Q_CAP(CHIPS)':
 'B': CDS_PINID='B';
NODE_NAME     U50 4
 '@T6G_MB_LIB.T6G(SCH_1):PAGE263_I156@PURE_QUANTA.MAX11617EEET(CHIPS)':
 'AIN8': CDS_PINID='AIN8';
NODE_NAME     U50 3
 '@T6G_MB_LIB.T6G(SCH_1):PAGE263_I156@PURE_QUANTA.MAX11617EEET(CHIPS)':
 'AIN9': CDS_PINID='AIN9';
NODE_NAME     U50 2
 '@T6G_MB_LIB.T6G(SCH_1):PAGE263_I156@PURE_QUANTA.MAX11617EEET(CHIPS)':
 'AIN10': CDS_PINID='AIN10';
NODE_NAME     U50 15
 '@T6G_MB_LIB.T6G(SCH_1):PAGE263_I156@PURE_QUANTA.MAX11617EEET(CHIPS)':
 'GND': CDS_PINID='GND';
NODE_NAME     C1075 2
 '@T6G_MB_LIB.T6G(SCH_1):PAGE263_I165@PURE_QUANTA.Q_CAP(CHIPS)':
 'B': CDS_PINID='B';
NODE_NAME     C1077 2
 '@T6G_MB_LIB.T6G(SCH_1):PAGE263_I166@PURE_QUANTA.Q_CAP(CHIPS)':
 'B': CDS_PINID='B';
NODE_NAME     C1078 2
 '@T6G_MB_LIB.T6G(SCH_1):PAGE263_I173@PURE_QUANTA.Q_CAP(CHIPS)':
 'B': CDS_PINID='B';
NODE_NAME     C1086 2
 '@T6G_MB_LIB.T6G(SCH_1):PAGE263_I175@PURE_QUANTA.Q_CAP(CHIPS)':
 'B': CDS_PINID='B';
NODE_NAME     C1079 2
 '@T6G_MB_LIB.T6G(SCH_1):PAGE263_I185@PURE_QUANTA.Q_CAP(CHIPS)':
 'B': CDS_PINID='B';
NODE_NAME     C1087 2
 '@T6G_MB_LIB.T6G(SCH_1):PAGE263_I187@PURE_QUANTA.Q_CAP(CHIPS)':
 'B': CDS_PINID='B';
NODE_NAME     C1083 2
 '@T6G_MB_LIB.T6G(SCH_1):PAGE263_I198@PURE_QUANTA.Q_CAP(CHIPS)':
 'B': CDS_PINID='B';
NODE_NAME     C1091 2
 '@T6G_MB_LIB.T6G(SCH_1):PAGE263_I200@PURE_QUANTA.Q_CAP(CHIPS)':
 'B': CDS_PINID='B';
NODE_NAME     C1082 2
 '@T6G_MB_LIB.T6G(SCH_1):PAGE263_I209@PURE_QUANTA.Q_CAP(CHIPS)':
 'B': CDS_PINID='B';
NODE_NAME     C1089 2
 '@T6G_MB_LIB.T6G(SCH_1):PAGE263_I211@PURE_QUANTA.Q_CAP(CHIPS)':
 'B': CDS_PINID='B';
NODE_NAME     R1224 2
 '@T6G_MB_LIB.T6G(SCH_1):PAGE263_I216@PURE_QUANTA.Q_RES(CHIPS)':
 'B': CDS_PINID='B';
NODE_NAME     C1080 2
 '@T6G_MB_LIB.T6G(SCH_1):PAGE263_I221@PURE_QUANTA.Q_CAP(CHIPS)':
 'B': CDS_PINID='B';
NODE_NAME     C1088 2
 '@T6G_MB_LIB.T6G(SCH_1):PAGE263_I223@PURE_QUANTA.Q_CAP(CHIPS)':
 'B': CDS_PINID='B';
NODE_NAME     C1081 2
 '@T6G_MB_LIB.T6G(SCH_1):PAGE263_I232@PURE_QUANTA.Q_CAP(CHIPS)':
 'B': CDS_PINID='B';
NODE_NAME     C1090 2
 '@T6G_MB_LIB.T6G(SCH_1):PAGE263_I237@PURE_QUANTA.Q_CAP(CHIPS)':
 'B': CDS_PINID='B';
NODE_NAME     C1108 2
 '@T6G_MB_LIB.T6G(SCH_1):PAGE466_I5@PURE_QUANTA.Q_CAP(CHIPS)':
 'B': CDS_PINID='B';
NODE_NAME     R1306 1
 '@T6G_MB_LIB.T6G(SCH_1):PAGE466_I12@PURE_QUANTA.Q_RES(CHIPS)':
 'A': CDS_PINID='A';
NODE_NAME     R1309 1
 '@T6G_MB_LIB.T6G(SCH_1):PAGE466_I13@PURE_QUANTA.Q_RES(CHIPS)':
 'A': CDS_PINID='A';
NODE_NAME     C1097 2
 '@T6G_MB_LIB.T6G(SCH_1):PAGE466_I19@PURE_QUANTA.Q_CAP(CHIPS)':
 'B': CDS_PINID='B';
NODE_NAME     U55 10
 '@T6G_MB_LIB.T6G(SCH_1):PAGE466_I28@PURE_QUANTA.ISL28022FRZT(CHIPS)':
 'GND': CDS_PINID='GND';
NODE_NAME     U55 TH
 '@T6G_MB_LIB.T6G(SCH_1):PAGE466_I28@PURE_QUANTA.ISL28022FRZT(CHIPS)':
 'TH_GND': CDS_PINID='TH_GND';
NODE_NAME     U56 10
 '@T6G_MB_LIB.T6G(SCH_1):PAGE466_I29@PURE_QUANTA.ISL28022FRZT(CHIPS)':
 'GND': CDS_PINID='GND';
NODE_NAME     U56 TH
 '@T6G_MB_LIB.T6G(SCH_1):PAGE466_I29@PURE_QUANTA.ISL28022FRZT(CHIPS)':
 'TH_GND': CDS_PINID='TH_GND';
NODE_NAME     C1106 2
 '@T6G_MB_LIB.T6G(SCH_1):PAGE466_I36@PURE_QUANTA.Q_CAP(CHIPS)':
 'B': CDS_PINID='B';
NODE_NAME     R1307 1
 '@T6G_MB_LIB.T6G(SCH_1):PAGE466_I44@PURE_QUANTA.Q_RES(CHIPS)':
 'A': CDS_PINID='A';
NODE_NAME     R1310 1
 '@T6G_MB_LIB.T6G(SCH_1):PAGE466_I45@PURE_QUANTA.Q_RES(CHIPS)':
 'A': CDS_PINID='A';
NODE_NAME     C1109 2
 '@T6G_MB_LIB.T6G(SCH_1):PAGE466_I51@PURE_QUANTA.Q_CAP(CHIPS)':
 'B': CDS_PINID='B';
NODE_NAME     U52 10
 '@T6G_MB_LIB.T6G(SCH_1):PAGE466_I57@PURE_QUANTA.ISL28022FRZT(CHIPS)':
 'GND': CDS_PINID='GND';
NODE_NAME     U52 TH
 '@T6G_MB_LIB.T6G(SCH_1):PAGE466_I57@PURE_QUANTA.ISL28022FRZT(CHIPS)':
 'TH_GND': CDS_PINID='TH_GND';
NODE_NAME     C1096 2
 '@T6G_MB_LIB.T6G(SCH_1):PAGE466_I66@PURE_QUANTA.Q_CAP(CHIPS)':
 'B': CDS_PINID='B';
NODE_NAME     R1305 1
 '@T6G_MB_LIB.T6G(SCH_1):PAGE466_I72@PURE_QUANTA.Q_RES(CHIPS)':
 'A': CDS_PINID='A';
NODE_NAME     C1107 2
 '@T6G_MB_LIB.T6G(SCH_1):PAGE466_I81@PURE_QUANTA.Q_CAP(CHIPS)':
 'B': CDS_PINID='B';
NODE_NAME     PC393 2
 '@T6G_MB_LIB.T6G(SCH_1):PAGE193_I92@PURE_QUANTA.Q_CAPP(CHIPS)':
 'B': CDS_PINID='B';
NODE_NAME     PC390 2
 '@T6G_MB_LIB.T6G(SCH_1):PAGE193_I93@PURE_QUANTA.Q_CAPP(CHIPS)':
 'B': CDS_PINID='B';
NODE_NAME     PC454 2
 '@T6G_MB_LIB.T6G(SCH_1):PAGE197_I85@PURE_QUANTA.Q_CAPP(CHIPS)':
 'B': CDS_PINID='B';
NODE_NAME     R1308 1
 '@T6G_MB_LIB.T6G(SCH_1):PAGE466_I96@PURE_QUANTA.Q_RES(CHIPS)':
 'A': CDS_PINID='A';
NODE_NAME     U167 1
 '@T6G_MB_LIB.T6G(SCH_1):PAGE156_I130@PURE_QUANTA.NCP698SQ15T1G(CHIPS)':
 'GND': CDS_PINID='GND';
NODE_NAME     U213 9
 '@T6G_MB_LIB.T6G(SCH_1):PAGE138_I111@PURE_QUANTA.IML3112Y2B000NCG8(CHIPS)':
 'TH_GND': CDS_PINID='TH_GND';
NODE_NAME     C24 2
 '@T6G_MB_LIB.T6G(SCH_1):PAGE138_I112@PURE_QUANTA.Q_CAP(CHIPS)':
 'B': CDS_PINID='B';
NODE_NAME     C9 2
 '@T6G_MB_LIB.T6G(SCH_1):PAGE138_I113@PURE_QUANTA.Q_CAP(CHIPS)':
 'B': CDS_PINID='B';
NODE_NAME     U4 5
 '@T6G_MB_LIB.T6G(SCH_1):PAGE138_I114@PURE_QUANTA.PI3CSW12ZUAEX(CHIPS)':
 'GND': CDS_PINID='GND';
NODE_NAME     U2 4
 '@T6G_MB_LIB.T6G(SCH_1):PAGE137_I99@PURE_QUANTA.PCA9617ADP(CHIPS)':
 'GND': CDS_PINID='GND';
NODE_NAME     R1364 2
 '@T6G_MB_LIB.T6G(SCH_1):PAGE385_I111@PURE_QUANTA.Q_RES(CHIPS)':
 'B': CDS_PINID='B';
NODE_NAME     R1370 2
 '@T6G_MB_LIB.T6G(SCH_1):PAGE385_I114@PURE_QUANTA.Q_RES(CHIPS)':
 'B': CDS_PINID='B';
NODE_NAME     R1368 2
 '@T6G_MB_LIB.T6G(SCH_1):PAGE385_I119@PURE_QUANTA.Q_RES(CHIPS)':
 'B': CDS_PINID='B';
NODE_NAME     R973 2
 '@T6G_MB_LIB.T6G(SCH_1):PAGE385_I121@PURE_QUANTA.Q_RES(CHIPS)':
 'B': CDS_PINID='B';
NODE_NAME     R6809 2
 '@T6G_MB_LIB.T6G(SCH_1):PAGE386_I18@PURE_QUANTA.Q_RES(CHIPS)':
 'B': CDS_PINID='B';
NODE_NAME     R1391 2
 '@T6G_MB_LIB.T6G(SCH_1):PAGE408_I84@PURE_QUANTA.Q_RES(CHIPS)':
 'B': CDS_PINID='B';
NODE_NAME     R1395 2
 '@T6G_MB_LIB.T6G(SCH_1):PAGE408_I94@PURE_QUANTA.Q_RES(CHIPS)':
 'B': CDS_PINID='B';
NODE_NAME     R1398 2
 '@T6G_MB_LIB.T6G(SCH_1):PAGE408_I98@PURE_QUANTA.Q_RES(CHIPS)':
 'B': CDS_PINID='B';
NODE_NAME     R1041 2
 '@T6G_MB_LIB.T6G(SCH_1):PAGE409_I18@PURE_QUANTA.Q_RES(CHIPS)':
 'B': CDS_PINID='B';
NODE_NAME     R1022 2
 '@T6G_MB_LIB.T6G(SCH_1):PAGE408_I102@PURE_QUANTA.Q_RES(CHIPS)':
 'B': CDS_PINID='B';
NODE_NAME     R1400 2
 '@T6G_MB_LIB.T6G(SCH_1):PAGE419_I84@PURE_QUANTA.Q_RES(CHIPS)':
 'B': CDS_PINID='B';
NODE_NAME     R1406 2
 '@T6G_MB_LIB.T6G(SCH_1):PAGE419_I95@PURE_QUANTA.Q_RES(CHIPS)':
 'B': CDS_PINID='B';
NODE_NAME     R1404 2
 '@T6G_MB_LIB.T6G(SCH_1):PAGE419_I99@PURE_QUANTA.Q_RES(CHIPS)':
 'B': CDS_PINID='B';
NODE_NAME     R1064 2
 '@T6G_MB_LIB.T6G(SCH_1):PAGE419_I102@PURE_QUANTA.Q_RES(CHIPS)':
 'B': CDS_PINID='B';
NODE_NAME     R1082 2
 '@T6G_MB_LIB.T6G(SCH_1):PAGE420_I18@PURE_QUANTA.Q_RES(CHIPS)':
 'B': CDS_PINID='B';
NODE_NAME     R1408 2
 '@T6G_MB_LIB.T6G(SCH_1):PAGE430_I85@PURE_QUANTA.Q_RES(CHIPS)':
 'B': CDS_PINID='B';
NODE_NAME     R1414 2
 '@T6G_MB_LIB.T6G(SCH_1):PAGE430_I96@PURE_QUANTA.Q_RES(CHIPS)':
 'B': CDS_PINID='B';
NODE_NAME     R1412 2
 '@T6G_MB_LIB.T6G(SCH_1):PAGE430_I101@PURE_QUANTA.Q_RES(CHIPS)':
 'B': CDS_PINID='B';
NODE_NAME     R1106 2
 '@T6G_MB_LIB.T6G(SCH_1):PAGE430_I102@PURE_QUANTA.Q_RES(CHIPS)':
 'B': CDS_PINID='B';
NODE_NAME     R1124 2
 '@T6G_MB_LIB.T6G(SCH_1):PAGE431_I18@PURE_QUANTA.Q_RES(CHIPS)':
 'B': CDS_PINID='B';
NODE_NAME     R1387 2
 '@T6G_MB_LIB.T6G(SCH_1):PAGE401_I108@PURE_QUANTA.Q_RES(CHIPS)':
 'B': CDS_PINID='B';
NODE_NAME     R1380 2
 '@T6G_MB_LIB.T6G(SCH_1):PAGE401_I112@PURE_QUANTA.Q_RES(CHIPS)':
 'B': CDS_PINID='B';
NODE_NAME     R1389 2
 '@T6G_MB_LIB.T6G(SCH_1):PAGE401_I124@PURE_QUANTA.Q_RES(CHIPS)':
 'B': CDS_PINID='B';
NODE_NAME     R6723 2
 '@T6G_MB_LIB.T6G(SCH_1):PAGE401_I128@PURE_QUANTA.Q_RES(CHIPS)':
 'B': CDS_PINID='B';
NODE_NAME     R701 2
 '@T6G_MB_LIB.T6G(SCH_1):PAGE400_I105@PURE_QUANTA.Q_RES(CHIPS)':
 'B': CDS_PINID='B';
NODE_NAME     R1376 2
 '@T6G_MB_LIB.T6G(SCH_1):PAGE392_I111@PURE_QUANTA.Q_RES(CHIPS)':
 'B': CDS_PINID='B';
NODE_NAME     R1372 2
 '@T6G_MB_LIB.T6G(SCH_1):PAGE392_I115@PURE_QUANTA.Q_RES(CHIPS)':
 'B': CDS_PINID='B';
NODE_NAME     R1378 2
 '@T6G_MB_LIB.T6G(SCH_1):PAGE392_I126@PURE_QUANTA.Q_RES(CHIPS)':
 'B': CDS_PINID='B';
NODE_NAME     R756 2
 '@T6G_MB_LIB.T6G(SCH_1):PAGE392_I132@PURE_QUANTA.Q_RES(CHIPS)':
 'B': CDS_PINID='B';
NODE_NAME     R6731 2
 '@T6G_MB_LIB.T6G(SCH_1):PAGE391_I20@PURE_QUANTA.Q_RES(CHIPS)':
 'B': CDS_PINID='B';
NODE_NAME     R1421 2
 '@T6G_MB_LIB.T6G(SCH_1):PAGE451_I98@PURE_QUANTA.Q_RES(CHIPS)':
 'B': CDS_PINID='B';
NODE_NAME     R1416 2
 '@T6G_MB_LIB.T6G(SCH_1):PAGE451_I102@PURE_QUANTA.Q_RES(CHIPS)':
 'B': CDS_PINID='B';
NODE_NAME     R1427 2
 '@T6G_MB_LIB.T6G(SCH_1):PAGE451_I113@PURE_QUANTA.Q_RES(CHIPS)':
 'B': CDS_PINID='B';
NODE_NAME     R869 2
 '@T6G_MB_LIB.T6G(SCH_1):PAGE451_I119@PURE_QUANTA.Q_RES(CHIPS)':
 'B': CDS_PINID='B';
NODE_NAME     R6795 2
 '@T6G_MB_LIB.T6G(SCH_1):PAGE452_I20@PURE_QUANTA.Q_RES(CHIPS)':
 'B': CDS_PINID='B';
NODE_NAME     R1433 2
 '@T6G_MB_LIB.T6G(SCH_1):PAGE462_I98@PURE_QUANTA.Q_RES(CHIPS)':
 'B': CDS_PINID='B';
NODE_NAME     R1429 2
 '@T6G_MB_LIB.T6G(SCH_1):PAGE462_I103@PURE_QUANTA.Q_RES(CHIPS)':
 'B': CDS_PINID='B';
NODE_NAME     R1435 2
 '@T6G_MB_LIB.T6G(SCH_1):PAGE462_I114@PURE_QUANTA.Q_RES(CHIPS)':
 'B': CDS_PINID='B';
NODE_NAME     R910 2
 '@T6G_MB_LIB.T6G(SCH_1):PAGE462_I119@PURE_QUANTA.Q_RES(CHIPS)':
 'B': CDS_PINID='B';
NODE_NAME     R6901 2
 '@T6G_MB_LIB.T6G(SCH_1):PAGE463_I18@PURE_QUANTA.Q_RES(CHIPS)':
 'B': CDS_PINID='B';
NODE_NAME     R1365 2
 '@T6G_MB_LIB.T6G(SCH_1):PAGE385_I123@PURE_QUANTA.Q_RES(CHIPS)':
 'B': CDS_PINID='B';
NODE_NAME     R1392 2
 '@T6G_MB_LIB.T6G(SCH_1):PAGE408_I119@PURE_QUANTA.Q_RES(CHIPS)':
 'B': CDS_PINID='B';
NODE_NAME     R1401 2
 '@T6G_MB_LIB.T6G(SCH_1):PAGE419_I120@PURE_QUANTA.Q_RES(CHIPS)':
 'B': CDS_PINID='B';
NODE_NAME     R1409 2
 '@T6G_MB_LIB.T6G(SCH_1):PAGE430_I117@PURE_QUANTA.Q_RES(CHIPS)':
 'B': CDS_PINID='B';
NODE_NAME     R1381 2
 '@T6G_MB_LIB.T6G(SCH_1):PAGE401_I144@PURE_QUANTA.Q_RES(CHIPS)':
 'B': CDS_PINID='B';
NODE_NAME     R1373 2
 '@T6G_MB_LIB.T6G(SCH_1):PAGE392_I150@PURE_QUANTA.Q_RES(CHIPS)':
 'B': CDS_PINID='B';
NODE_NAME     R1417 2
 '@T6G_MB_LIB.T6G(SCH_1):PAGE451_I136@PURE_QUANTA.Q_RES(CHIPS)':
 'B': CDS_PINID='B';
NODE_NAME     R1430 2
 '@T6G_MB_LIB.T6G(SCH_1):PAGE462_I136@PURE_QUANTA.Q_RES(CHIPS)':
 'B': CDS_PINID='B';
NODE_NAME     JP10 3
 '@T6G_MB_LIB.T6G(SCH_1):PAGE372_I103@PURE_QUANTA.CONN3_210HP1030BR1(CHIPS)':
 '3': CDS_PINID='\3\';
NODE_NAME     JP6500 3
 '@T6G_MB_LIB.T6G(SCH_1):PAGE378_I116@PURE_QUANTA.CONN3_210HP1030BR1(CHIPS)':
 '3': CDS_PINID='\3\';
NODE_NAME     SW1 1
 '@T6G_MB_LIB.T6G(SCH_1):PAGE144_I90@PURE_QUANTA.SW20S_DHNF10FQTR(CHIPS)':
 '1': CDS_PINID='\1\';
NODE_NAME     SW1 3
 '@T6G_MB_LIB.T6G(SCH_1):PAGE144_I90@PURE_QUANTA.SW20S_DHNF10FQTR(CHIPS)':
 '3': CDS_PINID='\3\';
NODE_NAME     SW1 9
 '@T6G_MB_LIB.T6G(SCH_1):PAGE144_I90@PURE_QUANTA.SW20S_DHNF10FQTR(CHIPS)':
 '9': CDS_PINID='\9\';
NODE_NAME     C8008 2
 '@T6G_MB_LIB.T6G(SCH_1):PAGE340_I79@PURE_QUANTA.Q_CAP(CHIPS)':
 'B': CDS_PINID='B';
NODE_NAME     U8001 1
 '@T6G_MB_LIB.T6G(SCH_1):PAGE340_I80@PURE_QUANTA.APX80929SAG7(CHIPS)':
 'GND': CDS_PINID='GND';
NODE_NAME     R8093 2
 '@T6G_MB_LIB.T6G(SCH_1):PAGE340_I84@PURE_QUANTA.Q_RES(CHIPS)':
 'B': CDS_PINID='B';
NODE_NAME     C8009 2
 '@T6G_MB_LIB.T6G(SCH_1):PAGE257_I66@PURE_QUANTA.Q_CAP(CHIPS)':
 'B': CDS_PINID='B';
NODE_NAME     U8002 1
 '@T6G_MB_LIB.T6G(SCH_1):PAGE257_I67@PURE_QUANTA.APX80929SAG7(CHIPS)':
 'GND': CDS_PINID='GND';
NODE_NAME     R8096 2
 '@T6G_MB_LIB.T6G(SCH_1):PAGE257_I70@PURE_QUANTA.Q_RES(CHIPS)':
 'B': CDS_PINID='B';
NODE_NAME     PJ09_P0_N 1
 '@T6G_MB_LIB.T6G(SCH_1):PAGE475_I215@PURE_QUANTA.Q_SHORT(CHIPS)':
 '1': CDS_PINID='\1\';
NODE_NAME     PJ09_P1_N 1
 '@T6G_MB_LIB.T6G(SCH_1):PAGE477_I96@PURE_QUANTA.Q_SHORT(CHIPS)':
 '1': CDS_PINID='\1\';
NODE_NAME     C542 2
 '@T6G_MB_LIB.T6G(SCH_1):PAGE388_I90@PURE_QUANTA.Q_CAP(CHIPS)':
 'B': CDS_PINID='B';
NODE_NAME     C545 2
 '@T6G_MB_LIB.T6G(SCH_1):PAGE388_I91@PURE_QUANTA.Q_CAP(CHIPS)':
 'B': CDS_PINID='B';
NODE_NAME     C583 2
 '@T6G_MB_LIB.T6G(SCH_1):PAGE388_I93@PURE_QUANTA.Q_CAP(CHIPS)':
 'B': CDS_PINID='B';
NODE_NAME     C566 2
 '@T6G_MB_LIB.T6G(SCH_1):PAGE388_I94@PURE_QUANTA.Q_CAP(CHIPS)':
 'B': CDS_PINID='B';
NODE_NAME     C621 2
 '@T6G_MB_LIB.T6G(SCH_1):PAGE411_I90@PURE_QUANTA.Q_CAP(CHIPS)':
 'B': CDS_PINID='B';
NODE_NAME     C624 2
 '@T6G_MB_LIB.T6G(SCH_1):PAGE411_I91@PURE_QUANTA.Q_CAP(CHIPS)':
 'B': CDS_PINID='B';
NODE_NAME     C658 2
 '@T6G_MB_LIB.T6G(SCH_1):PAGE411_I92@PURE_QUANTA.Q_CAP(CHIPS)':
 'B': CDS_PINID='B';
NODE_NAME     C659 2
 '@T6G_MB_LIB.T6G(SCH_1):PAGE411_I93@PURE_QUANTA.Q_CAP(CHIPS)':
 'B': CDS_PINID='B';
NODE_NAME     C660 2
 '@T6G_MB_LIB.T6G(SCH_1):PAGE411_I94@PURE_QUANTA.Q_CAP(CHIPS)':
 'B': CDS_PINID='B';
NODE_NAME     C787 2
 '@T6G_MB_LIB.T6G(SCH_1):PAGE422_I90@PURE_QUANTA.Q_CAP(CHIPS)':
 'B': CDS_PINID='B';
NODE_NAME     C793 2
 '@T6G_MB_LIB.T6G(SCH_1):PAGE422_I91@PURE_QUANTA.Q_CAP(CHIPS)':
 'B': CDS_PINID='B';
NODE_NAME     C972 2
 '@T6G_MB_LIB.T6G(SCH_1):PAGE422_I92@PURE_QUANTA.Q_CAP(CHIPS)':
 'B': CDS_PINID='B';
NODE_NAME     C985 2
 '@T6G_MB_LIB.T6G(SCH_1):PAGE422_I93@PURE_QUANTA.Q_CAP(CHIPS)':
 'B': CDS_PINID='B';
NODE_NAME     C1018 2
 '@T6G_MB_LIB.T6G(SCH_1):PAGE433_I90@PURE_QUANTA.Q_CAP(CHIPS)':
 'B': CDS_PINID='B';
NODE_NAME     C1020 2
 '@T6G_MB_LIB.T6G(SCH_1):PAGE433_I91@PURE_QUANTA.Q_CAP(CHIPS)':
 'B': CDS_PINID='B';
NODE_NAME     C1051 2
 '@T6G_MB_LIB.T6G(SCH_1):PAGE433_I92@PURE_QUANTA.Q_CAP(CHIPS)':
 'B': CDS_PINID='B';
NODE_NAME     C1053 2
 '@T6G_MB_LIB.T6G(SCH_1):PAGE433_I93@PURE_QUANTA.Q_CAP(CHIPS)':
 'B': CDS_PINID='B';
NODE_NAME     C187 2
 '@T6G_MB_LIB.T6G(SCH_1):PAGE398_I99@PURE_QUANTA.Q_CAP(CHIPS)':
 'B': CDS_PINID='B';
NODE_NAME     C201 2
 '@T6G_MB_LIB.T6G(SCH_1):PAGE398_I100@PURE_QUANTA.Q_CAP(CHIPS)':
 'B': CDS_PINID='B';
NODE_NAME     C281 2
 '@T6G_MB_LIB.T6G(SCH_1):PAGE398_I101@PURE_QUANTA.Q_CAP(CHIPS)':
 'B': CDS_PINID='B';
NODE_NAME     C283 2
 '@T6G_MB_LIB.T6G(SCH_1):PAGE398_I102@PURE_QUANTA.Q_CAP(CHIPS)':
 'B': CDS_PINID='B';
NODE_NAME     C306 2
 '@T6G_MB_LIB.T6G(SCH_1):PAGE443_I90@PURE_QUANTA.Q_CAP(CHIPS)':
 'B': CDS_PINID='B';
NODE_NAME     C315 2
 '@T6G_MB_LIB.T6G(SCH_1):PAGE443_I91@PURE_QUANTA.Q_CAP(CHIPS)':
 'B': CDS_PINID='B';
NODE_NAME     C341 2
 '@T6G_MB_LIB.T6G(SCH_1):PAGE443_I92@PURE_QUANTA.Q_CAP(CHIPS)':
 'B': CDS_PINID='B';
NODE_NAME     C350 2
 '@T6G_MB_LIB.T6G(SCH_1):PAGE443_I93@PURE_QUANTA.Q_CAP(CHIPS)':
 'B': CDS_PINID='B';
NODE_NAME     C390 2
 '@T6G_MB_LIB.T6G(SCH_1):PAGE454_I90@PURE_QUANTA.Q_CAP(CHIPS)':
 'B': CDS_PINID='B';
NODE_NAME     C394 2
 '@T6G_MB_LIB.T6G(SCH_1):PAGE454_I91@PURE_QUANTA.Q_CAP(CHIPS)':
 'B': CDS_PINID='B';
NODE_NAME     C426 2
 '@T6G_MB_LIB.T6G(SCH_1):PAGE454_I92@PURE_QUANTA.Q_CAP(CHIPS)':
 'B': CDS_PINID='B';
NODE_NAME     C428 2
 '@T6G_MB_LIB.T6G(SCH_1):PAGE454_I93@PURE_QUANTA.Q_CAP(CHIPS)':
 'B': CDS_PINID='B';
NODE_NAME     C456 2
 '@T6G_MB_LIB.T6G(SCH_1):PAGE465_I90@PURE_QUANTA.Q_CAP(CHIPS)':
 'B': CDS_PINID='B';
NODE_NAME     C460 2
 '@T6G_MB_LIB.T6G(SCH_1):PAGE465_I91@PURE_QUANTA.Q_CAP(CHIPS)':
 'B': CDS_PINID='B';
NODE_NAME     C496 2
 '@T6G_MB_LIB.T6G(SCH_1):PAGE465_I92@PURE_QUANTA.Q_CAP(CHIPS)':
 'B': CDS_PINID='B';
NODE_NAME     C498 2
 '@T6G_MB_LIB.T6G(SCH_1):PAGE465_I93@PURE_QUANTA.Q_CAP(CHIPS)':
 'B': CDS_PINID='B';
NODE_NAME     PC6902 2
 '@T6G_MB_LIB.T6G(SCH_1):PAGE469_I56@PURE_QUANTA.Q_CAP(CHIPS)':
 'B': CDS_PINID='B';
NODE_NAME     PC6901 2
 '@T6G_MB_LIB.T6G(SCH_1):PAGE469_I57@PURE_QUANTA.Q_CAP(CHIPS)':
 'B': CDS_PINID='B';
NODE_NAME     PC6900 2
 '@T6G_MB_LIB.T6G(SCH_1):PAGE469_I58@PURE_QUANTA.Q_CAP(CHIPS)':
 'B': CDS_PINID='B';
NODE_NAME     PC6905 2
 '@T6G_MB_LIB.T6G(SCH_1):PAGE470_I55@PURE_QUANTA.Q_CAP(CHIPS)':
 'B': CDS_PINID='B';
NODE_NAME     PC6904 2
 '@T6G_MB_LIB.T6G(SCH_1):PAGE470_I56@PURE_QUANTA.Q_CAP(CHIPS)':
 'B': CDS_PINID='B';
NODE_NAME     PC6903 2
 '@T6G_MB_LIB.T6G(SCH_1):PAGE470_I57@PURE_QUANTA.Q_CAP(CHIPS)':
 'B': CDS_PINID='B';
NODE_NAME     C71 2
 '@T6G_MB_LIB.T6G(SCH_1):PAGE232_I75@PURE_QUANTA.Q_CAP(CHIPS)':
 'B': CDS_PINID='B';
NODE_NAME     C94 2
 '@T6G_MB_LIB.T6G(SCH_1):PAGE232_I76@PURE_QUANTA.Q_CAP(CHIPS)':
 'B': CDS_PINID='B';
NODE_NAME     C215 2
 '@T6G_MB_LIB.T6G(SCH_1):PAGE28_I230@PURE_QUANTA.Q_CAP(CHIPS)':
 'B': CDS_PINID='B';
NODE_NAME     C216 2
 '@T6G_MB_LIB.T6G(SCH_1):PAGE28_I231@PURE_QUANTA.Q_CAP(CHIPS)':
 'B': CDS_PINID='B';
NODE_NAME     C93 2
 '@T6G_MB_LIB.T6G(SCH_1):PAGE153_I91@PURE_QUANTA.Q_CAP(CHIPS)':
 'B': CDS_PINID='B';
NODE_NAME     R1229 2
 '@T6G_MB_LIB.T6G(SCH_1):PAGE263_I242@PURE_QUANTA.Q_RES(CHIPS)':
 'B': CDS_PINID='B';
NODE_NAME     R1221 2
 '@T6G_MB_LIB.T6G(SCH_1):PAGE263_I243@PURE_QUANTA.Q_RES(CHIPS)':
 'B': CDS_PINID='B';
NODE_NAME     R1220 2
 '@T6G_MB_LIB.T6G(SCH_1):PAGE263_I244@PURE_QUANTA.Q_RES(CHIPS)':
 'B': CDS_PINID='B';
NODE_NAME     R1223 2
 '@T6G_MB_LIB.T6G(SCH_1):PAGE263_I245@PURE_QUANTA.Q_RES(CHIPS)':
 'B': CDS_PINID='B';
NODE_NAME     R1222 2
 '@T6G_MB_LIB.T6G(SCH_1):PAGE263_I246@PURE_QUANTA.Q_RES(CHIPS)':
 'B': CDS_PINID='B';
NODE_NAME     R1225 2
 '@T6G_MB_LIB.T6G(SCH_1):PAGE263_I247@PURE_QUANTA.Q_RES(CHIPS)':
 'B': CDS_PINID='B';
NODE_NAME     C7003 2
 '@T6G_MB_LIB.T6G(SCH_1):PAGE388_I95@PURE_QUANTA.Q_CAP(CHIPS)':
 'B': CDS_PINID='B';
NODE_NAME     C7002 2
 '@T6G_MB_LIB.T6G(SCH_1):PAGE388_I96@PURE_QUANTA.Q_CAP(CHIPS)':
 'B': CDS_PINID='B';
NODE_NAME     C7001 2
 '@T6G_MB_LIB.T6G(SCH_1):PAGE388_I97@PURE_QUANTA.Q_CAPP(CHIPS)':
 'B': CDS_PINID='B';
NODE_NAME     C7000 2
 '@T6G_MB_LIB.T6G(SCH_1):PAGE388_I98@PURE_QUANTA.Q_CAPP(CHIPS)':
 'B': CDS_PINID='B';
NODE_NAME     C7004 2
 '@T6G_MB_LIB.T6G(SCH_1):PAGE454_I94@PURE_QUANTA.Q_CAPP(CHIPS)':
 'B': CDS_PINID='B';
NODE_NAME     C7005 2
 '@T6G_MB_LIB.T6G(SCH_1):PAGE454_I95@PURE_QUANTA.Q_CAPP(CHIPS)':
 'B': CDS_PINID='B';
NODE_NAME     C7006 2
 '@T6G_MB_LIB.T6G(SCH_1):PAGE454_I96@PURE_QUANTA.Q_CAP(CHIPS)':
 'B': CDS_PINID='B';
NODE_NAME     C7007 2
 '@T6G_MB_LIB.T6G(SCH_1):PAGE454_I97@PURE_QUANTA.Q_CAP(CHIPS)':
 'B': CDS_PINID='B';
NODE_NAME     C7008 2
 '@T6G_MB_LIB.T6G(SCH_1):PAGE388_I99@PURE_QUANTA.Q_CAPP(CHIPS)':
 'B': CDS_PINID='B';
NODE_NAME     C7009 2
 '@T6G_MB_LIB.T6G(SCH_1):PAGE388_I100@PURE_QUANTA.Q_CAPP(CHIPS)':
 'B': CDS_PINID='B';
NODE_NAME     C7010 2
 '@T6G_MB_LIB.T6G(SCH_1):PAGE388_I101@PURE_QUANTA.Q_CAP(CHIPS)':
 'B': CDS_PINID='B';
NODE_NAME     C7011 2
 '@T6G_MB_LIB.T6G(SCH_1):PAGE411_I95@PURE_QUANTA.Q_CAPP(CHIPS)':
 'B': CDS_PINID='B';
NODE_NAME     C7012 2
 '@T6G_MB_LIB.T6G(SCH_1):PAGE411_I96@PURE_QUANTA.Q_CAPP(CHIPS)':
 'B': CDS_PINID='B';
NODE_NAME     C7013 2
 '@T6G_MB_LIB.T6G(SCH_1):PAGE411_I97@PURE_QUANTA.Q_CAP(CHIPS)':
 'B': CDS_PINID='B';
NODE_NAME     C7014 2
 '@T6G_MB_LIB.T6G(SCH_1):PAGE422_I94@PURE_QUANTA.Q_CAPP(CHIPS)':
 'B': CDS_PINID='B';
NODE_NAME     C7015 2
 '@T6G_MB_LIB.T6G(SCH_1):PAGE422_I95@PURE_QUANTA.Q_CAPP(CHIPS)':
 'B': CDS_PINID='B';
NODE_NAME     C7016 2
 '@T6G_MB_LIB.T6G(SCH_1):PAGE422_I96@PURE_QUANTA.Q_CAP(CHIPS)':
 'B': CDS_PINID='B';
NODE_NAME     C7017 2
 '@T6G_MB_LIB.T6G(SCH_1):PAGE433_I94@PURE_QUANTA.Q_CAPP(CHIPS)':
 'B': CDS_PINID='B';
NODE_NAME     C7018 2
 '@T6G_MB_LIB.T6G(SCH_1):PAGE433_I95@PURE_QUANTA.Q_CAPP(CHIPS)':
 'B': CDS_PINID='B';
NODE_NAME     C7019 2
 '@T6G_MB_LIB.T6G(SCH_1):PAGE433_I96@PURE_QUANTA.Q_CAP(CHIPS)':
 'B': CDS_PINID='B';
NODE_NAME     C7020 2
 '@T6G_MB_LIB.T6G(SCH_1):PAGE398_I103@PURE_QUANTA.Q_CAPP(CHIPS)':
 'B': CDS_PINID='B';
NODE_NAME     C7021 2
 '@T6G_MB_LIB.T6G(SCH_1):PAGE398_I104@PURE_QUANTA.Q_CAPP(CHIPS)':
 'B': CDS_PINID='B';
NODE_NAME     C7022 2
 '@T6G_MB_LIB.T6G(SCH_1):PAGE398_I105@PURE_QUANTA.Q_CAP(CHIPS)':
 'B': CDS_PINID='B';
NODE_NAME     C7023 2
 '@T6G_MB_LIB.T6G(SCH_1):PAGE443_I94@PURE_QUANTA.Q_CAPP(CHIPS)':
 'B': CDS_PINID='B';
NODE_NAME     C7024 2
 '@T6G_MB_LIB.T6G(SCH_1):PAGE443_I95@PURE_QUANTA.Q_CAPP(CHIPS)':
 'B': CDS_PINID='B';
NODE_NAME     C7025 2
 '@T6G_MB_LIB.T6G(SCH_1):PAGE443_I96@PURE_QUANTA.Q_CAP(CHIPS)':
 'B': CDS_PINID='B';
NODE_NAME     C7026 2
 '@T6G_MB_LIB.T6G(SCH_1):PAGE454_I98@PURE_QUANTA.Q_CAPP(CHIPS)':
 'B': CDS_PINID='B';
NODE_NAME     C7027 2
 '@T6G_MB_LIB.T6G(SCH_1):PAGE454_I99@PURE_QUANTA.Q_CAPP(CHIPS)':
 'B': CDS_PINID='B';
NODE_NAME     C7028 2
 '@T6G_MB_LIB.T6G(SCH_1):PAGE454_I100@PURE_QUANTA.Q_CAP(CHIPS)':
 'B': CDS_PINID='B';
NODE_NAME     C7029 2
 '@T6G_MB_LIB.T6G(SCH_1):PAGE465_I94@PURE_QUANTA.Q_CAPP(CHIPS)':
 'B': CDS_PINID='B';
NODE_NAME     C7030 2
 '@T6G_MB_LIB.T6G(SCH_1):PAGE465_I95@PURE_QUANTA.Q_CAPP(CHIPS)':
 'B': CDS_PINID='B';
NODE_NAME     C7031 2
 '@T6G_MB_LIB.T6G(SCH_1):PAGE465_I96@PURE_QUANTA.Q_CAP(CHIPS)':
 'B': CDS_PINID='B';
NODE_NAME     PC7000 2
 '@T6G_MB_LIB.T6G(SCH_1):PAGE180_I85@PURE_QUANTA.Q_CAP(CHIPS)':
 'B': CDS_PINID='B';
NODE_NAME     PC7001 2
 '@T6G_MB_LIB.T6G(SCH_1):PAGE197_I86@PURE_QUANTA.Q_CAP(CHIPS)':
 'B': CDS_PINID='B';
NODE_NAME     PC7002 2
 '@T6G_MB_LIB.T6G(SCH_1):PAGE183_I95@PURE_QUANTA.Q_CAP(CHIPS)':
 'B': CDS_PINID='B';
NODE_NAME     PC7003 2
 '@T6G_MB_LIB.T6G(SCH_1):PAGE200_I95@PURE_QUANTA.Q_CAP(CHIPS)':
 'B': CDS_PINID='B';
NODE_NAME     U247 10
 '@T6G_MB_LIB.T6G(SCH_1):PAGE232_I77@PURE_QUANTA.9FGL0251DKILFT(CHIPS)':
 'GND_10': CDS_PINID='GND_10';
NODE_NAME     U247 21
 '@T6G_MB_LIB.T6G(SCH_1):PAGE232_I77@PURE_QUANTA.9FGL0251DKILFT(CHIPS)':
 'GND_21': CDS_PINID='GND_21';
NODE_NAME     U247 15
 '@T6G_MB_LIB.T6G(SCH_1):PAGE232_I77@PURE_QUANTA.9FGL0251DKILFT(CHIPS)':
 'GNDA': CDS_PINID='GNDA';
NODE_NAME     U247 6
 '@T6G_MB_LIB.T6G(SCH_1):PAGE232_I77@PURE_QUANTA.9FGL0251DKILFT(CHIPS)':
 'GNDDIG': CDS_PINID='GNDDIG';
NODE_NAME     U247 5
 '@T6G_MB_LIB.T6G(SCH_1):PAGE232_I77@PURE_QUANTA.9FGL0251DKILFT(CHIPS)':
 'GNDREF': CDS_PINID='GNDREF';
NODE_NAME     U247 24
 '@T6G_MB_LIB.T6G(SCH_1):PAGE232_I77@PURE_QUANTA.9FGL0251DKILFT(CHIPS)':
 'GNDXTAL': CDS_PINID='GNDXTAL';
NODE_NAME     U247 25
 '@T6G_MB_LIB.T6G(SCH_1):PAGE232_I77@PURE_QUANTA.9FGL0251DKILFT(CHIPS)':
 'TH_GND': CDS_PINID='TH_GND';
NODE_NAME     C7032 2
 '@T6G_MB_LIB.T6G(SCH_1):PAGE388_I102@PURE_QUANTA.Q_CAPP(CHIPS)':
 'B': CDS_PINID='B';
NODE_NAME     C7033 2
 '@T6G_MB_LIB.T6G(SCH_1):PAGE388_I103@PURE_QUANTA.Q_CAP(CHIPS)':
 'B': CDS_PINID='B';
NODE_NAME     C7034 2
 '@T6G_MB_LIB.T6G(SCH_1):PAGE388_I104@PURE_QUANTA.Q_CAP(CHIPS)':
 'B': CDS_PINID='B';
NODE_NAME     C7035 2
 '@T6G_MB_LIB.T6G(SCH_1):PAGE388_I105@PURE_QUANTA.Q_CAP(CHIPS)':
 'B': CDS_PINID='B';
NODE_NAME     C7036 2
 '@T6G_MB_LIB.T6G(SCH_1):PAGE388_I106@PURE_QUANTA.Q_CAP(CHIPS)':
 'B': CDS_PINID='B';
NODE_NAME     C7037 2
 '@T6G_MB_LIB.T6G(SCH_1):PAGE454_I101@PURE_QUANTA.Q_CAPP(CHIPS)':
 'B': CDS_PINID='B';
NODE_NAME     C7038 2
 '@T6G_MB_LIB.T6G(SCH_1):PAGE454_I102@PURE_QUANTA.Q_CAP(CHIPS)':
 'B': CDS_PINID='B';
NODE_NAME     C7039 2
 '@T6G_MB_LIB.T6G(SCH_1):PAGE454_I103@PURE_QUANTA.Q_CAP(CHIPS)':
 'B': CDS_PINID='B';
NODE_NAME     C7040 2
 '@T6G_MB_LIB.T6G(SCH_1):PAGE454_I104@PURE_QUANTA.Q_CAP(CHIPS)':
 'B': CDS_PINID='B';
NODE_NAME     C7041 2
 '@T6G_MB_LIB.T6G(SCH_1):PAGE454_I105@PURE_QUANTA.Q_CAP(CHIPS)':
 'B': CDS_PINID='B';
NODE_NAME     R855 2
 '@T6G_MB_LIB.T6G(SCH_1):PAGE146_I3@PURE_QUANTA.Q_RES(CHIPS)':
 'B': CDS_PINID='B';
NODE_NAME     C1113 2
 '@T6G_MB_LIB.T6G(SCH_1):PAGE146_I6@PURE_QUANTA.Q_CAP(CHIPS)':
 'B': CDS_PINID='B';
NODE_NAME     R1049 2
 '@T6G_MB_LIB.T6G(SCH_1):PAGE146_I12@PURE_QUANTA.Q_RES(CHIPS)':
 'B': CDS_PINID='B';
NODE_NAME     R1474 2
 '@T6G_MB_LIB.T6G(SCH_1):PAGE146_I14@PURE_QUANTA.Q_RES(CHIPS)':
 'B': CDS_PINID='B';
NODE_NAME     Q7001 1
 '@T6G_MB_LIB.T6G(SCH_1):PAGE146_I16@PURE_QUANTA.MOSFET_NCH_1D3S(CHIPS)':
 '1': CDS_PINID='\1\';
NODE_NAME     Q7001 2
 '@T6G_MB_LIB.T6G(SCH_1):PAGE146_I16@PURE_QUANTA.MOSFET_NCH_1D3S(CHIPS)':
 '2': CDS_PINID='\2\';
NODE_NAME     Q7001 3
 '@T6G_MB_LIB.T6G(SCH_1):PAGE146_I16@PURE_QUANTA.MOSFET_NCH_1D3S(CHIPS)':
 '3': CDS_PINID='\3\';
NODE_NAME     Q7003 1
 '@T6G_MB_LIB.T6G(SCH_1):PAGE146_I22@PURE_QUANTA.MOSFET_NCH_1D3S(CHIPS)':
 '1': CDS_PINID='\1\';
NODE_NAME     Q7003 2
 '@T6G_MB_LIB.T6G(SCH_1):PAGE146_I22@PURE_QUANTA.MOSFET_NCH_1D3S(CHIPS)':
 '2': CDS_PINID='\2\';
NODE_NAME     Q7003 3
 '@T6G_MB_LIB.T6G(SCH_1):PAGE146_I22@PURE_QUANTA.MOSFET_NCH_1D3S(CHIPS)':
 '3': CDS_PINID='\3\';
NODE_NAME     R1475 2
 '@T6G_MB_LIB.T6G(SCH_1):PAGE146_I28@PURE_QUANTA.Q_RES(CHIPS)':
 'B': CDS_PINID='B';
NODE_NAME     C1114 2
 '@T6G_MB_LIB.T6G(SCH_1):PAGE146_I30@PURE_QUANTA.Q_CAP(CHIPS)':
 'B': CDS_PINID='B';
NODE_NAME     R954 2
 '@T6G_MB_LIB.T6G(SCH_1):PAGE146_I36@PURE_QUANTA.Q_RES(CHIPS)':
 'B': CDS_PINID='B';
NODE_NAME     R1092 2
 '@T6G_MB_LIB.T6G(SCH_1):PAGE146_I39@PURE_QUANTA.Q_RES(CHIPS)':
 'B': CDS_PINID='B';
NODE_NAME     U9050 3
 '@T6G_MB_LIB.T6G(SCH_1):PAGE340_I91@PURE_QUANTA.74LVC1G08W57(CHIPS)':
 'GND': CDS_PINID='GND';
NODE_NAME     C9050 2
 '@T6G_MB_LIB.T6G(SCH_1):PAGE340_I94@PURE_QUANTA.Q_CAP(CHIPS)':
 'B': CDS_PINID='B';
NODE_NAME     U9051 3
 '@T6G_MB_LIB.T6G(SCH_1):PAGE257_I78@PURE_QUANTA.74LVC1G08W57(CHIPS)':
 'GND': CDS_PINID='GND';
NODE_NAME     C9051 2
 '@T6G_MB_LIB.T6G(SCH_1):PAGE257_I81@PURE_QUANTA.Q_CAP(CHIPS)':
 'B': CDS_PINID='B';
NODE_NAME     C1115 2
 '@T6G_MB_LIB.T6G(SCH_1):PAGE363_I478@PURE_QUANTA.Q_CAP(CHIPS)':
 'B': CDS_PINID='B';
NODE_NAME     C213 2
 '@T6G_MB_LIB.T6G(SCH_1):PAGE28_I232@PURE_QUANTA.Q_CAP(CHIPS)':
 'B': CDS_PINID='B';
NODE_NAME     C214 2
 '@T6G_MB_LIB.T6G(SCH_1):PAGE28_I233@PURE_QUANTA.Q_CAP(CHIPS)':
 'B': CDS_PINID='B';
NODE_NAME     C6000 2
 '@T6G_MB_LIB.T6G(SCH_1):PAGE348_I219@PURE_QUANTA.Q_CAP(CHIPS)':
 'B': CDS_PINID='B';
NODE_NAME     R4809 2
 '@T6G_MB_LIB.T6G(SCH_1):PAGE348_I220@PURE_QUANTA.Q_RES(CHIPS)':
 'B': CDS_PINID='B';
NODE_NAME     R6133 2
 '@T6G_MB_LIB.T6G(SCH_1):PAGE83_I132@PURE_QUANTA.Q_RES(CHIPS)':
 'B': CDS_PINID='B';
NODE_NAME     R6134 2
 '@T6G_MB_LIB.T6G(SCH_1):PAGE83_I133@PURE_QUANTA.Q_RES(CHIPS)':
 'B': CDS_PINID='B';
NODE_NAME     R6135 2
 '@T6G_MB_LIB.T6G(SCH_1):PAGE83_I136@PURE_QUANTA.Q_RES(CHIPS)':
 'B': CDS_PINID='B';
NODE_NAME     R6149 2
 '@T6G_MB_LIB.T6G(SCH_1):PAGE83_I137@PURE_QUANTA.Q_RES(CHIPS)':
 'B': CDS_PINID='B';
NODE_NAME     R6150 2
 '@T6G_MB_LIB.T6G(SCH_1):PAGE83_I139@PURE_QUANTA.Q_RES(CHIPS)':
 'B': CDS_PINID='B';
NODE_NAME     R6151 2
 '@T6G_MB_LIB.T6G(SCH_1):PAGE83_I141@PURE_QUANTA.Q_RES(CHIPS)':
 'B': CDS_PINID='B';
NODE_NAME     PU299 3
 '@T6G_MB_LIB.T6G(SCH_1):PAGE350_I95@PURE_QUANTA.RS31312R(CHIPS)':
 'ENTM': CDS_PINID='ENTM';
NODE_NAME     PU299 7
 '@T6G_MB_LIB.T6G(SCH_1):PAGE350_I95@PURE_QUANTA.RS31312R(CHIPS)':
 'GND': CDS_PINID='GND';
NODE_NAME     PU299 2
 '@T6G_MB_LIB.T6G(SCH_1):PAGE350_I95@PURE_QUANTA.RS31312R(CHIPS)':
 'LOADEN': CDS_PINID='LOADEN';
NODE_NAME     PU204 3
 '@T6G_MB_LIB.T6G(SCH_1):PAGE339_I137@PURE_QUANTA.RS31312R(CHIPS)':
 'ENTM': CDS_PINID='ENTM';
NODE_NAME     PU204 7
 '@T6G_MB_LIB.T6G(SCH_1):PAGE339_I137@PURE_QUANTA.RS31312R(CHIPS)':
 'GND': CDS_PINID='GND';
NODE_NAME     PU204 2
 '@T6G_MB_LIB.T6G(SCH_1):PAGE339_I137@PURE_QUANTA.RS31312R(CHIPS)':
 'LOADEN': CDS_PINID='LOADEN';
NODE_NAME     PU206 3
 '@T6G_MB_LIB.T6G(SCH_1):PAGE344_I82@PURE_QUANTA.RS31312R(CHIPS)':
 'ENTM': CDS_PINID='ENTM';
NODE_NAME     PU206 7
 '@T6G_MB_LIB.T6G(SCH_1):PAGE344_I82@PURE_QUANTA.RS31312R(CHIPS)':
 'GND': CDS_PINID='GND';
NODE_NAME     PU206 2
 '@T6G_MB_LIB.T6G(SCH_1):PAGE344_I82@PURE_QUANTA.RS31312R(CHIPS)':
 'LOADEN': CDS_PINID='LOADEN';
NODE_NAME     PU292 3
 '@T6G_MB_LIB.T6G(SCH_1):PAGE323_I76@PURE_QUANTA.RS31312R(CHIPS)':
 'ENTM': CDS_PINID='ENTM';
NODE_NAME     PU292 7
 '@T6G_MB_LIB.T6G(SCH_1):PAGE323_I76@PURE_QUANTA.RS31312R(CHIPS)':
 'GND': CDS_PINID='GND';
NODE_NAME     PU292 2
 '@T6G_MB_LIB.T6G(SCH_1):PAGE323_I76@PURE_QUANTA.RS31312R(CHIPS)':
 'LOADEN': CDS_PINID='LOADEN';
NODE_NAME     R6284 2
 '@T6G_MB_LIB.T6G(SCH_1):PAGE157_I171@PURE_QUANTA.Q_RES(CHIPS)':
 'B': CDS_PINID='B';
NODE_NAME     C6090 2
 '@T6G_MB_LIB.T6G(SCH_1):PAGE157_I174@PURE_QUANTA.Q_CAP(CHIPS)':
 'B': CDS_PINID='B';
NODE_NAME     C6091 2
 '@T6G_MB_LIB.T6G(SCH_1):PAGE157_I175@PURE_QUANTA.Q_CAP(CHIPS)':
 'B': CDS_PINID='B';
NET_NAME
'GPIO2_RT_CPU0_P0'
 '@T6G_MB_LIB.T6G(SCH_1):GPIO2_RT_CPU0_P0':
 C_SIGNAL='@t6g_mb_lib.t6g(sch_1):gpio2_rt_cpu0_p0';
NODE_NAME     R979 1
 '@T6G_MB_LIB.T6G(SCH_1):PAGE385_I27@PURE_QUANTA.Q_RES(CHIPS)':
 'A': CDS_PINID='A';
NODE_NAME     R978 2
 '@T6G_MB_LIB.T6G(SCH_1):PAGE385_I30@PURE_QUANTA.Q_RES(CHIPS)':
 'B': CDS_PINID='B';
NODE_NAME     U6010 FJ25
 '@T6G_MB_LIB.T6G(SCH_1):PAGE385_I53@PURE_QUANTA.PT5161LRS(CHIPS)':
 'GPIO2': CDS_PINID='GPIO2';
NET_NAME
'GPIO2_RT_CPU0_P1'
 '@T6G_MB_LIB.T6G(SCH_1):GPIO2_RT_CPU0_P1':
 C_SIGNAL='@t6g_mb_lib.t6g(sch_1):gpio2_rt_cpu0_p1';
NODE_NAME     R1028 1
 '@T6G_MB_LIB.T6G(SCH_1):PAGE408_I7@PURE_QUANTA.Q_RES(CHIPS)':
 'A': CDS_PINID='A';
NODE_NAME     R1027 2
 '@T6G_MB_LIB.T6G(SCH_1):PAGE408_I10@PURE_QUANTA.Q_RES(CHIPS)':
 'B': CDS_PINID='B';
NODE_NAME     U6011 FJ25
 '@T6G_MB_LIB.T6G(SCH_1):PAGE408_I83@PURE_QUANTA.PT5161LRS(CHIPS)':
 'GPIO2': CDS_PINID='GPIO2';
NET_NAME
'GPIO2_RT_CPU0_P2'
 '@T6G_MB_LIB.T6G(SCH_1):GPIO2_RT_CPU0_P2':
 C_SIGNAL='@t6g_mb_lib.t6g(sch_1):gpio2_rt_cpu0_p2';
NODE_NAME     R1070 1
 '@T6G_MB_LIB.T6G(SCH_1):PAGE419_I7@PURE_QUANTA.Q_RES(CHIPS)':
 'A': CDS_PINID='A';
NODE_NAME     R1069 2
 '@T6G_MB_LIB.T6G(SCH_1):PAGE419_I10@PURE_QUANTA.Q_RES(CHIPS)':
 'B': CDS_PINID='B';
NODE_NAME     U6012 FJ25
 '@T6G_MB_LIB.T6G(SCH_1):PAGE419_I83@PURE_QUANTA.PT5161LRS(CHIPS)':
 'GPIO2': CDS_PINID='GPIO2';
NET_NAME
'GPIO2_RT_CPU0_P3'
 '@T6G_MB_LIB.T6G(SCH_1):GPIO2_RT_CPU0_P3':
 C_SIGNAL='@t6g_mb_lib.t6g(sch_1):gpio2_rt_cpu0_p3';
NODE_NAME     R1112 1
 '@T6G_MB_LIB.T6G(SCH_1):PAGE430_I7@PURE_QUANTA.Q_RES(CHIPS)':
 'A': CDS_PINID='A';
NODE_NAME     R1111 2
 '@T6G_MB_LIB.T6G(SCH_1):PAGE430_I10@PURE_QUANTA.Q_RES(CHIPS)':
 'B': CDS_PINID='B';
NODE_NAME     U6013 FJ25
 '@T6G_MB_LIB.T6G(SCH_1):PAGE430_I83@PURE_QUANTA.PT5161LRS(CHIPS)':
 'GPIO2': CDS_PINID='GPIO2';
NET_NAME
'GPIO2_RT_CPU1_P0'
 '@T6G_MB_LIB.T6G(SCH_1):GPIO2_RT_CPU1_P0':
 C_SIGNAL='@t6g_mb_lib.t6g(sch_1):gpio2_rt_cpu1_p0';
NODE_NAME     U6014 FJ25
 '@T6G_MB_LIB.T6G(SCH_1):PAGE401_I1@PURE_QUANTA.PT5161LRS(CHIPS)':
 'GPIO2': CDS_PINID='GPIO2';
NODE_NAME     R706 2
 '@T6G_MB_LIB.T6G(SCH_1):PAGE401_I29@PURE_QUANTA.Q_RES(CHIPS)':
 'B': CDS_PINID='B';
NODE_NAME     R707 1
 '@T6G_MB_LIB.T6G(SCH_1):PAGE401_I36@PURE_QUANTA.Q_RES(CHIPS)':
 'A': CDS_PINID='A';
NET_NAME
'GPIO2_RT_CPU1_P1'
 '@T6G_MB_LIB.T6G(SCH_1):GPIO2_RT_CPU1_P1':
 C_SIGNAL='@t6g_mb_lib.t6g(sch_1):gpio2_rt_cpu1_p1';
NODE_NAME     R782 1
 '@T6G_MB_LIB.T6G(SCH_1):PAGE392_I21@PURE_QUANTA.Q_RES(CHIPS)':
 'A': CDS_PINID='A';
NODE_NAME     R781 2
 '@T6G_MB_LIB.T6G(SCH_1):PAGE392_I24@PURE_QUANTA.Q_RES(CHIPS)':
 'B': CDS_PINID='B';
NODE_NAME     U6015 FJ25
 '@T6G_MB_LIB.T6G(SCH_1):PAGE392_I47@PURE_QUANTA.PT5161LRS(CHIPS)':
 'GPIO2': CDS_PINID='GPIO2';
NET_NAME
'GPIO2_RT_CPU1_P2'
 '@T6G_MB_LIB.T6G(SCH_1):GPIO2_RT_CPU1_P2':
 C_SIGNAL='@t6g_mb_lib.t6g(sch_1):gpio2_rt_cpu1_p2';
NODE_NAME     R875 1
 '@T6G_MB_LIB.T6G(SCH_1):PAGE451_I19@PURE_QUANTA.Q_RES(CHIPS)':
 'A': CDS_PINID='A';
NODE_NAME     R874 2
 '@T6G_MB_LIB.T6G(SCH_1):PAGE451_I21@PURE_QUANTA.Q_RES(CHIPS)':
 'B': CDS_PINID='B';
NODE_NAME     U6016 FJ25
 '@T6G_MB_LIB.T6G(SCH_1):PAGE451_I97@PURE_QUANTA.PT5161LRS(CHIPS)':
 'GPIO2': CDS_PINID='GPIO2';
NET_NAME
'GPIO2_RT_CPU1_P3'
 '@T6G_MB_LIB.T6G(SCH_1):GPIO2_RT_CPU1_P3':
 C_SIGNAL='@t6g_mb_lib.t6g(sch_1):gpio2_rt_cpu1_p3';
NODE_NAME     R916 1
 '@T6G_MB_LIB.T6G(SCH_1):PAGE462_I19@PURE_QUANTA.Q_RES(CHIPS)':
 'A': CDS_PINID='A';
NODE_NAME     R915 2
 '@T6G_MB_LIB.T6G(SCH_1):PAGE462_I22@PURE_QUANTA.Q_RES(CHIPS)':
 'B': CDS_PINID='B';
NODE_NAME     U6017 FJ25
 '@T6G_MB_LIB.T6G(SCH_1):PAGE462_I97@PURE_QUANTA.PT5161LRS(CHIPS)':
 'GPIO2': CDS_PINID='GPIO2';
NET_NAME
'GPIO3_RT_CPU0_P0'
 '@T6G_MB_LIB.T6G(SCH_1):GPIO3_RT_CPU0_P0':
 C_SIGNAL='@t6g_mb_lib.t6g(sch_1):gpio3_rt_cpu0_p0';
NODE_NAME     R980 1
 '@T6G_MB_LIB.T6G(SCH_1):PAGE385_I28@PURE_QUANTA.Q_RES(CHIPS)':
 'A': CDS_PINID='A';
NODE_NAME     U6010 FJ28
 '@T6G_MB_LIB.T6G(SCH_1):PAGE385_I53@PURE_QUANTA.PT5161LRS(CHIPS)':
 'GPIO3': CDS_PINID='GPIO3';
NET_NAME
'GPIO3_RT_CPU0_P1'
 '@T6G_MB_LIB.T6G(SCH_1):GPIO3_RT_CPU0_P1':
 C_SIGNAL='@t6g_mb_lib.t6g(sch_1):gpio3_rt_cpu0_p1';
NODE_NAME     R1029 1
 '@T6G_MB_LIB.T6G(SCH_1):PAGE408_I8@PURE_QUANTA.Q_RES(CHIPS)':
 'A': CDS_PINID='A';
NODE_NAME     U6011 FJ28
 '@T6G_MB_LIB.T6G(SCH_1):PAGE408_I83@PURE_QUANTA.PT5161LRS(CHIPS)':
 'GPIO3': CDS_PINID='GPIO3';
NET_NAME
'GPIO3_RT_CPU0_P2'
 '@T6G_MB_LIB.T6G(SCH_1):GPIO3_RT_CPU0_P2':
 C_SIGNAL='@t6g_mb_lib.t6g(sch_1):gpio3_rt_cpu0_p2';
NODE_NAME     R1072 1
 '@T6G_MB_LIB.T6G(SCH_1):PAGE419_I8@PURE_QUANTA.Q_RES(CHIPS)':
 'A': CDS_PINID='A';
NODE_NAME     U6012 FJ28
 '@T6G_MB_LIB.T6G(SCH_1):PAGE419_I83@PURE_QUANTA.PT5161LRS(CHIPS)':
 'GPIO3': CDS_PINID='GPIO3';
NET_NAME
'GPIO3_RT_CPU0_P3'
 '@T6G_MB_LIB.T6G(SCH_1):GPIO3_RT_CPU0_P3':
 C_SIGNAL='@t6g_mb_lib.t6g(sch_1):gpio3_rt_cpu0_p3';
NODE_NAME     R1113 1
 '@T6G_MB_LIB.T6G(SCH_1):PAGE430_I8@PURE_QUANTA.Q_RES(CHIPS)':
 'A': CDS_PINID='A';
NODE_NAME     U6013 FJ28
 '@T6G_MB_LIB.T6G(SCH_1):PAGE430_I83@PURE_QUANTA.PT5161LRS(CHIPS)':
 'GPIO3': CDS_PINID='GPIO3';
NET_NAME
'GPIO3_RT_CPU1_P0'
 '@T6G_MB_LIB.T6G(SCH_1):GPIO3_RT_CPU1_P0':
 C_SIGNAL='@t6g_mb_lib.t6g(sch_1):gpio3_rt_cpu1_p0';
NODE_NAME     U6014 FJ28
 '@T6G_MB_LIB.T6G(SCH_1):PAGE401_I1@PURE_QUANTA.PT5161LRS(CHIPS)':
 'GPIO3': CDS_PINID='GPIO3';
NODE_NAME     R715 1
 '@T6G_MB_LIB.T6G(SCH_1):PAGE401_I35@PURE_QUANTA.Q_RES(CHIPS)':
 'A': CDS_PINID='A';
NET_NAME
'GPIO3_RT_CPU1_P1'
 '@T6G_MB_LIB.T6G(SCH_1):GPIO3_RT_CPU1_P1':
 C_SIGNAL='@t6g_mb_lib.t6g(sch_1):gpio3_rt_cpu1_p1';
NODE_NAME     R783 1
 '@T6G_MB_LIB.T6G(SCH_1):PAGE392_I22@PURE_QUANTA.Q_RES(CHIPS)':
 'A': CDS_PINID='A';
NODE_NAME     U6015 FJ28
 '@T6G_MB_LIB.T6G(SCH_1):PAGE392_I47@PURE_QUANTA.PT5161LRS(CHIPS)':
 'GPIO3': CDS_PINID='GPIO3';
NET_NAME
'GPIO3_RT_CPU1_P2'
 '@T6G_MB_LIB.T6G(SCH_1):GPIO3_RT_CPU1_P2':
 C_SIGNAL='@t6g_mb_lib.t6g(sch_1):gpio3_rt_cpu1_p2';
NODE_NAME     R876 1
 '@T6G_MB_LIB.T6G(SCH_1):PAGE451_I20@PURE_QUANTA.Q_RES(CHIPS)':
 'A': CDS_PINID='A';
NODE_NAME     U6016 FJ28
 '@T6G_MB_LIB.T6G(SCH_1):PAGE451_I97@PURE_QUANTA.PT5161LRS(CHIPS)':
 'GPIO3': CDS_PINID='GPIO3';
NET_NAME
'GPIO3_RT_CPU1_P3'
 '@T6G_MB_LIB.T6G(SCH_1):GPIO3_RT_CPU1_P3':
 C_SIGNAL='@t6g_mb_lib.t6g(sch_1):gpio3_rt_cpu1_p3';
NODE_NAME     R917 1
 '@T6G_MB_LIB.T6G(SCH_1):PAGE462_I20@PURE_QUANTA.Q_RES(CHIPS)':
 'A': CDS_PINID='A';
NODE_NAME     U6017 FJ28
 '@T6G_MB_LIB.T6G(SCH_1):PAGE462_I97@PURE_QUANTA.PT5161LRS(CHIPS)':
 'GPIO3': CDS_PINID='GPIO3';
NET_NAME
'GPU_3V3IO_RSVD0_FFU'
 '@T6G_MB_LIB.T6G(SCH_1):GPU_3V3IO_RSVD0_FFU':
 C_SIGNAL='@t6g_mb_lib.t6g(sch_1):gpu_3v3io_rsvd0_ffu';
NODE_NAME     J109 N4
 '@T6G_MB_LIB.T6G(SCH_1):PAGE319_I76@PURE_QUANTA.CONN112_10137002101LF(CHIPS)':
 'N4': CDS_PINID='N4';
NODE_NAME     R4120 1
 '@T6G_MB_LIB.T6G(SCH_1):PAGE332_I22@PURE_QUANTA.Q_RES(CHIPS)':
 'A': CDS_PINID='A';
NODE_NAME     R4119 2
 '@T6G_MB_LIB.T6G(SCH_1):PAGE332_I23@PURE_QUANTA.Q_RES(CHIPS)':
 'B': CDS_PINID='B';
NODE_NAME     Q128 2
 '@T6G_MB_LIB.T6G(SCH_1):PAGE332_I37@PURE_QUANTA.MOSFET_NCH_DUAL(CHIPS)':
 'G1': CDS_PINID='G1';
NODE_NAME     R4575 1
 '@T6G_MB_LIB.T6G(SCH_1):PAGE332_I44@PURE_QUANTA.Q_RES(CHIPS)':
 'A': CDS_PINID='A';
NET_NAME
'GPU_3V3IO_RSVD0_FFU_ISO'
 '@T6G_MB_LIB.T6G(SCH_1):GPU_3V3IO_RSVD0_FFU_ISO':
 C_SIGNAL='@t6g_mb_lib.t6g(sch_1):gpu_3v3io_rsvd0_ffu_iso';
NODE_NAME     R4143 2
 '@T6G_MB_LIB.T6G(SCH_1):PAGE80_I231@PURE_QUANTA.Q_RES(CHIPS)':
 'B': CDS_PINID='B';
NODE_NAME     Q128 3
 '@T6G_MB_LIB.T6G(SCH_1):PAGE332_I42@PURE_QUANTA.MOSFET_NCH_DUAL(CHIPS)':
 'D2': CDS_PINID='D2';
NODE_NAME     R4575 2
 '@T6G_MB_LIB.T6G(SCH_1):PAGE332_I44@PURE_QUANTA.Q_RES(CHIPS)':
 'B': CDS_PINID='B';
NODE_NAME     C12 1
 '@T6G_MB_LIB.T6G(SCH_1):PAGE332_I75@PURE_QUANTA.Q_CAP(CHIPS)':
 'A': CDS_PINID='A';
NODE_NAME     R4128 2
 '@T6G_MB_LIB.T6G(SCH_1):PAGE332_I104@PURE_QUANTA.Q_RES(CHIPS)':
 'B': CDS_PINID='B';
NET_NAME
'GPU_3V3IO_RSVD0_FFU_ISO_R'
 '@T6G_MB_LIB.T6G(SCH_1):GPU_3V3IO_RSVD0_FFU_ISO_R':
 C_SIGNAL='@t6g_mb_lib.t6g(sch_1):gpu_3v3io_rsvd0_ffu_iso_r';
NODE_NAME     U18 W13
 '@T6G_MB_LIB.T6G(SCH_1):PAGE80_I216@PURE_QUANTA.LCMXO3LF9400C5BG484C(CHIPS)':
 'PB30D': CDS_PINID='PB30D';
NODE_NAME     R4143 1
 '@T6G_MB_LIB.T6G(SCH_1):PAGE80_I231@PURE_QUANTA.Q_RES(CHIPS)':
 'A': CDS_PINID='A';
NET_NAME
'GPU_3V3IO_RSVD0_FFU_N'
 '@T6G_MB_LIB.T6G(SCH_1):GPU_3V3IO_RSVD0_FFU_N':
 C_SIGNAL='@t6g_mb_lib.t6g(sch_1):gpu_3v3io_rsvd0_ffu_n';
NODE_NAME     Q128 6
 '@T6G_MB_LIB.T6G(SCH_1):PAGE332_I37@PURE_QUANTA.MOSFET_NCH_DUAL(CHIPS)':
 'D1': CDS_PINID='D1';
NODE_NAME     R4125 2
 '@T6G_MB_LIB.T6G(SCH_1):PAGE332_I39@PURE_QUANTA.Q_RES(CHIPS)':
 'B': CDS_PINID='B';
NODE_NAME     Q128 5
 '@T6G_MB_LIB.T6G(SCH_1):PAGE332_I42@PURE_QUANTA.MOSFET_NCH_DUAL(CHIPS)':
 'G2': CDS_PINID='G2';
NET_NAME
'GPU_3V3IO_RSVD1'
 '@T6G_MB_LIB.T6G(SCH_1):GPU_3V3IO_RSVD1':
 C_SIGNAL='@t6g_mb_lib.t6g(sch_1):gpu_3v3io_rsvd1';
NODE_NAME     R4159 1
 '@T6G_MB_LIB.T6G(SCH_1):PAGE331_I13@PURE_QUANTA.Q_RES(CHIPS)':
 'A': CDS_PINID='A';
NODE_NAME     R4158 2
 '@T6G_MB_LIB.T6G(SCH_1):PAGE331_I14@PURE_QUANTA.Q_RES(CHIPS)':
 'B': CDS_PINID='B';
NODE_NAME     Q135 2
 '@T6G_MB_LIB.T6G(SCH_1):PAGE331_I25@PURE_QUANTA.MOSFET_NCH_DUAL(CHIPS)':
 'G1': CDS_PINID='G1';
NODE_NAME     R4569 1
 '@T6G_MB_LIB.T6G(SCH_1):PAGE331_I107@PURE_QUANTA.Q_RES(CHIPS)':
 'A': CDS_PINID='A';
NODE_NAME     J105 A7
 '@T6G_MB_LIB.T6G(SCH_1):PAGE326_I76@PURE_QUANTA.CONN112_10137002101LF(CHIPS)':
 'A7': CDS_PINID='A7';
NET_NAME
'GPU_3V3IO_RSVD1_FFU'
 '@T6G_MB_LIB.T6G(SCH_1):GPU_3V3IO_RSVD1_FFU':
 C_SIGNAL='@t6g_mb_lib.t6g(sch_1):gpu_3v3io_rsvd1_ffu';
NODE_NAME     J109 N6
 '@T6G_MB_LIB.T6G(SCH_1):PAGE319_I16@PURE_QUANTA.CONN112_10137002101LF(CHIPS)':
 'N6': CDS_PINID='N6';
NODE_NAME     R4123 2
 '@T6G_MB_LIB.T6G(SCH_1):PAGE332_I18@PURE_QUANTA.Q_RES(CHIPS)':
 'B': CDS_PINID='B';
NODE_NAME     Q131 2
 '@T6G_MB_LIB.T6G(SCH_1):PAGE332_I30@PURE_QUANTA.MOSFET_NCH_DUAL(CHIPS)':
 'G1': CDS_PINID='G1';
NODE_NAME     R4572 1
 '@T6G_MB_LIB.T6G(SCH_1):PAGE332_I41@PURE_QUANTA.Q_RES(CHIPS)':
 'A': CDS_PINID='A';
NODE_NAME     R4124 1
 '@T6G_MB_LIB.T6G(SCH_1):PAGE332_I135@PURE_QUANTA.Q_RES(CHIPS)':
 'A': CDS_PINID='A';
NET_NAME
'GPU_3V3IO_RSVD1_FFU_ISO'
 '@T6G_MB_LIB.T6G(SCH_1):GPU_3V3IO_RSVD1_FFU_ISO':
 C_SIGNAL='@t6g_mb_lib.t6g(sch_1):gpu_3v3io_rsvd1_ffu_iso';
NODE_NAME     R4144 2
 '@T6G_MB_LIB.T6G(SCH_1):PAGE80_I233@PURE_QUANTA.Q_RES(CHIPS)':
 'B': CDS_PINID='B';
NODE_NAME     Q131 3
 '@T6G_MB_LIB.T6G(SCH_1):PAGE332_I40@PURE_QUANTA.MOSFET_NCH_DUAL(CHIPS)':
 'D2': CDS_PINID='D2';
NODE_NAME     R4572 2
 '@T6G_MB_LIB.T6G(SCH_1):PAGE332_I41@PURE_QUANTA.Q_RES(CHIPS)':
 'B': CDS_PINID='B';
NODE_NAME     R4130 2
 '@T6G_MB_LIB.T6G(SCH_1):PAGE332_I70@PURE_QUANTA.Q_RES(CHIPS)':
 'B': CDS_PINID='B';
NODE_NAME     C14 1
 '@T6G_MB_LIB.T6G(SCH_1):PAGE332_I73@PURE_QUANTA.Q_CAP(CHIPS)':
 'A': CDS_PINID='A';
NET_NAME
'GPU_3V3IO_RSVD1_FFU_ISO_R'
 '@T6G_MB_LIB.T6G(SCH_1):GPU_3V3IO_RSVD1_FFU_ISO_R':
 C_SIGNAL='@t6g_mb_lib.t6g(sch_1):gpu_3v3io_rsvd1_ffu_iso_r';
NODE_NAME     U18 T13
 '@T6G_MB_LIB.T6G(SCH_1):PAGE80_I216@PURE_QUANTA.LCMXO3LF9400C5BG484C(CHIPS)':
 'PB32A': CDS_PINID='PB32A';
NODE_NAME     R4144 1
 '@T6G_MB_LIB.T6G(SCH_1):PAGE80_I233@PURE_QUANTA.Q_RES(CHIPS)':
 'A': CDS_PINID='A';
NET_NAME
'GPU_3V3IO_RSVD1_FFU_N'
 '@T6G_MB_LIB.T6G(SCH_1):GPU_3V3IO_RSVD1_FFU_N':
 C_SIGNAL='@t6g_mb_lib.t6g(sch_1):gpu_3v3io_rsvd1_ffu_n';
NODE_NAME     Q131 6
 '@T6G_MB_LIB.T6G(SCH_1):PAGE332_I30@PURE_QUANTA.MOSFET_NCH_DUAL(CHIPS)':
 'D1': CDS_PINID='D1';
NODE_NAME     R4127 2
 '@T6G_MB_LIB.T6G(SCH_1):PAGE332_I35@PURE_QUANTA.Q_RES(CHIPS)':
 'B': CDS_PINID='B';
NODE_NAME     Q131 5
 '@T6G_MB_LIB.T6G(SCH_1):PAGE332_I40@PURE_QUANTA.MOSFET_NCH_DUAL(CHIPS)':
 'G2': CDS_PINID='G2';
NET_NAME
'GPU_3V3IO_RSVD1_ISO'
 '@T6G_MB_LIB.T6G(SCH_1):GPU_3V3IO_RSVD1_ISO':
 C_SIGNAL='@t6g_mb_lib.t6g(sch_1):gpu_3v3io_rsvd1_iso';
NODE_NAME     Q135 3
 '@T6G_MB_LIB.T6G(SCH_1):PAGE331_I29@PURE_QUANTA.MOSFET_NCH_DUAL(CHIPS)':
 'D2': CDS_PINID='D2';
NODE_NAME     C4 1
 '@T6G_MB_LIB.T6G(SCH_1):PAGE331_I44@PURE_QUANTA.Q_CAP(CHIPS)':
 'A': CDS_PINID='A';
NODE_NAME     R4167 2
 '@T6G_MB_LIB.T6G(SCH_1):PAGE331_I47@PURE_QUANTA.Q_RES(CHIPS)':
 'B': CDS_PINID='B';
NODE_NAME     R4569 2
 '@T6G_MB_LIB.T6G(SCH_1):PAGE331_I107@PURE_QUANTA.Q_RES(CHIPS)':
 'B': CDS_PINID='B';
NODE_NAME     R4170 2
 '@T6G_MB_LIB.T6G(SCH_1):PAGE80_I220@PURE_QUANTA.Q_RES(CHIPS)':
 'B': CDS_PINID='B';
NET_NAME
'GPU_3V3IO_RSVD1_ISO_R'
 '@T6G_MB_LIB.T6G(SCH_1):GPU_3V3IO_RSVD1_ISO_R':
 C_SIGNAL='@t6g_mb_lib.t6g(sch_1):gpu_3v3io_rsvd1_iso_r';
NODE_NAME     U18 AB12
 '@T6G_MB_LIB.T6G(SCH_1):PAGE80_I216@PURE_QUANTA.LCMXO3LF9400C5BG484C(CHIPS)':
 'PB29A||PCLKT2_1': CDS_PINID='\pb29a||pclkt2_1\';
NODE_NAME     R4170 1
 '@T6G_MB_LIB.T6G(SCH_1):PAGE80_I220@PURE_QUANTA.Q_RES(CHIPS)':
 'A': CDS_PINID='A';
NET_NAME
'GPU_3V3IO_RSVD1_N'
 '@T6G_MB_LIB.T6G(SCH_1):GPU_3V3IO_RSVD1_N':
 C_SIGNAL='@t6g_mb_lib.t6g(sch_1):gpu_3v3io_rsvd1_n';
NODE_NAME     Q135 6
 '@T6G_MB_LIB.T6G(SCH_1):PAGE331_I25@PURE_QUANTA.MOSFET_NCH_DUAL(CHIPS)':
 'D1': CDS_PINID='D1';
NODE_NAME     R4164 2
 '@T6G_MB_LIB.T6G(SCH_1):PAGE331_I27@PURE_QUANTA.Q_RES(CHIPS)':
 'B': CDS_PINID='B';
NODE_NAME     Q135 5
 '@T6G_MB_LIB.T6G(SCH_1):PAGE331_I29@PURE_QUANTA.MOSFET_NCH_DUAL(CHIPS)':
 'G2': CDS_PINID='G2';
NET_NAME
'GPU_3V3IO_RSVD3'
 '@T6G_MB_LIB.T6G(SCH_1):GPU_3V3IO_RSVD3':
 C_SIGNAL='@t6g_mb_lib.t6g(sch_1):gpu_3v3io_rsvd3';
NODE_NAME     R4163 1
 '@T6G_MB_LIB.T6G(SCH_1):PAGE331_I8@PURE_QUANTA.Q_RES(CHIPS)':
 'A': CDS_PINID='A';
NODE_NAME     R4162 2
 '@T6G_MB_LIB.T6G(SCH_1):PAGE331_I9@PURE_QUANTA.Q_RES(CHIPS)':
 'B': CDS_PINID='B';
NODE_NAME     Q137 2
 '@T6G_MB_LIB.T6G(SCH_1):PAGE331_I21@PURE_QUANTA.MOSFET_NCH_DUAL(CHIPS)':
 'G1': CDS_PINID='G1';
NODE_NAME     R4570 1
 '@T6G_MB_LIB.T6G(SCH_1):PAGE331_I109@PURE_QUANTA.Q_RES(CHIPS)':
 'A': CDS_PINID='A';
NODE_NAME     J105 A5
 '@T6G_MB_LIB.T6G(SCH_1):PAGE326_I76@PURE_QUANTA.CONN112_10137002101LF(CHIPS)':
 'A5': CDS_PINID='A5';
NET_NAME
'GPU_3V3IO_RSVD3_FFU'
 '@T6G_MB_LIB.T6G(SCH_1):GPU_3V3IO_RSVD3_FFU':
 C_SIGNAL='@t6g_mb_lib.t6g(sch_1):gpu_3v3io_rsvd3_ffu';
NODE_NAME     J108 A1
 '@T6G_MB_LIB.T6G(SCH_1):PAGE320_I72@PURE_QUANTA.CONN112_10137002101LF(CHIPS)':
 'A1': CDS_PINID='A1';
NODE_NAME     R4132 1
 '@T6G_MB_LIB.T6G(SCH_1):PAGE332_I96@PURE_QUANTA.Q_RES(CHIPS)':
 'A': CDS_PINID='A';
NODE_NAME     R4131 2
 '@T6G_MB_LIB.T6G(SCH_1):PAGE332_I97@PURE_QUANTA.Q_RES(CHIPS)':
 'B': CDS_PINID='B';
NODE_NAME     Q130 2
 '@T6G_MB_LIB.T6G(SCH_1):PAGE332_I102@PURE_QUANTA.MOSFET_NCH_DUAL(CHIPS)':
 'G1': CDS_PINID='G1';
NODE_NAME     R4577 1
 '@T6G_MB_LIB.T6G(SCH_1):PAGE332_I109@PURE_QUANTA.Q_RES(CHIPS)':
 'A': CDS_PINID='A';
NET_NAME
'GPU_3V3IO_RSVD3_FFU_ISO'
 '@T6G_MB_LIB.T6G(SCH_1):GPU_3V3IO_RSVD3_FFU_ISO':
 C_SIGNAL='@t6g_mb_lib.t6g(sch_1):gpu_3v3io_rsvd3_ffu_iso';
NODE_NAME     R4146 2
 '@T6G_MB_LIB.T6G(SCH_1):PAGE79_I122@PURE_QUANTA.Q_RES(CHIPS)':
 'B': CDS_PINID='B';
NODE_NAME     R4577 2
 '@T6G_MB_LIB.T6G(SCH_1):PAGE332_I109@PURE_QUANTA.Q_RES(CHIPS)':
 'B': CDS_PINID='B';
NODE_NAME     Q130 3
 '@T6G_MB_LIB.T6G(SCH_1):PAGE332_I123@PURE_QUANTA.MOSFET_NCH_DUAL(CHIPS)':
 'D2': CDS_PINID='D2';
NODE_NAME     C16 1
 '@T6G_MB_LIB.T6G(SCH_1):PAGE332_I130@PURE_QUANTA.Q_CAP(CHIPS)':
 'A': CDS_PINID='A';
NODE_NAME     R4140 2
 '@T6G_MB_LIB.T6G(SCH_1):PAGE332_I131@PURE_QUANTA.Q_RES(CHIPS)':
 'B': CDS_PINID='B';
NET_NAME
'GPU_3V3IO_RSVD3_FFU_ISO_R'
 '@T6G_MB_LIB.T6G(SCH_1):GPU_3V3IO_RSVD3_FFU_ISO_R':
 C_SIGNAL='@t6g_mb_lib.t6g(sch_1):gpu_3v3io_rsvd3_ffu_iso_r';
NODE_NAME     U18 F12
 '@T6G_MB_LIB.T6G(SCH_1):PAGE79_I94@PURE_QUANTA.LCMXO3LF9400C5BG484C(CHIPS)':
 'PT28B': CDS_PINID='PT28B';
NODE_NAME     R4146 1
 '@T6G_MB_LIB.T6G(SCH_1):PAGE79_I122@PURE_QUANTA.Q_RES(CHIPS)':
 'A': CDS_PINID='A';
NET_NAME
'GPU_3V3IO_RSVD3_FFU_N'
 '@T6G_MB_LIB.T6G(SCH_1):GPU_3V3IO_RSVD3_FFU_N':
 C_SIGNAL='@t6g_mb_lib.t6g(sch_1):gpu_3v3io_rsvd3_ffu_n';
NODE_NAME     Q130 6
 '@T6G_MB_LIB.T6G(SCH_1):PAGE332_I102@PURE_QUANTA.MOSFET_NCH_DUAL(CHIPS)':
 'D1': CDS_PINID='D1';
NODE_NAME     R4137 2
 '@T6G_MB_LIB.T6G(SCH_1):PAGE332_I107@PURE_QUANTA.Q_RES(CHIPS)':
 'B': CDS_PINID='B';
NODE_NAME     Q130 5
 '@T6G_MB_LIB.T6G(SCH_1):PAGE332_I123@PURE_QUANTA.MOSFET_NCH_DUAL(CHIPS)':
 'G2': CDS_PINID='G2';
NET_NAME
'GPU_3V3IO_RSVD3_ISO'
 '@T6G_MB_LIB.T6G(SCH_1):GPU_3V3IO_RSVD3_ISO':
 C_SIGNAL='@t6g_mb_lib.t6g(sch_1):gpu_3v3io_rsvd3_iso';
NODE_NAME     Q137 3
 '@T6G_MB_LIB.T6G(SCH_1):PAGE331_I28@PURE_QUANTA.MOSFET_NCH_DUAL(CHIPS)':
 'D2': CDS_PINID='D2';
NODE_NAME     R4169 2
 '@T6G_MB_LIB.T6G(SCH_1):PAGE331_I39@PURE_QUANTA.Q_RES(CHIPS)':
 'B': CDS_PINID='B';
NODE_NAME     C7 1
 '@T6G_MB_LIB.T6G(SCH_1):PAGE331_I42@PURE_QUANTA.Q_CAP(CHIPS)':
 'A': CDS_PINID='A';
NODE_NAME     R4570 2
 '@T6G_MB_LIB.T6G(SCH_1):PAGE331_I109@PURE_QUANTA.Q_RES(CHIPS)':
 'B': CDS_PINID='B';
NODE_NAME     R4171 2
 '@T6G_MB_LIB.T6G(SCH_1):PAGE80_I223@PURE_QUANTA.Q_RES(CHIPS)':
 'B': CDS_PINID='B';
NET_NAME
'GPU_3V3IO_RSVD3_ISO_R'
 '@T6G_MB_LIB.T6G(SCH_1):GPU_3V3IO_RSVD3_ISO_R':
 C_SIGNAL='@t6g_mb_lib.t6g(sch_1):gpu_3v3io_rsvd3_iso_r';
NODE_NAME     U18 AA12
 '@T6G_MB_LIB.T6G(SCH_1):PAGE80_I216@PURE_QUANTA.LCMXO3LF9400C5BG484C(CHIPS)':
 'PB29B||PCLKC2_1': CDS_PINID='\pb29b||pclkc2_1\';
NODE_NAME     R4171 1
 '@T6G_MB_LIB.T6G(SCH_1):PAGE80_I223@PURE_QUANTA.Q_RES(CHIPS)':
 'A': CDS_PINID='A';
NET_NAME
'GPU_3V3IO_RSVD3_N'
 '@T6G_MB_LIB.T6G(SCH_1):GPU_3V3IO_RSVD3_N':
 C_SIGNAL='@t6g_mb_lib.t6g(sch_1):gpu_3v3io_rsvd3_n';
NODE_NAME     Q137 6
 '@T6G_MB_LIB.T6G(SCH_1):PAGE331_I21@PURE_QUANTA.MOSFET_NCH_DUAL(CHIPS)':
 'D1': CDS_PINID='D1';
NODE_NAME     R4166 2
 '@T6G_MB_LIB.T6G(SCH_1):PAGE331_I23@PURE_QUANTA.Q_RES(CHIPS)':
 'B': CDS_PINID='B';
NODE_NAME     Q137 5
 '@T6G_MB_LIB.T6G(SCH_1):PAGE331_I28@PURE_QUANTA.MOSFET_NCH_DUAL(CHIPS)':
 'G2': CDS_PINID='G2';
NET_NAME
'GPU_3V3IO_RSVD4'
 '@T6G_MB_LIB.T6G(SCH_1):GPU_3V3IO_RSVD4':
 C_SIGNAL='@t6g_mb_lib.t6g(sch_1):gpu_3v3io_rsvd4';
NODE_NAME     R4161 1
 '@T6G_MB_LIB.T6G(SCH_1):PAGE331_I2@PURE_QUANTA.Q_RES(CHIPS)':
 'A': CDS_PINID='A';
NODE_NAME     R4160 2
 '@T6G_MB_LIB.T6G(SCH_1):PAGE331_I4@PURE_QUANTA.Q_RES(CHIPS)':
 'B': CDS_PINID='B';
NODE_NAME     Q136 2
 '@T6G_MB_LIB.T6G(SCH_1):PAGE331_I17@PURE_QUANTA.MOSFET_NCH_DUAL(CHIPS)':
 'G1': CDS_PINID='G1';
NODE_NAME     R4571 1
 '@T6G_MB_LIB.T6G(SCH_1):PAGE331_I108@PURE_QUANTA.Q_RES(CHIPS)':
 'A': CDS_PINID='A';
NODE_NAME     J105 A1
 '@T6G_MB_LIB.T6G(SCH_1):PAGE326_I75@PURE_QUANTA.CONN112_10137002101LF(CHIPS)':
 'A1': CDS_PINID='A1';
NET_NAME
'GPU_3V3IO_RSVD4_ISO'
 '@T6G_MB_LIB.T6G(SCH_1):GPU_3V3IO_RSVD4_ISO':
 C_SIGNAL='@t6g_mb_lib.t6g(sch_1):gpu_3v3io_rsvd4_iso';
NODE_NAME     Q136 3
 '@T6G_MB_LIB.T6G(SCH_1):PAGE331_I22@PURE_QUANTA.MOSFET_NCH_DUAL(CHIPS)':
 'D2': CDS_PINID='D2';
NODE_NAME     C5 1
 '@T6G_MB_LIB.T6G(SCH_1):PAGE331_I33@PURE_QUANTA.Q_CAP(CHIPS)':
 'A': CDS_PINID='A';
NODE_NAME     R4168 2
 '@T6G_MB_LIB.T6G(SCH_1):PAGE331_I35@PURE_QUANTA.Q_RES(CHIPS)':
 'B': CDS_PINID='B';
NODE_NAME     R4571 2
 '@T6G_MB_LIB.T6G(SCH_1):PAGE331_I108@PURE_QUANTA.Q_RES(CHIPS)':
 'B': CDS_PINID='B';
NODE_NAME     R4172 2
 '@T6G_MB_LIB.T6G(SCH_1):PAGE80_I224@PURE_QUANTA.Q_RES(CHIPS)':
 'B': CDS_PINID='B';
NET_NAME
'GPU_3V3IO_RSVD4_ISO_R'
 '@T6G_MB_LIB.T6G(SCH_1):GPU_3V3IO_RSVD4_ISO_R':
 C_SIGNAL='@t6g_mb_lib.t6g(sch_1):gpu_3v3io_rsvd4_iso_r';
NODE_NAME     U18 V13
 '@T6G_MB_LIB.T6G(SCH_1):PAGE80_I216@PURE_QUANTA.LCMXO3LF9400C5BG484C(CHIPS)':
 'PB29C': CDS_PINID='PB29C';
NODE_NAME     R4172 1
 '@T6G_MB_LIB.T6G(SCH_1):PAGE80_I224@PURE_QUANTA.Q_RES(CHIPS)':
 'A': CDS_PINID='A';
NET_NAME
'GPU_3V3IO_RSVD4_N'
 '@T6G_MB_LIB.T6G(SCH_1):GPU_3V3IO_RSVD4_N':
 C_SIGNAL='@t6g_mb_lib.t6g(sch_1):gpu_3v3io_rsvd4_n';
NODE_NAME     Q136 6
 '@T6G_MB_LIB.T6G(SCH_1):PAGE331_I17@PURE_QUANTA.MOSFET_NCH_DUAL(CHIPS)':
 'D1': CDS_PINID='D1';
NODE_NAME     R4165 2
 '@T6G_MB_LIB.T6G(SCH_1):PAGE331_I18@PURE_QUANTA.Q_RES(CHIPS)':
 'B': CDS_PINID='B';
NODE_NAME     Q136 5
 '@T6G_MB_LIB.T6G(SCH_1):PAGE331_I22@PURE_QUANTA.MOSFET_NCH_DUAL(CHIPS)':
 'G2': CDS_PINID='G2';
NET_NAME
'GPU_3V3IO_RSVD5_FFU'
 '@T6G_MB_LIB.T6G(SCH_1):GPU_3V3IO_RSVD5_FFU':
 C_SIGNAL='@t6g_mb_lib.t6g(sch_1):gpu_3v3io_rsvd5_ffu';
NODE_NAME     J108 A5
 '@T6G_MB_LIB.T6G(SCH_1):PAGE320_I15@PURE_QUANTA.CONN112_10137002101LF(CHIPS)':
 'A5': CDS_PINID='A5';
NODE_NAME     R4134 1
 '@T6G_MB_LIB.T6G(SCH_1):PAGE332_I81@PURE_QUANTA.Q_RES(CHIPS)':
 'A': CDS_PINID='A';
NODE_NAME     R4133 2
 '@T6G_MB_LIB.T6G(SCH_1):PAGE332_I82@PURE_QUANTA.Q_RES(CHIPS)':
 'B': CDS_PINID='B';
NODE_NAME     Q129 2
 '@T6G_MB_LIB.T6G(SCH_1):PAGE332_I86@PURE_QUANTA.MOSFET_NCH_DUAL(CHIPS)':
 'G1': CDS_PINID='G1';
NODE_NAME     R4576 1
 '@T6G_MB_LIB.T6G(SCH_1):PAGE332_I91@PURE_QUANTA.Q_RES(CHIPS)':
 'A': CDS_PINID='A';
NET_NAME
'GPU_3V3IO_RSVD5_FFU_ISO'
 '@T6G_MB_LIB.T6G(SCH_1):GPU_3V3IO_RSVD5_FFU_ISO':
 C_SIGNAL='@t6g_mb_lib.t6g(sch_1):gpu_3v3io_rsvd5_ffu_iso';
NODE_NAME     R4148 2
 '@T6G_MB_LIB.T6G(SCH_1):PAGE80_I242@PURE_QUANTA.Q_RES(CHIPS)':
 'B': CDS_PINID='B';
NODE_NAME     R4576 2
 '@T6G_MB_LIB.T6G(SCH_1):PAGE332_I91@PURE_QUANTA.Q_RES(CHIPS)':
 'B': CDS_PINID='B';
NODE_NAME     Q129 3
 '@T6G_MB_LIB.T6G(SCH_1):PAGE332_I113@PURE_QUANTA.MOSFET_NCH_DUAL(CHIPS)':
 'D2': CDS_PINID='D2';
NODE_NAME     R4141 2
 '@T6G_MB_LIB.T6G(SCH_1):PAGE332_I114@PURE_QUANTA.Q_RES(CHIPS)':
 'B': CDS_PINID='B';
NODE_NAME     C17 1
 '@T6G_MB_LIB.T6G(SCH_1):PAGE332_I118@PURE_QUANTA.Q_CAP(CHIPS)':
 'A': CDS_PINID='A';
NET_NAME
'GPU_3V3IO_RSVD5_FFU_ISO_R'
 '@T6G_MB_LIB.T6G(SCH_1):GPU_3V3IO_RSVD5_FFU_ISO_R':
 C_SIGNAL='@t6g_mb_lib.t6g(sch_1):gpu_3v3io_rsvd5_ffu_iso_r';
NODE_NAME     U18 AB14
 '@T6G_MB_LIB.T6G(SCH_1):PAGE80_I216@PURE_QUANTA.LCMXO3LF9400C5BG484C(CHIPS)':
 'PB33A': CDS_PINID='PB33A';
NODE_NAME     R4148 1
 '@T6G_MB_LIB.T6G(SCH_1):PAGE80_I242@PURE_QUANTA.Q_RES(CHIPS)':
 'A': CDS_PINID='A';
NET_NAME
'GPU_3V3IO_RSVD5_FFU_N'
 '@T6G_MB_LIB.T6G(SCH_1):GPU_3V3IO_RSVD5_FFU_N':
 C_SIGNAL='@t6g_mb_lib.t6g(sch_1):gpu_3v3io_rsvd5_ffu_n';
NODE_NAME     Q129 6
 '@T6G_MB_LIB.T6G(SCH_1):PAGE332_I86@PURE_QUANTA.MOSFET_NCH_DUAL(CHIPS)':
 'D1': CDS_PINID='D1';
NODE_NAME     R4138 2
 '@T6G_MB_LIB.T6G(SCH_1):PAGE332_I88@PURE_QUANTA.Q_RES(CHIPS)':
 'B': CDS_PINID='B';
NODE_NAME     Q129 5
 '@T6G_MB_LIB.T6G(SCH_1):PAGE332_I113@PURE_QUANTA.MOSFET_NCH_DUAL(CHIPS)':
 'G2': CDS_PINID='G2';
NET_NAME
'GPU_BASE_HMC_READY'
 '@T6G_MB_LIB.T6G(SCH_1):GPU_BASE_HMC_READY':
 C_SIGNAL='@t6g_mb_lib.t6g(sch_1):gpu_base_hmc_ready';
NODE_NAME     Q102 2
 '@T6G_MB_LIB.T6G(SCH_1):PAGE299_I40@PURE_QUANTA.MOSFET_NCH_DUAL(CHIPS)':
 'G1': CDS_PINID='G1';
NODE_NAME     R3429 2
 '@T6G_MB_LIB.T6G(SCH_1):PAGE299_I130@PURE_QUANTA.Q_RES(CHIPS)':
 'B': CDS_PINID='B';
NODE_NAME     R3463 1
 '@T6G_MB_LIB.T6G(SCH_1):PAGE299_I131@PURE_QUANTA.Q_RES(CHIPS)':
 'A': CDS_PINID='A';
NODE_NAME     J110 A5
 '@T6G_MB_LIB.T6G(SCH_1):PAGE318_I16@PURE_QUANTA.CONN112_10137002101LF(CHIPS)':
 'A5': CDS_PINID='A5';
NET_NAME
'GPU_BASE_HMC_READY_ISO'
 '@T6G_MB_LIB.T6G(SCH_1):GPU_BASE_HMC_READY_ISO':
 C_SIGNAL='@t6g_mb_lib.t6g(sch_1):gpu_base_hmc_ready_iso';
NODE_NAME     Q102 3
 '@T6G_MB_LIB.T6G(SCH_1):PAGE299_I48@PURE_QUANTA.MOSFET_NCH_DUAL(CHIPS)':
 'D2': CDS_PINID='D2';
NODE_NAME     R3438 2
 '@T6G_MB_LIB.T6G(SCH_1):PAGE299_I55@PURE_QUANTA.Q_RES(CHIPS)':
 'B': CDS_PINID='B';
NODE_NAME     C1973 1
 '@T6G_MB_LIB.T6G(SCH_1):PAGE299_I71@PURE_QUANTA.Q_CAP(CHIPS)':
 'A': CDS_PINID='A';
NODE_NAME     R3480 2
 '@T6G_MB_LIB.T6G(SCH_1):PAGE80_I247@PURE_QUANTA.Q_RES(CHIPS)':
 'B': CDS_PINID='B';
NET_NAME
'GPU_BASE_HMC_READY_ISO_R'
 '@T6G_MB_LIB.T6G(SCH_1):GPU_BASE_HMC_READY_ISO_R':
 C_SIGNAL='@t6g_mb_lib.t6g(sch_1):gpu_base_hmc_ready_iso_r';
NODE_NAME     U18 AB15
 '@T6G_MB_LIB.T6G(SCH_1):PAGE80_I216@PURE_QUANTA.LCMXO3LF9400C5BG484C(CHIPS)':
 'PB35A': CDS_PINID='PB35A';
NODE_NAME     R3480 1
 '@T6G_MB_LIB.T6G(SCH_1):PAGE80_I247@PURE_QUANTA.Q_RES(CHIPS)':
 'A': CDS_PINID='A';
NET_NAME
'GPU_BASE_HMC_READY_N'
 '@T6G_MB_LIB.T6G(SCH_1):GPU_BASE_HMC_READY_N':
 C_SIGNAL='@t6g_mb_lib.t6g(sch_1):gpu_base_hmc_ready_n';
NODE_NAME     Q102 6
 '@T6G_MB_LIB.T6G(SCH_1):PAGE299_I40@PURE_QUANTA.MOSFET_NCH_DUAL(CHIPS)':
 'D1': CDS_PINID='D1';
NODE_NAME     Q102 5
 '@T6G_MB_LIB.T6G(SCH_1):PAGE299_I48@PURE_QUANTA.MOSFET_NCH_DUAL(CHIPS)':
 'G2': CDS_PINID='G2';
NODE_NAME     R3433 2
 '@T6G_MB_LIB.T6G(SCH_1):PAGE299_I49@PURE_QUANTA.Q_RES(CHIPS)':
 'B': CDS_PINID='B';
NET_NAME
'GPU_BASE_ID0'
 '@T6G_MB_LIB.T6G(SCH_1):GPU_BASE_ID0':
 C_SIGNAL='@t6g_mb_lib.t6g(sch_1):gpu_base_id0';
NODE_NAME     J111 A3
 '@T6G_MB_LIB.T6G(SCH_1):PAGE328_I76@PURE_QUANTA.CONN112_10137002101LF(CHIPS)':
 'A3': CDS_PINID='A3';
NODE_NAME     R3516 1
 '@T6G_MB_LIB.T6G(SCH_1):PAGE246_I56@PURE_QUANTA.Q_RES(CHIPS)':
 'A': CDS_PINID='A';
NODE_NAME     R3440 1
 '@T6G_MB_LIB.T6G(SCH_1):PAGE330_I65@PURE_QUANTA.Q_RES(CHIPS)':
 'A': CDS_PINID='A';
NET_NAME
'GPU_BASE_ID0_R'
 '@T6G_MB_LIB.T6G(SCH_1):GPU_BASE_ID0_R':
 C_SIGNAL='@t6g_mb_lib.t6g(sch_1):gpu_base_id0_r';
NODE_NAME     R3516 2
 '@T6G_MB_LIB.T6G(SCH_1):PAGE246_I56@PURE_QUANTA.Q_RES(CHIPS)':
 'B': CDS_PINID='B';
NODE_NAME     U181 15
 '@T6G_MB_LIB.T6G(SCH_1):PAGE246_I83@PURE_QUANTA.PCA9539RPW(CHIPS)':
 'IO1_2': CDS_PINID='IO1_2';
NET_NAME
'GPU_BASE_ID1'
 '@T6G_MB_LIB.T6G(SCH_1):GPU_BASE_ID1':
 C_SIGNAL='@t6g_mb_lib.t6g(sch_1):gpu_base_id1';
NODE_NAME     J111 N8
 '@T6G_MB_LIB.T6G(SCH_1):PAGE328_I38@PURE_QUANTA.CONN112_10137002101LF(CHIPS)':
 'N8': CDS_PINID='N8';
NODE_NAME     R3499 1
 '@T6G_MB_LIB.T6G(SCH_1):PAGE246_I57@PURE_QUANTA.Q_RES(CHIPS)':
 'A': CDS_PINID='A';
NODE_NAME     R3441 1
 '@T6G_MB_LIB.T6G(SCH_1):PAGE330_I64@PURE_QUANTA.Q_RES(CHIPS)':
 'A': CDS_PINID='A';
NET_NAME
'GPU_BASE_ID1_R'
 '@T6G_MB_LIB.T6G(SCH_1):GPU_BASE_ID1_R':
 C_SIGNAL='@t6g_mb_lib.t6g(sch_1):gpu_base_id1_r';
NODE_NAME     R3499 2
 '@T6G_MB_LIB.T6G(SCH_1):PAGE246_I57@PURE_QUANTA.Q_RES(CHIPS)':
 'B': CDS_PINID='B';
NODE_NAME     U181 16
 '@T6G_MB_LIB.T6G(SCH_1):PAGE246_I83@PURE_QUANTA.PCA9539RPW(CHIPS)':
 'IO1_3': CDS_PINID='IO1_3';
NET_NAME
'GPU_BASE_STBY_EN'
 '@T6G_MB_LIB.T6G(SCH_1):GPU_BASE_STBY_EN':
 C_SIGNAL='@t6g_mb_lib.t6g(sch_1):gpu_base_stby_en';
NODE_NAME     U253 3
 '@T6G_MB_LIB.T6G(SCH_1):PAGE334_I26@PURE_QUANTA.74LVC2G17GW(CHIPS)':
 'A1': CDS_PINID='A1';
NODE_NAME     R3452 1
 '@T6G_MB_LIB.T6G(SCH_1):PAGE334_I95@PURE_QUANTA.Q_RES(CHIPS)':
 'A': CDS_PINID='A';
NODE_NAME     R3451 2
 '@T6G_MB_LIB.T6G(SCH_1):PAGE334_I127@PURE_QUANTA.Q_RES(CHIPS)':
 'B': CDS_PINID='B';
NODE_NAME     R3479 2
 '@T6G_MB_LIB.T6G(SCH_1):PAGE80_I281@PURE_QUANTA.Q_RES(CHIPS)':
 'B': CDS_PINID='B';
NET_NAME
'GPU_BASE_STBY_EN_BUF'
 '@T6G_MB_LIB.T6G(SCH_1):GPU_BASE_STBY_EN_BUF':
 C_SIGNAL='@t6g_mb_lib.t6g(sch_1):gpu_base_stby_en_buf';
NODE_NAME     R3392 2
 '@T6G_MB_LIB.T6G(SCH_1):PAGE334_I62@PURE_QUANTA.Q_RES(CHIPS)':
 'B': CDS_PINID='B';
NODE_NAME     J110 A7
 '@T6G_MB_LIB.T6G(SCH_1):PAGE318_I16@PURE_QUANTA.CONN112_10137002101LF(CHIPS)':
 'A7': CDS_PINID='A7';
NET_NAME
'GPU_BASE_STBY_EN_BUF_R'
 '@T6G_MB_LIB.T6G(SCH_1):GPU_BASE_STBY_EN_BUF_R':
 C_SIGNAL='@t6g_mb_lib.t6g(sch_1):gpu_base_stby_en_buf_r';
NODE_NAME     U253 4
 '@T6G_MB_LIB.T6G(SCH_1):PAGE334_I26@PURE_QUANTA.74LVC2G17GW(CHIPS)':
 'B1': CDS_PINID='B1';
NODE_NAME     R3392 1
 '@T6G_MB_LIB.T6G(SCH_1):PAGE334_I62@PURE_QUANTA.Q_RES(CHIPS)':
 'A': CDS_PINID='A';
NODE_NAME     R3457 1
 '@T6G_MB_LIB.T6G(SCH_1):PAGE334_I123@PURE_QUANTA.Q_RES(CHIPS)':
 'A': CDS_PINID='A';
NODE_NAME     R3456 2
 '@T6G_MB_LIB.T6G(SCH_1):PAGE334_I124@PURE_QUANTA.Q_RES(CHIPS)':
 'B': CDS_PINID='B';
NET_NAME
'GPU_BASE_STBY_EN_R'
 '@T6G_MB_LIB.T6G(SCH_1):GPU_BASE_STBY_EN_R':
 C_SIGNAL='@t6g_mb_lib.t6g(sch_1):gpu_base_stby_en_r';
NODE_NAME     U18 Y19
 '@T6G_MB_LIB.T6G(SCH_1):PAGE80_I216@PURE_QUANTA.LCMXO3LF9400C5BG484C(CHIPS)':
 'PB44C': CDS_PINID='PB44C';
NODE_NAME     R3479 1
 '@T6G_MB_LIB.T6G(SCH_1):PAGE80_I281@PURE_QUANTA.Q_RES(CHIPS)':
 'A': CDS_PINID='A';
NET_NAME
'GPU_FPGA_BOOT_EN'
 '@T6G_MB_LIB.T6G(SCH_1):GPU_FPGA_BOOT_EN':
 C_SIGNAL='@t6g_mb_lib.t6g(sch_1):gpu_fpga_boot_en';
NODE_NAME     U253 1
 '@T6G_MB_LIB.T6G(SCH_1):PAGE334_I26@PURE_QUANTA.74LVC2G17GW(CHIPS)':
 'A0': CDS_PINID='A0';
NODE_NAME     R3448 2
 '@T6G_MB_LIB.T6G(SCH_1):PAGE334_I168@PURE_QUANTA.Q_RES(CHIPS)':
 'B': CDS_PINID='B';
NODE_NAME     R3449 1
 '@T6G_MB_LIB.T6G(SCH_1):PAGE334_I170@PURE_QUANTA.Q_RES(CHIPS)':
 'A': CDS_PINID='A';
NODE_NAME     R3482 2
 '@T6G_MB_LIB.T6G(SCH_1):PAGE80_I278@PURE_QUANTA.Q_RES(CHIPS)':
 'B': CDS_PINID='B';
NET_NAME
'GPU_FPGA_BOOT_EN_BUF'
 '@T6G_MB_LIB.T6G(SCH_1):GPU_FPGA_BOOT_EN_BUF':
 C_SIGNAL='@t6g_mb_lib.t6g(sch_1):gpu_fpga_boot_en_buf';
NODE_NAME     R3390 2
 '@T6G_MB_LIB.T6G(SCH_1):PAGE334_I162@PURE_QUANTA.Q_RES(CHIPS)':
 'B': CDS_PINID='B';
NODE_NAME     J110 N2
 '@T6G_MB_LIB.T6G(SCH_1):PAGE318_I76@PURE_QUANTA.CONN112_10137002101LF(CHIPS)':
 'N2': CDS_PINID='N2';
NET_NAME
'GPU_FPGA_BOOT_EN_BUF_R'
 '@T6G_MB_LIB.T6G(SCH_1):GPU_FPGA_BOOT_EN_BUF_R':
 C_SIGNAL='@t6g_mb_lib.t6g(sch_1):gpu_fpga_boot_en_buf_r';
NODE_NAME     U253 6
 '@T6G_MB_LIB.T6G(SCH_1):PAGE334_I26@PURE_QUANTA.74LVC2G17GW(CHIPS)':
 'B0': CDS_PINID='B0';
NODE_NAME     R3390 1
 '@T6G_MB_LIB.T6G(SCH_1):PAGE334_I162@PURE_QUANTA.Q_RES(CHIPS)':
 'A': CDS_PINID='A';
NODE_NAME     R3453 2
 '@T6G_MB_LIB.T6G(SCH_1):PAGE334_I164@PURE_QUANTA.Q_RES(CHIPS)':
 'B': CDS_PINID='B';
NODE_NAME     R3454 1
 '@T6G_MB_LIB.T6G(SCH_1):PAGE334_I165@PURE_QUANTA.Q_RES(CHIPS)':
 'A': CDS_PINID='A';
NET_NAME
'GPU_FPGA_BOOT_EN_R'
 '@T6G_MB_LIB.T6G(SCH_1):GPU_FPGA_BOOT_EN_R':
 C_SIGNAL='@t6g_mb_lib.t6g(sch_1):gpu_fpga_boot_en_r';
NODE_NAME     U18 T15
 '@T6G_MB_LIB.T6G(SCH_1):PAGE80_I216@PURE_QUANTA.LCMXO3LF9400C5BG484C(CHIPS)':
 'PB43C': CDS_PINID='PB43C';
NODE_NAME     R3482 1
 '@T6G_MB_LIB.T6G(SCH_1):PAGE80_I278@PURE_QUANTA.Q_RES(CHIPS)':
 'A': CDS_PINID='A';
NET_NAME
'GPU_FPGA_EROT_FATALERR'
 '@T6G_MB_LIB.T6G(SCH_1):GPU_FPGA_EROT_FATALERR':
 C_SIGNAL='@t6g_mb_lib.t6g(sch_1):gpu_fpga_erot_fatalerr';
NODE_NAME     Q108 5
 '@T6G_MB_LIB.T6G(SCH_1):PAGE299_I168@PURE_QUANTA.MOSFET_NCH_DUAL(CHIPS)':
 'G2': CDS_PINID='G2';
NODE_NAME     Q108 6
 '@T6G_MB_LIB.T6G(SCH_1):PAGE299_I169@PURE_QUANTA.MOSFET_NCH_DUAL(CHIPS)':
 'D1': CDS_PINID='D1';
NODE_NAME     R3503 2
 '@T6G_MB_LIB.T6G(SCH_1):PAGE299_I177@PURE_QUANTA.Q_RES(CHIPS)':
 'B': CDS_PINID='B';
NET_NAME
'GPU_FPGA_EROT_FATALERR_ISO_N'
 '@T6G_MB_LIB.T6G(SCH_1):GPU_FPGA_EROT_FATALERR_ISO_N':
 C_SIGNAL='@t6g_mb_lib.t6g(sch_1):gpu_fpga_erot_fatalerr_iso_n';
NODE_NAME     Q108 3
 '@T6G_MB_LIB.T6G(SCH_1):PAGE299_I168@PURE_QUANTA.MOSFET_NCH_DUAL(CHIPS)':
 'D2': CDS_PINID='D2';
NODE_NAME     C1988 1
 '@T6G_MB_LIB.T6G(SCH_1):PAGE299_I171@PURE_QUANTA.Q_CAP(CHIPS)':
 'A': CDS_PINID='A';
NODE_NAME     R3504 2
 '@T6G_MB_LIB.T6G(SCH_1):PAGE299_I174@PURE_QUANTA.Q_RES(CHIPS)':
 'B': CDS_PINID='B';
NODE_NAME     R3505 2
 '@T6G_MB_LIB.T6G(SCH_1):PAGE80_I259@PURE_QUANTA.Q_RES(CHIPS)':
 'B': CDS_PINID='B';
NET_NAME
'GPU_FPGA_EROT_FATALERR_ISO_R_N'
 '@T6G_MB_LIB.T6G(SCH_1):GPU_FPGA_EROT_FATALERR_ISO_R_N':
 C_SIGNAL='@t6g_mb_lib.t6g(sch_1):gpu_fpga_erot_fatalerr_iso_r_n';
NODE_NAME     U18 AA16
 '@T6G_MB_LIB.T6G(SCH_1):PAGE80_I216@PURE_QUANTA.LCMXO3LF9400C5BG484C(CHIPS)':
 'PB38B': CDS_PINID='PB38B';
NODE_NAME     R3505 1
 '@T6G_MB_LIB.T6G(SCH_1):PAGE80_I259@PURE_QUANTA.Q_RES(CHIPS)':
 'A': CDS_PINID='A';
NET_NAME
'GPU_FPGA_EROT_FATALERR_N'
 '@T6G_MB_LIB.T6G(SCH_1):GPU_FPGA_EROT_FATALERR_N':
 C_SIGNAL='@t6g_mb_lib.t6g(sch_1):gpu_fpga_erot_fatalerr_n';
NODE_NAME     Q108 2
 '@T6G_MB_LIB.T6G(SCH_1):PAGE299_I169@PURE_QUANTA.MOSFET_NCH_DUAL(CHIPS)':
 'G1': CDS_PINID='G1';
NODE_NAME     R3502 1
 '@T6G_MB_LIB.T6G(SCH_1):PAGE299_I181@PURE_QUANTA.Q_RES(CHIPS)':
 'A': CDS_PINID='A';
NODE_NAME     R3525 2
 '@T6G_MB_LIB.T6G(SCH_1):PAGE299_I184@PURE_QUANTA.Q_RES(CHIPS)':
 'B': CDS_PINID='B';
NODE_NAME     J109 N2
 '@T6G_MB_LIB.T6G(SCH_1):PAGE319_I76@PURE_QUANTA.CONN112_10137002101LF(CHIPS)':
 'N2': CDS_PINID='N2';
NET_NAME
'GPU_FPGA_EROT_RECOV_BUF_N'
 '@T6G_MB_LIB.T6G(SCH_1):GPU_FPGA_EROT_RECOV_BUF_N':
 C_SIGNAL='@t6g_mb_lib.t6g(sch_1):gpu_fpga_erot_recov_buf_n';
NODE_NAME     R3497 2
 '@T6G_MB_LIB.T6G(SCH_1):PAGE255_I53@PURE_QUANTA.Q_RES(CHIPS)':
 'B': CDS_PINID='B';
NODE_NAME     J110 A1
 '@T6G_MB_LIB.T6G(SCH_1):PAGE318_I76@PURE_QUANTA.CONN112_10137002101LF(CHIPS)':
 'A1': CDS_PINID='A1';
NET_NAME
'GPU_FPGA_EROT_RECOV_BUF_R_N'
 '@T6G_MB_LIB.T6G(SCH_1):GPU_FPGA_EROT_RECOV_BUF_R_N':
 C_SIGNAL='@t6g_mb_lib.t6g(sch_1):gpu_fpga_erot_recov_buf_r_n';
NODE_NAME     U257 6
 '@T6G_MB_LIB.T6G(SCH_1):PAGE255_I50@PURE_QUANTA.74LVC2G07DW7(CHIPS)':
 '1Y': CDS_PINID='\1y\';
NODE_NAME     R3497 1
 '@T6G_MB_LIB.T6G(SCH_1):PAGE255_I53@PURE_QUANTA.Q_RES(CHIPS)':
 'A': CDS_PINID='A';
NODE_NAME     R3494 2
 '@T6G_MB_LIB.T6G(SCH_1):PAGE255_I55@PURE_QUANTA.Q_RES(CHIPS)':
 'B': CDS_PINID='B';
NODE_NAME     R3495 1
 '@T6G_MB_LIB.T6G(SCH_1):PAGE255_I62@PURE_QUANTA.Q_RES(CHIPS)':
 'A': CDS_PINID='A';
NET_NAME
'GPU_FPGA_EROT_RECOV_N'
 '@T6G_MB_LIB.T6G(SCH_1):GPU_FPGA_EROT_RECOV_N':
 C_SIGNAL='@t6g_mb_lib.t6g(sch_1):gpu_fpga_erot_recov_n';
NODE_NAME     U257 1
 '@T6G_MB_LIB.T6G(SCH_1):PAGE255_I50@PURE_QUANTA.74LVC2G07DW7(CHIPS)':
 '1A': CDS_PINID='\1a\';
NODE_NAME     R3490 2
 '@T6G_MB_LIB.T6G(SCH_1):PAGE255_I57@PURE_QUANTA.Q_RES(CHIPS)':
 'B': CDS_PINID='B';
NODE_NAME     R3491 1
 '@T6G_MB_LIB.T6G(SCH_1):PAGE255_I70@PURE_QUANTA.Q_RES(CHIPS)':
 'A': CDS_PINID='A';
NODE_NAME     R3483 1
 '@T6G_MB_LIB.T6G(SCH_1):PAGE80_I290@PURE_QUANTA.Q_RES(CHIPS)':
 'A': CDS_PINID='A';
NET_NAME
'GPU_FPGA_EROT_RECOV_R_N'
 '@T6G_MB_LIB.T6G(SCH_1):GPU_FPGA_EROT_RECOV_R_N':
 C_SIGNAL='@t6g_mb_lib.t6g(sch_1):gpu_fpga_erot_recov_r_n';
NODE_NAME     U18 AA5
 '@T6G_MB_LIB.T6G(SCH_1):PAGE80_I216@PURE_QUANTA.LCMXO3LF9400C5BG484C(CHIPS)':
 'PB10A': CDS_PINID='PB10A';
NODE_NAME     R3483 2
 '@T6G_MB_LIB.T6G(SCH_1):PAGE80_I290@PURE_QUANTA.Q_RES(CHIPS)':
 'B': CDS_PINID='B';
NET_NAME
'GPU_FPGA_EROT_RST_BUF_N'
 '@T6G_MB_LIB.T6G(SCH_1):GPU_FPGA_EROT_RST_BUF_N':
 C_SIGNAL='@t6g_mb_lib.t6g(sch_1):gpu_fpga_erot_rst_buf_n';
NODE_NAME     R3496 2
 '@T6G_MB_LIB.T6G(SCH_1):PAGE255_I45@PURE_QUANTA.Q_RES(CHIPS)':
 'B': CDS_PINID='B';
NODE_NAME     J110 N8
 '@T6G_MB_LIB.T6G(SCH_1):PAGE318_I16@PURE_QUANTA.CONN112_10137002101LF(CHIPS)':
 'N8': CDS_PINID='N8';
NET_NAME
'GPU_FPGA_EROT_RST_BUF_R_N'
 '@T6G_MB_LIB.T6G(SCH_1):GPU_FPGA_EROT_RST_BUF_R_N':
 C_SIGNAL='@t6g_mb_lib.t6g(sch_1):gpu_fpga_erot_rst_buf_r_n';
NODE_NAME     U255 4
 '@T6G_MB_LIB.T6G(SCH_1):PAGE255_I16@PURE_QUANTA.74LVC2G07DW7(CHIPS)':
 '2Y': CDS_PINID='\2y\';
NODE_NAME     R3496 1
 '@T6G_MB_LIB.T6G(SCH_1):PAGE255_I45@PURE_QUANTA.Q_RES(CHIPS)':
 'A': CDS_PINID='A';
NODE_NAME     R3492 2
 '@T6G_MB_LIB.T6G(SCH_1):PAGE255_I47@PURE_QUANTA.Q_RES(CHIPS)':
 'B': CDS_PINID='B';
NODE_NAME     R3493 1
 '@T6G_MB_LIB.T6G(SCH_1):PAGE255_I48@PURE_QUANTA.Q_RES(CHIPS)':
 'A': CDS_PINID='A';
NET_NAME
'GPU_FPGA_EROT_RST_N'
 '@T6G_MB_LIB.T6G(SCH_1):GPU_FPGA_EROT_RST_N':
 C_SIGNAL='@t6g_mb_lib.t6g(sch_1):gpu_fpga_erot_rst_n';
NODE_NAME     U255 3
 '@T6G_MB_LIB.T6G(SCH_1):PAGE255_I16@PURE_QUANTA.74LVC2G07DW7(CHIPS)':
 '2A': CDS_PINID='\2a\';
NODE_NAME     R3488 2
 '@T6G_MB_LIB.T6G(SCH_1):PAGE255_I40@PURE_QUANTA.Q_RES(CHIPS)':
 'B': CDS_PINID='B';
NODE_NAME     R3489 1
 '@T6G_MB_LIB.T6G(SCH_1):PAGE255_I42@PURE_QUANTA.Q_RES(CHIPS)':
 'A': CDS_PINID='A';
NODE_NAME     R3478 1
 '@T6G_MB_LIB.T6G(SCH_1):PAGE80_I288@PURE_QUANTA.Q_RES(CHIPS)':
 'A': CDS_PINID='A';
NET_NAME
'GPU_FPGA_EROT_RST_R_N'
 '@T6G_MB_LIB.T6G(SCH_1):GPU_FPGA_EROT_RST_R_N':
 C_SIGNAL='@t6g_mb_lib.t6g(sch_1):gpu_fpga_erot_rst_r_n';
NODE_NAME     U18 AA4
 '@T6G_MB_LIB.T6G(SCH_1):PAGE80_I216@PURE_QUANTA.LCMXO3LF9400C5BG484C(CHIPS)':
 'PB8A': CDS_PINID='PB8A';
NODE_NAME     R3478 2
 '@T6G_MB_LIB.T6G(SCH_1):PAGE80_I288@PURE_QUANTA.Q_RES(CHIPS)':
 'B': CDS_PINID='B';
NET_NAME
'GPU_FPGA_OVERT'
 '@T6G_MB_LIB.T6G(SCH_1):GPU_FPGA_OVERT':
 C_SIGNAL='@t6g_mb_lib.t6g(sch_1):gpu_fpga_overt';
NODE_NAME     Q104 6
 '@T6G_MB_LIB.T6G(SCH_1):PAGE299_I21@PURE_QUANTA.MOSFET_NCH_DUAL(CHIPS)':
 'D1': CDS_PINID='D1';
NODE_NAME     R3435 2
 '@T6G_MB_LIB.T6G(SCH_1):PAGE299_I23@PURE_QUANTA.Q_RES(CHIPS)':
 'B': CDS_PINID='B';
NODE_NAME     Q104 5
 '@T6G_MB_LIB.T6G(SCH_1):PAGE299_I26@PURE_QUANTA.MOSFET_NCH_DUAL(CHIPS)':
 'G2': CDS_PINID='G2';
NET_NAME
'GPU_FPGA_OVERT_ISO_N'
 '@T6G_MB_LIB.T6G(SCH_1):GPU_FPGA_OVERT_ISO_N':
 C_SIGNAL='@t6g_mb_lib.t6g(sch_1):gpu_fpga_overt_iso_n';
NODE_NAME     Q104 3
 '@T6G_MB_LIB.T6G(SCH_1):PAGE299_I26@PURE_QUANTA.MOSFET_NCH_DUAL(CHIPS)':
 'D2': CDS_PINID='D2';
NODE_NAME     R3437 2
 '@T6G_MB_LIB.T6G(SCH_1):PAGE299_I27@PURE_QUANTA.Q_RES(CHIPS)':
 'B': CDS_PINID='B';
NODE_NAME     C1976 1
 '@T6G_MB_LIB.T6G(SCH_1):PAGE299_I30@PURE_QUANTA.Q_CAP(CHIPS)':
 'A': CDS_PINID='A';
NODE_NAME     R3484 2
 '@T6G_MB_LIB.T6G(SCH_1):PAGE80_I254@PURE_QUANTA.Q_RES(CHIPS)':
 'B': CDS_PINID='B';
NET_NAME
'GPU_FPGA_OVERT_ISO_R_N'
 '@T6G_MB_LIB.T6G(SCH_1):GPU_FPGA_OVERT_ISO_R_N':
 C_SIGNAL='@t6g_mb_lib.t6g(sch_1):gpu_fpga_overt_iso_r_n';
NODE_NAME     U18 Y15
 '@T6G_MB_LIB.T6G(SCH_1):PAGE80_I216@PURE_QUANTA.LCMXO3LF9400C5BG484C(CHIPS)':
 'PB35C': CDS_PINID='PB35C';
NODE_NAME     R3484 1
 '@T6G_MB_LIB.T6G(SCH_1):PAGE80_I254@PURE_QUANTA.Q_RES(CHIPS)':
 'A': CDS_PINID='A';
NET_NAME
'GPU_FPGA_OVERT_N'
 '@T6G_MB_LIB.T6G(SCH_1):GPU_FPGA_OVERT_N':
 C_SIGNAL='@t6g_mb_lib.t6g(sch_1):gpu_fpga_overt_n';
NODE_NAME     R3430 1
 '@T6G_MB_LIB.T6G(SCH_1):PAGE299_I3@PURE_QUANTA.Q_RES(CHIPS)':
 'A': CDS_PINID='A';
NODE_NAME     Q104 2
 '@T6G_MB_LIB.T6G(SCH_1):PAGE299_I21@PURE_QUANTA.MOSFET_NCH_DUAL(CHIPS)':
 'G1': CDS_PINID='G1';
NODE_NAME     R3464 2
 '@T6G_MB_LIB.T6G(SCH_1):PAGE299_I134@PURE_QUANTA.Q_RES(CHIPS)':
 'B': CDS_PINID='B';
NODE_NAME     J108 A7
 '@T6G_MB_LIB.T6G(SCH_1):PAGE320_I15@PURE_QUANTA.CONN112_10137002101LF(CHIPS)':
 'A7': CDS_PINID='A7';
NET_NAME
'GPU_FPGA_READY'
 '@T6G_MB_LIB.T6G(SCH_1):GPU_FPGA_READY':
 C_SIGNAL='@t6g_mb_lib.t6g(sch_1):gpu_fpga_ready';
NODE_NAME     Q96 2
 '@T6G_MB_LIB.T6G(SCH_1):PAGE333_I154@PURE_QUANTA.MOSFET_NCH_DUAL(CHIPS)':
 'G1': CDS_PINID='G1';
NODE_NAME     R3318 2
 '@T6G_MB_LIB.T6G(SCH_1):PAGE333_I171@PURE_QUANTA.Q_RES(CHIPS)':
 'B': CDS_PINID='B';
NODE_NAME     R3511 1
 '@T6G_MB_LIB.T6G(SCH_1):PAGE333_I172@PURE_QUANTA.Q_RES(CHIPS)':
 'A': CDS_PINID='A';
NODE_NAME     J112 T2
 '@T6G_MB_LIB.T6G(SCH_1):PAGE329_I102@PURE_QUANTA.CONN160_10131762101LF(CHIPS)':
 'T2': CDS_PINID='T2';
NET_NAME
'GPU_FPGA_READY_ISO'
 '@T6G_MB_LIB.T6G(SCH_1):GPU_FPGA_READY_ISO':
 C_SIGNAL='@t6g_mb_lib.t6g(sch_1):gpu_fpga_ready_iso';
NODE_NAME     C1881 1
 '@T6G_MB_LIB.T6G(SCH_1):PAGE333_I156@PURE_QUANTA.Q_CAP(CHIPS)':
 'A': CDS_PINID='A';
NODE_NAME     R3321 2
 '@T6G_MB_LIB.T6G(SCH_1):PAGE333_I158@PURE_QUANTA.Q_RES(CHIPS)':
 'B': CDS_PINID='B';
NODE_NAME     Q96 3
 '@T6G_MB_LIB.T6G(SCH_1):PAGE333_I159@PURE_QUANTA.MOSFET_NCH_DUAL(CHIPS)':
 'D2': CDS_PINID='D2';
NODE_NAME     R3324 2
 '@T6G_MB_LIB.T6G(SCH_1):PAGE80_I276@PURE_QUANTA.Q_RES(CHIPS)':
 'B': CDS_PINID='B';
NET_NAME
'GPU_FPGA_READY_ISO_R'
 '@T6G_MB_LIB.T6G(SCH_1):GPU_FPGA_READY_ISO_R':
 C_SIGNAL='@t6g_mb_lib.t6g(sch_1):gpu_fpga_ready_iso_r';
NODE_NAME     U18 AB19
 '@T6G_MB_LIB.T6G(SCH_1):PAGE80_I216@PURE_QUANTA.LCMXO3LF9400C5BG484C(CHIPS)':
 'PB43A': CDS_PINID='PB43A';
NODE_NAME     R3324 1
 '@T6G_MB_LIB.T6G(SCH_1):PAGE80_I276@PURE_QUANTA.Q_RES(CHIPS)':
 'A': CDS_PINID='A';
NET_NAME
'GPU_FPGA_READY_N'
 '@T6G_MB_LIB.T6G(SCH_1):GPU_FPGA_READY_N':
 C_SIGNAL='@t6g_mb_lib.t6g(sch_1):gpu_fpga_ready_n';
NODE_NAME     Q96 6
 '@T6G_MB_LIB.T6G(SCH_1):PAGE333_I154@PURE_QUANTA.MOSFET_NCH_DUAL(CHIPS)':
 'D1': CDS_PINID='D1';
NODE_NAME     Q96 5
 '@T6G_MB_LIB.T6G(SCH_1):PAGE333_I159@PURE_QUANTA.MOSFET_NCH_DUAL(CHIPS)':
 'G2': CDS_PINID='G2';
NODE_NAME     R3320 2
 '@T6G_MB_LIB.T6G(SCH_1):PAGE333_I162@PURE_QUANTA.Q_RES(CHIPS)':
 'B': CDS_PINID='B';
NODE_NAME     R3326 1
 '@T6G_MB_LIB.T6G(SCH_1):PAGE232_I7@PURE_QUANTA.Q_RES(CHIPS)':
 'A': CDS_PINID='A';
NET_NAME
'GPU_FPGA_READY_R_N'
 '@T6G_MB_LIB.T6G(SCH_1):GPU_FPGA_READY_R_N':
 C_SIGNAL='@t6g_mb_lib.t6g(sch_1):gpu_fpga_ready_r_n';
NODE_NAME     R3326 2
 '@T6G_MB_LIB.T6G(SCH_1):PAGE232_I7@PURE_QUANTA.Q_RES(CHIPS)':
 'B': CDS_PINID='B';
NODE_NAME     U248 1
 '@T6G_MB_LIB.T6G(SCH_1):PAGE232_I26@PURE_QUANTA.74LVC1G32GW(CHIPS)':
 'I0': CDS_PINID='I0';
NET_NAME
'GPU_FPGA_RST_N'
 '@T6G_MB_LIB.T6G(SCH_1):GPU_FPGA_RST_N':
 C_SIGNAL='@t6g_mb_lib.t6g(sch_1):gpu_fpga_rst_n';
NODE_NAME     U18 V7
 '@T6G_MB_LIB.T6G(SCH_1):PAGE80_I216@PURE_QUANTA.LCMXO3LF9400C5BG484C(CHIPS)':
 'PB11D': CDS_PINID='PB11D';
NODE_NAME     R4608 2
 '@T6G_MB_LIB.T6G(SCH_1):PAGE80_I295@PURE_QUANTA.Q_RES(CHIPS)':
 'B': CDS_PINID='B';
NET_NAME
'GPU_FPGA_RST_R1_BUF_N'
 '@T6G_MB_LIB.T6G(SCH_1):GPU_FPGA_RST_R1_BUF_N':
 C_SIGNAL='@t6g_mb_lib.t6g(sch_1):gpu_fpga_rst_r1_buf_n';
NODE_NAME     U196 4
 '@T6G_MB_LIB.T6G(SCH_1):PAGE256_I127@PURE_QUANTA.74LVC2G17GW(CHIPS)':
 'B1': CDS_PINID='B1';
NODE_NAME     R3315 1
 '@T6G_MB_LIB.T6G(SCH_1):PAGE256_I181@PURE_QUANTA.Q_RES(CHIPS)':
 'A': CDS_PINID='A';
NODE_NAME     R3317 2
 '@T6G_MB_LIB.T6G(SCH_1):PAGE256_I190@PURE_QUANTA.Q_RES(CHIPS)':
 'B': CDS_PINID='B';
NODE_NAME     R3509 1
 '@T6G_MB_LIB.T6G(SCH_1):PAGE256_I191@PURE_QUANTA.Q_RES(CHIPS)':
 'A': CDS_PINID='A';
NET_NAME
'GPU_FPGA_RST_R_BUF_N'
 '@T6G_MB_LIB.T6G(SCH_1):GPU_FPGA_RST_R_BUF_N':
 C_SIGNAL='@t6g_mb_lib.t6g(sch_1):gpu_fpga_rst_r_buf_n';
NODE_NAME     R3315 2
 '@T6G_MB_LIB.T6G(SCH_1):PAGE256_I181@PURE_QUANTA.Q_RES(CHIPS)':
 'B': CDS_PINID='B';
NODE_NAME     J111 A7
 '@T6G_MB_LIB.T6G(SCH_1):PAGE328_I38@PURE_QUANTA.CONN112_10137002101LF(CHIPS)':
 'A7': CDS_PINID='A7';
NET_NAME
'GPU_FPGA_RST_R_N'
 '@T6G_MB_LIB.T6G(SCH_1):GPU_FPGA_RST_R_N':
 C_SIGNAL='@t6g_mb_lib.t6g(sch_1):gpu_fpga_rst_r_n';
NODE_NAME     U196 3
 '@T6G_MB_LIB.T6G(SCH_1):PAGE256_I127@PURE_QUANTA.74LVC2G17GW(CHIPS)':
 'A1': CDS_PINID='A1';
NODE_NAME     R3507 1
 '@T6G_MB_LIB.T6G(SCH_1):PAGE256_I192@PURE_QUANTA.Q_RES(CHIPS)':
 'A': CDS_PINID='A';
NODE_NAME     R3506 2
 '@T6G_MB_LIB.T6G(SCH_1):PAGE256_I193@PURE_QUANTA.Q_RES(CHIPS)':
 'B': CDS_PINID='B';
NODE_NAME     R4608 1
 '@T6G_MB_LIB.T6G(SCH_1):PAGE80_I295@PURE_QUANTA.Q_RES(CHIPS)':
 'A': CDS_PINID='A';
NET_NAME
'GPU_FPGA_THERM_OVERT'
 '@T6G_MB_LIB.T6G(SCH_1):GPU_FPGA_THERM_OVERT':
 C_SIGNAL='@t6g_mb_lib.t6g(sch_1):gpu_fpga_therm_overt';
NODE_NAME     Q101 6
 '@T6G_MB_LIB.T6G(SCH_1):PAGE299_I52@PURE_QUANTA.MOSFET_NCH_DUAL(CHIPS)':
 'D1': CDS_PINID='D1';
NODE_NAME     R3432 2
 '@T6G_MB_LIB.T6G(SCH_1):PAGE299_I53@PURE_QUANTA.Q_RES(CHIPS)':
 'B': CDS_PINID='B';
NODE_NAME     Q101 5
 '@T6G_MB_LIB.T6G(SCH_1):PAGE299_I57@PURE_QUANTA.MOSFET_NCH_DUAL(CHIPS)':
 'G2': CDS_PINID='G2';
NET_NAME
'GPU_FPGA_THERM_OVERT_ISO_N'
 '@T6G_MB_LIB.T6G(SCH_1):GPU_FPGA_THERM_OVERT_ISO_N':
 C_SIGNAL='@t6g_mb_lib.t6g(sch_1):gpu_fpga_therm_overt_iso_n';
NODE_NAME     Q101 3
 '@T6G_MB_LIB.T6G(SCH_1):PAGE299_I57@PURE_QUANTA.MOSFET_NCH_DUAL(CHIPS)':
 'D2': CDS_PINID='D2';
NODE_NAME     R3439 2
 '@T6G_MB_LIB.T6G(SCH_1):PAGE299_I59@PURE_QUANTA.Q_RES(CHIPS)':
 'B': CDS_PINID='B';
NODE_NAME     C1974 1
 '@T6G_MB_LIB.T6G(SCH_1):PAGE299_I74@PURE_QUANTA.Q_CAP(CHIPS)':
 'A': CDS_PINID='A';
NODE_NAME     R3476 2
 '@T6G_MB_LIB.T6G(SCH_1):PAGE80_I250@PURE_QUANTA.Q_RES(CHIPS)':
 'B': CDS_PINID='B';
NET_NAME
'GPU_FPGA_THERM_OVERT_ISO_R_N'
 '@T6G_MB_LIB.T6G(SCH_1):GPU_FPGA_THERM_OVERT_ISO_R_N':
 C_SIGNAL='@t6g_mb_lib.t6g(sch_1):gpu_fpga_therm_overt_iso_r_n';
NODE_NAME     U18 W14
 '@T6G_MB_LIB.T6G(SCH_1):PAGE80_I216@PURE_QUANTA.LCMXO3LF9400C5BG484C(CHIPS)':
 'PB33D': CDS_PINID='PB33D';
NODE_NAME     R3476 1
 '@T6G_MB_LIB.T6G(SCH_1):PAGE80_I250@PURE_QUANTA.Q_RES(CHIPS)':
 'A': CDS_PINID='A';
NET_NAME
'GPU_FPGA_THERM_OVERT_N'
 '@T6G_MB_LIB.T6G(SCH_1):GPU_FPGA_THERM_OVERT_N':
 C_SIGNAL='@t6g_mb_lib.t6g(sch_1):gpu_fpga_therm_overt_n';
NODE_NAME     R3428 1
 '@T6G_MB_LIB.T6G(SCH_1):PAGE299_I17@PURE_QUANTA.Q_RES(CHIPS)':
 'A': CDS_PINID='A';
NODE_NAME     Q101 2
 '@T6G_MB_LIB.T6G(SCH_1):PAGE299_I52@PURE_QUANTA.MOSFET_NCH_DUAL(CHIPS)':
 'G1': CDS_PINID='G1';
NODE_NAME     R3498 2
 '@T6G_MB_LIB.T6G(SCH_1):PAGE299_I167@PURE_QUANTA.Q_RES(CHIPS)':
 'B': CDS_PINID='B';
NODE_NAME     J112 T6
 '@T6G_MB_LIB.T6G(SCH_1):PAGE329_I7@PURE_QUANTA.CONN160_10131762101LF(CHIPS)':
 'T6': CDS_PINID='T6';
NET_NAME
'GPU_HMC_PRSNT'
 '@T6G_MB_LIB.T6G(SCH_1):GPU_HMC_PRSNT':
 C_SIGNAL='@t6g_mb_lib.t6g(sch_1):gpu_hmc_prsnt';
NODE_NAME     Q103 6
 '@T6G_MB_LIB.T6G(SCH_1):PAGE299_I37@PURE_QUANTA.MOSFET_NCH_DUAL(CHIPS)':
 'D1': CDS_PINID='D1';
NODE_NAME     R3434 2
 '@T6G_MB_LIB.T6G(SCH_1):PAGE299_I39@PURE_QUANTA.Q_RES(CHIPS)':
 'B': CDS_PINID='B';
NODE_NAME     Q103 5
 '@T6G_MB_LIB.T6G(SCH_1):PAGE299_I43@PURE_QUANTA.MOSFET_NCH_DUAL(CHIPS)':
 'G2': CDS_PINID='G2';
NET_NAME
'GPU_HMC_PRSNT_ISO_N'
 '@T6G_MB_LIB.T6G(SCH_1):GPU_HMC_PRSNT_ISO_N':
 C_SIGNAL='@t6g_mb_lib.t6g(sch_1):gpu_hmc_prsnt_iso_n';
NODE_NAME     Q103 3
 '@T6G_MB_LIB.T6G(SCH_1):PAGE299_I43@PURE_QUANTA.MOSFET_NCH_DUAL(CHIPS)':
 'D2': CDS_PINID='D2';
NODE_NAME     R3436 2
 '@T6G_MB_LIB.T6G(SCH_1):PAGE299_I45@PURE_QUANTA.Q_RES(CHIPS)':
 'B': CDS_PINID='B';
NODE_NAME     C1975 1
 '@T6G_MB_LIB.T6G(SCH_1):PAGE299_I129@PURE_QUANTA.Q_CAP(CHIPS)':
 'A': CDS_PINID='A';
NODE_NAME     R3481 2
 '@T6G_MB_LIB.T6G(SCH_1):PAGE80_I251@PURE_QUANTA.Q_RES(CHIPS)':
 'B': CDS_PINID='B';
NET_NAME
'GPU_HMC_PRSNT_ISO_R_N'
 '@T6G_MB_LIB.T6G(SCH_1):GPU_HMC_PRSNT_ISO_R_N':
 C_SIGNAL='@t6g_mb_lib.t6g(sch_1):gpu_hmc_prsnt_iso_r_n';
NODE_NAME     U18 AA15
 '@T6G_MB_LIB.T6G(SCH_1):PAGE80_I216@PURE_QUANTA.LCMXO3LF9400C5BG484C(CHIPS)':
 'PB35B': CDS_PINID='PB35B';
NODE_NAME     R3481 1
 '@T6G_MB_LIB.T6G(SCH_1):PAGE80_I251@PURE_QUANTA.Q_RES(CHIPS)':
 'A': CDS_PINID='A';
NET_NAME
'GPU_HMC_PRSNT_N'
 '@T6G_MB_LIB.T6G(SCH_1):GPU_HMC_PRSNT_N':
 C_SIGNAL='@t6g_mb_lib.t6g(sch_1):gpu_hmc_prsnt_n';
NODE_NAME     Q103 2
 '@T6G_MB_LIB.T6G(SCH_1):PAGE299_I37@PURE_QUANTA.MOSFET_NCH_DUAL(CHIPS)':
 'G1': CDS_PINID='G1';
NODE_NAME     R3465 2
 '@T6G_MB_LIB.T6G(SCH_1):PAGE299_I132@PURE_QUANTA.Q_RES(CHIPS)':
 'B': CDS_PINID='B';
NODE_NAME     R3431 1
 '@T6G_MB_LIB.T6G(SCH_1):PAGE299_I133@PURE_QUANTA.Q_RES(CHIPS)':
 'A': CDS_PINID='A';
NODE_NAME     J110 A3
 '@T6G_MB_LIB.T6G(SCH_1):PAGE318_I76@PURE_QUANTA.CONN112_10137002101LF(CHIPS)':
 'A3': CDS_PINID='A3';
NET_NAME
'GPU_NVS_PWR_BRAKE_N'
 '@T6G_MB_LIB.T6G(SCH_1):GPU_NVS_PWR_BRAKE_N':
 C_SIGNAL='@t6g_mb_lib.t6g(sch_1):gpu_nvs_pwr_brake_n';
NODE_NAME     U255 1
 '@T6G_MB_LIB.T6G(SCH_1):PAGE255_I16@PURE_QUANTA.74LVC2G07DW7(CHIPS)':
 '1A': CDS_PINID='\1a\';
NODE_NAME     R3460 1
 '@T6G_MB_LIB.T6G(SCH_1):PAGE255_I31@PURE_QUANTA.Q_RES(CHIPS)':
 'A': CDS_PINID='A';
NODE_NAME     R3477 1
 '@T6G_MB_LIB.T6G(SCH_1):PAGE80_I286@PURE_QUANTA.Q_RES(CHIPS)':
 'A': CDS_PINID='A';
NODE_NAME     R3459 2
 '@T6G_MB_LIB.T6G(SCH_1):PAGE255_I75@PURE_QUANTA.Q_RES(CHIPS)':
 'B': CDS_PINID='B';
NET_NAME
'GPU_NVS_PWR_BRAKE_N_BUF'
 '@T6G_MB_LIB.T6G(SCH_1):GPU_NVS_PWR_BRAKE_N_BUF':
 C_SIGNAL='@t6g_mb_lib.t6g(sch_1):gpu_nvs_pwr_brake_n_buf';
NODE_NAME     R3397 2
 '@T6G_MB_LIB.T6G(SCH_1):PAGE255_I37@PURE_QUANTA.Q_RES(CHIPS)':
 'B': CDS_PINID='B';
NODE_NAME     J112 T4
 '@T6G_MB_LIB.T6G(SCH_1):PAGE329_I102@PURE_QUANTA.CONN160_10131762101LF(CHIPS)':
 'T4': CDS_PINID='T4';
NET_NAME
'GPU_NVS_PWR_BRAKE_N_R'
 '@T6G_MB_LIB.T6G(SCH_1):GPU_NVS_PWR_BRAKE_N_R':
 C_SIGNAL='@t6g_mb_lib.t6g(sch_1):gpu_nvs_pwr_brake_n_r';
NODE_NAME     U255 6
 '@T6G_MB_LIB.T6G(SCH_1):PAGE255_I16@PURE_QUANTA.74LVC2G07DW7(CHIPS)':
 '1Y': CDS_PINID='\1y\';
NODE_NAME     R3462 1
 '@T6G_MB_LIB.T6G(SCH_1):PAGE255_I33@PURE_QUANTA.Q_RES(CHIPS)':
 'A': CDS_PINID='A';
NODE_NAME     R3461 2
 '@T6G_MB_LIB.T6G(SCH_1):PAGE255_I35@PURE_QUANTA.Q_RES(CHIPS)':
 'B': CDS_PINID='B';
NODE_NAME     R3397 1
 '@T6G_MB_LIB.T6G(SCH_1):PAGE255_I37@PURE_QUANTA.Q_RES(CHIPS)':
 'A': CDS_PINID='A';
NET_NAME
'GPU_NVS_PWR_BRAKE_R_N'
 '@T6G_MB_LIB.T6G(SCH_1):GPU_NVS_PWR_BRAKE_R_N':
 C_SIGNAL='@t6g_mb_lib.t6g(sch_1):gpu_nvs_pwr_brake_r_n';
NODE_NAME     U18 AB2
 '@T6G_MB_LIB.T6G(SCH_1):PAGE80_I216@PURE_QUANTA.LCMXO3LF9400C5BG484C(CHIPS)':
 'PB5B': CDS_PINID='PB5B';
NODE_NAME     R3477 2
 '@T6G_MB_LIB.T6G(SCH_1):PAGE80_I286@PURE_QUANTA.Q_RES(CHIPS)':
 'B': CDS_PINID='B';
NET_NAME
'GPU_PEX_STRAP0'
 '@T6G_MB_LIB.T6G(SCH_1):GPU_PEX_STRAP0':
 C_SIGNAL='@t6g_mb_lib.t6g(sch_1):gpu_pex_strap0';
NODE_NAME     J111 A5
 '@T6G_MB_LIB.T6G(SCH_1):PAGE328_I38@PURE_QUANTA.CONN112_10137002101LF(CHIPS)':
 'A5': CDS_PINID='A5';
NODE_NAME     R3518 1
 '@T6G_MB_LIB.T6G(SCH_1):PAGE246_I47@PURE_QUANTA.Q_RES(CHIPS)':
 'A': CDS_PINID='A';
NODE_NAME     R3442 1
 '@T6G_MB_LIB.T6G(SCH_1):PAGE330_I67@PURE_QUANTA.Q_RES(CHIPS)':
 'A': CDS_PINID='A';
NET_NAME
'GPU_PEX_STRAP0_R'
 '@T6G_MB_LIB.T6G(SCH_1):GPU_PEX_STRAP0_R':
 C_SIGNAL='@t6g_mb_lib.t6g(sch_1):gpu_pex_strap0_r';
NODE_NAME     R3518 2
 '@T6G_MB_LIB.T6G(SCH_1):PAGE246_I47@PURE_QUANTA.Q_RES(CHIPS)':
 'B': CDS_PINID='B';
NODE_NAME     U181 17
 '@T6G_MB_LIB.T6G(SCH_1):PAGE246_I83@PURE_QUANTA.PCA9539RPW(CHIPS)':
 'IO1_4': CDS_PINID='IO1_4';
NET_NAME
'GPU_PEX_STRAP1'
 '@T6G_MB_LIB.T6G(SCH_1):GPU_PEX_STRAP1':
 C_SIGNAL='@t6g_mb_lib.t6g(sch_1):gpu_pex_strap1';
NODE_NAME     J111 A1
 '@T6G_MB_LIB.T6G(SCH_1):PAGE328_I76@PURE_QUANTA.CONN112_10137002101LF(CHIPS)':
 'A1': CDS_PINID='A1';
NODE_NAME     R3517 1
 '@T6G_MB_LIB.T6G(SCH_1):PAGE246_I55@PURE_QUANTA.Q_RES(CHIPS)':
 'A': CDS_PINID='A';
NODE_NAME     R3443 1
 '@T6G_MB_LIB.T6G(SCH_1):PAGE330_I66@PURE_QUANTA.Q_RES(CHIPS)':
 'A': CDS_PINID='A';
NET_NAME
'GPU_PEX_STRAP1_R'
 '@T6G_MB_LIB.T6G(SCH_1):GPU_PEX_STRAP1_R':
 C_SIGNAL='@t6g_mb_lib.t6g(sch_1):gpu_pex_strap1_r';
NODE_NAME     R3517 2
 '@T6G_MB_LIB.T6G(SCH_1):PAGE246_I55@PURE_QUANTA.Q_RES(CHIPS)':
 'B': CDS_PINID='B';
NODE_NAME     U181 18
 '@T6G_MB_LIB.T6G(SCH_1):PAGE246_I83@PURE_QUANTA.PCA9539RPW(CHIPS)':
 'IO1_5': CDS_PINID='IO1_5';
NET_NAME
'GPU_PRSNT'
 '@T6G_MB_LIB.T6G(SCH_1):GPU_PRSNT':
 C_SIGNAL='@t6g_mb_lib.t6g(sch_1):gpu_prsnt';
NODE_NAME     Q107 5
 '@T6G_MB_LIB.T6G(SCH_1):PAGE299_I157@PURE_QUANTA.MOSFET_NCH_DUAL(CHIPS)':
 'G2': CDS_PINID='G2';
NODE_NAME     R3474 2
 '@T6G_MB_LIB.T6G(SCH_1):PAGE299_I158@PURE_QUANTA.Q_RES(CHIPS)':
 'B': CDS_PINID='B';
NODE_NAME     Q107 6
 '@T6G_MB_LIB.T6G(SCH_1):PAGE299_I160@PURE_QUANTA.MOSFET_NCH_DUAL(CHIPS)':
 'D1': CDS_PINID='D1';
NODE_NAME     R3770 1
 '@T6G_MB_LIB.T6G(SCH_1):PAGE364_I34@PURE_QUANTA.Q_RES(CHIPS)':
 'A': CDS_PINID='A';
NET_NAME
'GPU_PRSNT_N'
 '@T6G_MB_LIB.T6G(SCH_1):GPU_PRSNT_N':
 C_SIGNAL='@t6g_mb_lib.t6g(sch_1):gpu_prsnt_n';
NODE_NAME     Q107 2
 '@T6G_MB_LIB.T6G(SCH_1):PAGE299_I160@PURE_QUANTA.MOSFET_NCH_DUAL(CHIPS)':
 'G1': CDS_PINID='G1';
NODE_NAME     R3473 1
 '@T6G_MB_LIB.T6G(SCH_1):PAGE299_I163@PURE_QUANTA.Q_RES(CHIPS)':
 'A': CDS_PINID='A';
NODE_NAME     R3487 2
 '@T6G_MB_LIB.T6G(SCH_1):PAGE299_I166@PURE_QUANTA.Q_RES(CHIPS)':
 'B': CDS_PINID='B';
NODE_NAME     J111 N2
 '@T6G_MB_LIB.T6G(SCH_1):PAGE328_I76@PURE_QUANTA.CONN112_10137002101LF(CHIPS)':
 'N2': CDS_PINID='N2';
NET_NAME
'GPU_PRSNT_N_ISO'
 '@T6G_MB_LIB.T6G(SCH_1):GPU_PRSNT_N_ISO':
 C_SIGNAL='@t6g_mb_lib.t6g(sch_1):gpu_prsnt_n_iso';
NODE_NAME     C1978 1
 '@T6G_MB_LIB.T6G(SCH_1):PAGE299_I152@PURE_QUANTA.Q_CAP(CHIPS)':
 'A': CDS_PINID='A';
NODE_NAME     R3475 2
 '@T6G_MB_LIB.T6G(SCH_1):PAGE299_I154@PURE_QUANTA.Q_RES(CHIPS)':
 'B': CDS_PINID='B';
NODE_NAME     Q107 3
 '@T6G_MB_LIB.T6G(SCH_1):PAGE299_I157@PURE_QUANTA.MOSFET_NCH_DUAL(CHIPS)':
 'D2': CDS_PINID='D2';
NODE_NAME     R3486 2
 '@T6G_MB_LIB.T6G(SCH_1):PAGE80_I258@PURE_QUANTA.Q_RES(CHIPS)':
 'B': CDS_PINID='B';
NODE_NAME     R9001 1
 '@T6G_MB_LIB.T6G(SCH_1):PAGE246_I46@PURE_QUANTA.Q_RES(CHIPS)':
 'A': CDS_PINID='A';
NET_NAME
'GPU_PRSNT_N_ISO_R'
 '@T6G_MB_LIB.T6G(SCH_1):GPU_PRSNT_N_ISO_R':
 C_SIGNAL='@t6g_mb_lib.t6g(sch_1):gpu_prsnt_n_iso_r';
NODE_NAME     U18 AB16
 '@T6G_MB_LIB.T6G(SCH_1):PAGE80_I216@PURE_QUANTA.LCMXO3LF9400C5BG484C(CHIPS)':
 'PB38A': CDS_PINID='PB38A';
NODE_NAME     R3486 1
 '@T6G_MB_LIB.T6G(SCH_1):PAGE80_I258@PURE_QUANTA.Q_RES(CHIPS)':
 'A': CDS_PINID='A';
NET_NAME
'GPU_PRSNT_N_ISO_R1'
 '@T6G_MB_LIB.T6G(SCH_1):GPU_PRSNT_N_ISO_R1':
 C_SIGNAL='@t6g_mb_lib.t6g(sch_1):gpu_prsnt_n_iso_r1';
NODE_NAME     R9001 2
 '@T6G_MB_LIB.T6G(SCH_1):PAGE246_I46@PURE_QUANTA.Q_RES(CHIPS)':
 'B': CDS_PINID='B';
NODE_NAME     U181 9
 '@T6G_MB_LIB.T6G(SCH_1):PAGE246_I83@PURE_QUANTA.PCA9539RPW(CHIPS)':
 'IO0_5': CDS_PINID='IO0_5';
NET_NAME
'GPU_PRSNT_R'
 '@T6G_MB_LIB.T6G(SCH_1):GPU_PRSNT_R':
 C_SIGNAL='@t6g_mb_lib.t6g(sch_1):gpu_prsnt_r';
NODE_NAME     U278 2
 '@T6G_MB_LIB.T6G(SCH_1):PAGE364_I31@PURE_QUANTA.74LVC1G08W57(CHIPS)':
 'B': CDS_PINID='B';
NODE_NAME     R3770 2
 '@T6G_MB_LIB.T6G(SCH_1):PAGE364_I34@PURE_QUANTA.Q_RES(CHIPS)':
 'B': CDS_PINID='B';
NET_NAME
'GPU_WP_HW_CTRL_ISO'
 '@T6G_MB_LIB.T6G(SCH_1):GPU_WP_HW_CTRL_ISO':
 C_SIGNAL='@t6g_mb_lib.t6g(sch_1):gpu_wp_hw_ctrl_iso';
NODE_NAME     R9043 2
 '@T6G_MB_LIB.T6G(SCH_1):PAGE299_I192@PURE_QUANTA.Q_RES(CHIPS)':
 'B': CDS_PINID='B';
NODE_NAME     Q106 5
 '@T6G_MB_LIB.T6G(SCH_1):PAGE299_I200@PURE_QUANTA.MOSFET_NCH_DUAL(CHIPS)':
 'G2': CDS_PINID='G2';
NODE_NAME     Q106 6
 '@T6G_MB_LIB.T6G(SCH_1):PAGE299_I201@PURE_QUANTA.MOSFET_NCH_DUAL(CHIPS)':
 'D1': CDS_PINID='D1';
NET_NAME
'GPU_WP_HW_CTRL_ISO_N'
 '@T6G_MB_LIB.T6G(SCH_1):GPU_WP_HW_CTRL_ISO_N':
 C_SIGNAL='@t6g_mb_lib.t6g(sch_1):gpu_wp_hw_ctrl_iso_n';
NODE_NAME     J105 A3
 '@T6G_MB_LIB.T6G(SCH_1):PAGE326_I75@PURE_QUANTA.CONN112_10137002101LF(CHIPS)':
 'A3': CDS_PINID='A3';
NODE_NAME     R9044 2
 '@T6G_MB_LIB.T6G(SCH_1):PAGE299_I195@PURE_QUANTA.Q_RES(CHIPS)':
 'B': CDS_PINID='B';
NODE_NAME     R3472 2
 '@T6G_MB_LIB.T6G(SCH_1):PAGE299_I198@PURE_QUANTA.Q_RES(CHIPS)':
 'B': CDS_PINID='B';
NODE_NAME     Q106 3
 '@T6G_MB_LIB.T6G(SCH_1):PAGE299_I200@PURE_QUANTA.MOSFET_NCH_DUAL(CHIPS)':
 'D2': CDS_PINID='D2';
NET_NAME
'GPU_WP_HW_CTRL_N'
 '@T6G_MB_LIB.T6G(SCH_1):GPU_WP_HW_CTRL_N':
 C_SIGNAL='@t6g_mb_lib.t6g(sch_1):gpu_wp_hw_ctrl_n';
NODE_NAME     R3485 2
 '@T6G_MB_LIB.T6G(SCH_1):PAGE80_I255@PURE_QUANTA.Q_RES(CHIPS)':
 'B': CDS_PINID='B';
NODE_NAME     R3471 1
 '@T6G_MB_LIB.T6G(SCH_1):PAGE299_I187@PURE_QUANTA.Q_RES(CHIPS)':
 'A': CDS_PINID='A';
NODE_NAME     Q106 2
 '@T6G_MB_LIB.T6G(SCH_1):PAGE299_I201@PURE_QUANTA.MOSFET_NCH_DUAL(CHIPS)':
 'G1': CDS_PINID='G1';
NODE_NAME     R3470 2
 '@T6G_MB_LIB.T6G(SCH_1):PAGE299_I202@PURE_QUANTA.Q_RES(CHIPS)':
 'B': CDS_PINID='B';
NET_NAME
'GPU_WP_HW_CTRL_R_N'
 '@T6G_MB_LIB.T6G(SCH_1):GPU_WP_HW_CTRL_R_N':
 C_SIGNAL='@t6g_mb_lib.t6g(sch_1):gpu_wp_hw_ctrl_r_n';
NODE_NAME     U18 W15
 '@T6G_MB_LIB.T6G(SCH_1):PAGE80_I216@PURE_QUANTA.LCMXO3LF9400C5BG484C(CHIPS)':
 'PB35D': CDS_PINID='PB35D';
NODE_NAME     R3485 1
 '@T6G_MB_LIB.T6G(SCH_1):PAGE80_I255@PURE_QUANTA.Q_RES(CHIPS)':
 'A': CDS_PINID='A';
NET_NAME
'HDD_ACTIVITY_BUF'
 '@T6G_MB_LIB.T6G(SCH_1):HDD_ACTIVITY_BUF':
 C_SIGNAL='@t6g_mb_lib.t6g(sch_1):hdd_activity_buf';
NODE_NAME     U259 6
 '@T6G_MB_LIB.T6G(SCH_1):PAGE345_I5@PURE_QUANTA.SN74LVC2G07DCKR(CHIPS)':
 '1Y': CDS_PINID='\1y\';
NODE_NAME     Q95 2
 '@T6G_MB_LIB.T6G(SCH_1):PAGE345_I8@PURE_QUANTA.MOSFET_NCH_DUAL(CHIPS)':
 'G1': CDS_PINID='G1';
NODE_NAME     R3296 2
 '@T6G_MB_LIB.T6G(SCH_1):PAGE345_I51@PURE_QUANTA.Q_RES(CHIPS)':
 'B': CDS_PINID='B';
NET_NAME
'HDD_ACTIVITY_BUF_N'
 '@T6G_MB_LIB.T6G(SCH_1):HDD_ACTIVITY_BUF_N':
 C_SIGNAL='@t6g_mb_lib.t6g(sch_1):hdd_activity_buf_n';
NODE_NAME     Q95 6
 '@T6G_MB_LIB.T6G(SCH_1):PAGE345_I8@PURE_QUANTA.MOSFET_NCH_DUAL(CHIPS)':
 'D1': CDS_PINID='D1';
NODE_NAME     R3298 2
 '@T6G_MB_LIB.T6G(SCH_1):PAGE345_I58@PURE_QUANTA.Q_RES(CHIPS)':
 'B': CDS_PINID='B';
NODE_NAME     R5377 1
 '@T6G_MB_LIB.T6G(SCH_1):PAGE345_I62@PURE_QUANTA.Q_RES(CHIPS)':
 'A': CDS_PINID='A';
NET_NAME
'HDT_CPU0_HDT_CONN_TESTEN'
 '@T6G_MB_LIB.T6G(SCH_1):HDT_CPU0_HDT_CONN_TESTEN':
 C_SIGNAL='@t6g_mb_lib.t6g(sch_1):hdt_cpu0_hdt_conn_testen';
NODE_NAME     R1629 1
 '@T6G_MB_LIB.T6G(SCH_1):PAGE149_I112@PURE_QUANTA.Q_RES(CHIPS)':
 'A': CDS_PINID='A';
NODE_NAME     R1632 1
 '@T6G_MB_LIB.T6G(SCH_1):PAGE149_I114@PURE_QUANTA.Q_RES(CHIPS)':
 'A': CDS_PINID='A';
NODE_NAME     J54 18
 '@T6G_MB_LIB.T6G(SCH_1):PAGE149_I142@PURE_QUANTA.SCONN20_HSU2101L00007H(CHIPS)':
 '18': CDS_PINID='\18\';
NET_NAME
'HDT_CPU0_XTRIG_L5'
 '@T6G_MB_LIB.T6G(SCH_1):HDT_CPU0_XTRIG_L5':
 C_SIGNAL='@t6g_mb_lib.t6g(sch_1):hdt_cpu0_xtrig_l5';
NODE_NAME     J54 15
 '@T6G_MB_LIB.T6G(SCH_1):PAGE149_I142@PURE_QUANTA.SCONN20_HSU2101L00007H(CHIPS)':
 '15': CDS_PINID='\15\';
NODE_NAME     R478 2
 '@T6G_MB_LIB.T6G(SCH_1):PAGE149_I150@PURE_QUANTA.Q_RES(CHIPS)':
 'B': CDS_PINID='B';
NET_NAME
'HDT_CPU0_XTRIG_L6'
 '@T6G_MB_LIB.T6G(SCH_1):HDT_CPU0_XTRIG_L6':
 C_SIGNAL='@t6g_mb_lib.t6g(sch_1):hdt_cpu0_xtrig_l6';
NODE_NAME     J54 11
 '@T6G_MB_LIB.T6G(SCH_1):PAGE149_I142@PURE_QUANTA.SCONN20_HSU2101L00007H(CHIPS)':
 '11': CDS_PINID='\11\';
NODE_NAME     R476 2
 '@T6G_MB_LIB.T6G(SCH_1):PAGE149_I148@PURE_QUANTA.Q_RES(CHIPS)':
 'B': CDS_PINID='B';
NET_NAME
'HDT_CPU0_XTRIG_L7'
 '@T6G_MB_LIB.T6G(SCH_1):HDT_CPU0_XTRIG_L7':
 C_SIGNAL='@t6g_mb_lib.t6g(sch_1):hdt_cpu0_xtrig_l7';
NODE_NAME     J54 13
 '@T6G_MB_LIB.T6G(SCH_1):PAGE149_I142@PURE_QUANTA.SCONN20_HSU2101L00007H(CHIPS)':
 '13': CDS_PINID='\13\';
NODE_NAME     R477 2
 '@T6G_MB_LIB.T6G(SCH_1):PAGE149_I147@PURE_QUANTA.Q_RES(CHIPS)':
 'B': CDS_PINID='B';
NET_NAME
'HDT_HDR_DBREQ_N'
 '@T6G_MB_LIB.T6G(SCH_1):HDT_HDR_DBREQ_N':
 C_SIGNAL='@t6g_mb_lib.t6g(sch_1):hdt_hdr_dbreq_n';
NODE_NAME     U149 6
 '@T6G_MB_LIB.T6G(SCH_1):PAGE149_I31@PURE_QUANTA.SN74AVC4T774PWR(CHIPS)':
 'A4': CDS_PINID='A4';
NODE_NAME     R1631 2
 '@T6G_MB_LIB.T6G(SCH_1):PAGE149_I113@PURE_QUANTA.Q_RES(CHIPS)':
 'B': CDS_PINID='B';
NODE_NAME     C87 1
 '@T6G_MB_LIB.T6G(SCH_1):PAGE149_I134@PURE_QUANTA.Q_CAP(CHIPS)':
 'A': CDS_PINID='A';
NET_NAME
'HDT_HDR_DBREQ_R_N'
 '@T6G_MB_LIB.T6G(SCH_1):HDT_HDR_DBREQ_R_N':
 C_SIGNAL='@t6g_mb_lib.t6g(sch_1):hdt_hdr_dbreq_r_n';
NODE_NAME     R1631 1
 '@T6G_MB_LIB.T6G(SCH_1):PAGE149_I113@PURE_QUANTA.Q_RES(CHIPS)':
 'A': CDS_PINID='A';
NODE_NAME     R1630 2
 '@T6G_MB_LIB.T6G(SCH_1):PAGE149_I118@PURE_QUANTA.Q_RES(CHIPS)':
 'B': CDS_PINID='B';
NODE_NAME     J54 16
 '@T6G_MB_LIB.T6G(SCH_1):PAGE149_I142@PURE_QUANTA.SCONN20_HSU2101L00007H(CHIPS)':
 '16': CDS_PINID='\16\';
NET_NAME
'HDT_HDR_PWROK'
 '@T6G_MB_LIB.T6G(SCH_1):HDT_HDR_PWROK':
 C_SIGNAL='@t6g_mb_lib.t6g(sch_1):hdt_hdr_pwrok';
NODE_NAME     J54 10
 '@T6G_MB_LIB.T6G(SCH_1):PAGE149_I142@PURE_QUANTA.SCONN20_HSU2101L00007H(CHIPS)':
 '10': CDS_PINID='\10\';
NODE_NAME     R708 2
 '@T6G_MB_LIB.T6G(SCH_1):PAGE80_I168@PURE_QUANTA.Q_RES(CHIPS)':
 'B': CDS_PINID='B';
NET_NAME
'HDT_HDR_RESET_N'
 '@T6G_MB_LIB.T6G(SCH_1):HDT_HDR_RESET_N':
 C_SIGNAL='@t6g_mb_lib.t6g(sch_1):hdt_hdr_reset_n';
NODE_NAME     J54 12
 '@T6G_MB_LIB.T6G(SCH_1):PAGE149_I142@PURE_QUANTA.SCONN20_HSU2101L00007H(CHIPS)':
 '12': CDS_PINID='\12\';
NODE_NAME     R856 2
 '@T6G_MB_LIB.T6G(SCH_1):PAGE80_I167@PURE_QUANTA.Q_RES(CHIPS)':
 'B': CDS_PINID='B';
NET_NAME
'HDT_HDR_R_TCK'
 '@T6G_MB_LIB.T6G(SCH_1):HDT_HDR_R_TCK':
 C_SIGNAL='@t6g_mb_lib.t6g(sch_1):hdt_hdr_r_tck';
NODE_NAME     R1352 1
 '@T6G_MB_LIB.T6G(SCH_1):PAGE149_I132@PURE_QUANTA.Q_RES(CHIPS)':
 'A': CDS_PINID='A';
NODE_NAME     J54 2
 '@T6G_MB_LIB.T6G(SCH_1):PAGE149_I142@PURE_QUANTA.SCONN20_HSU2101L00007H(CHIPS)':
 '2': CDS_PINID='\2\';
NET_NAME
'HDT_HDR_R_TDI'
 '@T6G_MB_LIB.T6G(SCH_1):HDT_HDR_R_TDI':
 C_SIGNAL='@t6g_mb_lib.t6g(sch_1):hdt_hdr_r_tdi';
NODE_NAME     R1354 1
 '@T6G_MB_LIB.T6G(SCH_1):PAGE149_I109@PURE_QUANTA.Q_RES(CHIPS)':
 'A': CDS_PINID='A';
NODE_NAME     J54 6
 '@T6G_MB_LIB.T6G(SCH_1):PAGE149_I142@PURE_QUANTA.SCONN20_HSU2101L00007H(CHIPS)':
 '6': CDS_PINID='\6\';
NET_NAME
'HDT_HDR_R_TMS'
 '@T6G_MB_LIB.T6G(SCH_1):HDT_HDR_R_TMS':
 C_SIGNAL='@t6g_mb_lib.t6g(sch_1):hdt_hdr_r_tms';
NODE_NAME     R1353 1
 '@T6G_MB_LIB.T6G(SCH_1):PAGE149_I133@PURE_QUANTA.Q_RES(CHIPS)':
 'A': CDS_PINID='A';
NODE_NAME     J54 4
 '@T6G_MB_LIB.T6G(SCH_1):PAGE149_I142@PURE_QUANTA.SCONN20_HSU2101L00007H(CHIPS)':
 '4': CDS_PINID='\4\';
NET_NAME
'HDT_HDR_TCK'
 '@T6G_MB_LIB.T6G(SCH_1):HDT_HDR_TCK':
 C_SIGNAL='@t6g_mb_lib.t6g(sch_1):hdt_hdr_tck';
NODE_NAME     U149 3
 '@T6G_MB_LIB.T6G(SCH_1):PAGE149_I31@PURE_QUANTA.SN74AVC4T774PWR(CHIPS)':
 'A1': CDS_PINID='A1';
NODE_NAME     R1624 2
 '@T6G_MB_LIB.T6G(SCH_1):PAGE149_I111@PURE_QUANTA.Q_RES(CHIPS)':
 'B': CDS_PINID='B';
NODE_NAME     R1352 2
 '@T6G_MB_LIB.T6G(SCH_1):PAGE149_I132@PURE_QUANTA.Q_RES(CHIPS)':
 'B': CDS_PINID='B';
NODE_NAME     C604 1
 '@T6G_MB_LIB.T6G(SCH_1):PAGE149_I140@PURE_QUANTA.Q_CAP(CHIPS)':
 'A': CDS_PINID='A';
NET_NAME
'HDT_HDR_TDI'
 '@T6G_MB_LIB.T6G(SCH_1):HDT_HDR_TDI':
 C_SIGNAL='@t6g_mb_lib.t6g(sch_1):hdt_hdr_tdi';
NODE_NAME     U146 8
 '@T6G_MB_LIB.T6G(SCH_1):PAGE149_I76@PURE_QUANTA.SN74AVC2T245RSWR(CHIPS)':
 'A1': CDS_PINID='A1';
NODE_NAME     R1354 2
 '@T6G_MB_LIB.T6G(SCH_1):PAGE149_I109@PURE_QUANTA.Q_RES(CHIPS)':
 'B': CDS_PINID='B';
NODE_NAME     R1627 2
 '@T6G_MB_LIB.T6G(SCH_1):PAGE149_I116@PURE_QUANTA.Q_RES(CHIPS)':
 'B': CDS_PINID='B';
NODE_NAME     C605 1
 '@T6G_MB_LIB.T6G(SCH_1):PAGE149_I137@PURE_QUANTA.Q_CAP(CHIPS)':
 'A': CDS_PINID='A';
NET_NAME
'HDT_HDR_TDO'
 '@T6G_MB_LIB.T6G(SCH_1):HDT_HDR_TDO':
 C_SIGNAL='@t6g_mb_lib.t6g(sch_1):hdt_hdr_tdo';
NODE_NAME     R1628 2
 '@T6G_MB_LIB.T6G(SCH_1):PAGE149_I117@PURE_QUANTA.Q_RES(CHIPS)':
 'B': CDS_PINID='B';
NODE_NAME     J54 8
 '@T6G_MB_LIB.T6G(SCH_1):PAGE149_I142@PURE_QUANTA.SCONN20_HSU2101L00007H(CHIPS)':
 '8': CDS_PINID='\8\';
NODE_NAME     R6108 1
 '@T6G_MB_LIB.T6G(SCH_1):PAGE149_I159@PURE_QUANTA.Q_RES(CHIPS)':
 'A': CDS_PINID='A';
NET_NAME
'HDT_HDR_TDO_R'
 '@T6G_MB_LIB.T6G(SCH_1):HDT_HDR_TDO_R':
 C_SIGNAL='@t6g_mb_lib.t6g(sch_1):hdt_hdr_tdo_r';
NODE_NAME     U146 9
 '@T6G_MB_LIB.T6G(SCH_1):PAGE149_I76@PURE_QUANTA.SN74AVC2T245RSWR(CHIPS)':
 'A2': CDS_PINID='A2';
NODE_NAME     R6108 2
 '@T6G_MB_LIB.T6G(SCH_1):PAGE149_I159@PURE_QUANTA.Q_RES(CHIPS)':
 'B': CDS_PINID='B';
NET_NAME
'HDT_HDR_TMS'
 '@T6G_MB_LIB.T6G(SCH_1):HDT_HDR_TMS':
 C_SIGNAL='@t6g_mb_lib.t6g(sch_1):hdt_hdr_tms';
NODE_NAME     U149 4
 '@T6G_MB_LIB.T6G(SCH_1):PAGE149_I31@PURE_QUANTA.SN74AVC4T774PWR(CHIPS)':
 'A2': CDS_PINID='A2';
NODE_NAME     R1626 2
 '@T6G_MB_LIB.T6G(SCH_1):PAGE149_I115@PURE_QUANTA.Q_RES(CHIPS)':
 'B': CDS_PINID='B';
NODE_NAME     R1353 2
 '@T6G_MB_LIB.T6G(SCH_1):PAGE149_I133@PURE_QUANTA.Q_RES(CHIPS)':
 'B': CDS_PINID='B';
NET_NAME
'HDT_HDR_TRST_N'
 '@T6G_MB_LIB.T6G(SCH_1):HDT_HDR_TRST_N':
 C_SIGNAL='@t6g_mb_lib.t6g(sch_1):hdt_hdr_trst_n';
NODE_NAME     U149 5
 '@T6G_MB_LIB.T6G(SCH_1):PAGE149_I31@PURE_QUANTA.SN74AVC4T774PWR(CHIPS)':
 'A3': CDS_PINID='A3';
NODE_NAME     R1620 1
 '@T6G_MB_LIB.T6G(SCH_1):PAGE149_I149@PURE_QUANTA.Q_RES(CHIPS)':
 'A': CDS_PINID='A';
NODE_NAME     C85 1
 '@T6G_MB_LIB.T6G(SCH_1):PAGE149_I152@PURE_QUANTA.Q_CAP(CHIPS)':
 'A': CDS_PINID='A';
NET_NAME
'HDT_HDR_TRST_N_R'
 '@T6G_MB_LIB.T6G(SCH_1):HDT_HDR_TRST_N_R':
 C_SIGNAL='@t6g_mb_lib.t6g(sch_1):hdt_hdr_trst_n_r';
NODE_NAME     J54 9
 '@T6G_MB_LIB.T6G(SCH_1):PAGE149_I142@PURE_QUANTA.SCONN20_HSU2101L00007H(CHIPS)':
 '9': CDS_PINID='\9\';
NODE_NAME     R1621 2
 '@T6G_MB_LIB.T6G(SCH_1):PAGE149_I146@PURE_QUANTA.Q_RES(CHIPS)':
 'B': CDS_PINID='B';
NODE_NAME     R1620 2
 '@T6G_MB_LIB.T6G(SCH_1):PAGE149_I149@PURE_QUANTA.Q_RES(CHIPS)':
 'B': CDS_PINID='B';
NET_NAME
'HGX_DETECT'
 '@T6G_MB_LIB.T6G(SCH_1):HGX_DETECT':
 C_SIGNAL='@t6g_mb_lib.t6g(sch_1):hgx_detect';
NODE_NAME     Q148 5
 '@T6G_MB_LIB.T6G(SCH_1):PAGE331_I55@PURE_QUANTA.MOSFET_NCH_DUAL(CHIPS)':
 'G2': CDS_PINID='G2';
NODE_NAME     R4545 2
 '@T6G_MB_LIB.T6G(SCH_1):PAGE331_I57@PURE_QUANTA.Q_RES(CHIPS)':
 'B': CDS_PINID='B';
NODE_NAME     Q148 6
 '@T6G_MB_LIB.T6G(SCH_1):PAGE331_I61@PURE_QUANTA.MOSFET_NCH_DUAL(CHIPS)':
 'D1': CDS_PINID='D1';
NET_NAME
'HGX_DETECT_N'
 '@T6G_MB_LIB.T6G(SCH_1):HGX_DETECT_N':
 C_SIGNAL='@t6g_mb_lib.t6g(sch_1):hgx_detect_n';
NODE_NAME     Q148 2
 '@T6G_MB_LIB.T6G(SCH_1):PAGE331_I61@PURE_QUANTA.MOSFET_NCH_DUAL(CHIPS)':
 'G1': CDS_PINID='G1';
NODE_NAME     R4544 1
 '@T6G_MB_LIB.T6G(SCH_1):PAGE331_I62@PURE_QUANTA.Q_RES(CHIPS)':
 'A': CDS_PINID='A';
NODE_NAME     R4543 2
 '@T6G_MB_LIB.T6G(SCH_1):PAGE331_I85@PURE_QUANTA.Q_RES(CHIPS)':
 'B': CDS_PINID='B';
NODE_NAME     R4556 2
 '@T6G_MB_LIB.T6G(SCH_1):PAGE80_I226@PURE_QUANTA.Q_RES(CHIPS)':
 'B': CDS_PINID='B';
NET_NAME
'HGX_DETECT_N_ISO'
 '@T6G_MB_LIB.T6G(SCH_1):HGX_DETECT_N_ISO':
 C_SIGNAL='@t6g_mb_lib.t6g(sch_1):hgx_detect_n_iso';
NODE_NAME     Q148 3
 '@T6G_MB_LIB.T6G(SCH_1):PAGE331_I55@PURE_QUANTA.MOSFET_NCH_DUAL(CHIPS)':
 'D2': CDS_PINID='D2';
NODE_NAME     R4546 2
 '@T6G_MB_LIB.T6G(SCH_1):PAGE331_I110@PURE_QUANTA.Q_RES(CHIPS)':
 'B': CDS_PINID='B';
NODE_NAME     C6 1
 '@T6G_MB_LIB.T6G(SCH_1):PAGE331_I111@PURE_QUANTA.Q_CAP(CHIPS)':
 'A': CDS_PINID='A';
NODE_NAME     J112 A3
 '@T6G_MB_LIB.T6G(SCH_1):PAGE329_I102@PURE_QUANTA.CONN160_10131762101LF(CHIPS)':
 'A3': CDS_PINID='A3';
NODE_NAME     R2656 1
 '@T6G_MB_LIB.T6G(SCH_1):PAGE330_I69@PURE_QUANTA.Q_RES(CHIPS)':
 'A': CDS_PINID='A';
NET_NAME
'HGX_DETECT_N_R'
 '@T6G_MB_LIB.T6G(SCH_1):HGX_DETECT_N_R':
 C_SIGNAL='@t6g_mb_lib.t6g(sch_1):hgx_detect_n_r';
NODE_NAME     U18 U13
 '@T6G_MB_LIB.T6G(SCH_1):PAGE80_I216@PURE_QUANTA.LCMXO3LF9400C5BG484C(CHIPS)':
 'PB29D': CDS_PINID='PB29D';
NODE_NAME     R4556 1
 '@T6G_MB_LIB.T6G(SCH_1):PAGE80_I226@PURE_QUANTA.Q_RES(CHIPS)':
 'A': CDS_PINID='A';
NET_NAME
'HPDB_HSC_PWRGD'
 '@T6G_MB_LIB.T6G(SCH_1):HPDB_HSC_PWRGD':
 C_SIGNAL='@t6g_mb_lib.t6g(sch_1):hpdb_hsc_pwrgd';
NODE_NAME     R2802 2
 '@T6G_MB_LIB.T6G(SCH_1):PAGE363_I387@PURE_QUANTA.Q_RES(CHIPS)':
 'B': CDS_PINID='B';
NODE_NAME     R4552 1
 '@T6G_MB_LIB.T6G(SCH_1):PAGE364_I50@PURE_QUANTA.Q_RES(CHIPS)':
 'A': CDS_PINID='A';
NODE_NAME     R4551 2
 '@T6G_MB_LIB.T6G(SCH_1):PAGE364_I51@PURE_QUANTA.Q_RES(CHIPS)':
 'B': CDS_PINID='B';
NODE_NAME     Q145 2
 '@T6G_MB_LIB.T6G(SCH_1):PAGE364_I53@PURE_QUANTA.MOSFET_NCH_DUAL(CHIPS)':
 'G1': CDS_PINID='G1';
NET_NAME
'HPDB_HSC_PWRGD_ISO'
 '@T6G_MB_LIB.T6G(SCH_1):HPDB_HSC_PWRGD_ISO':
 C_SIGNAL='@t6g_mb_lib.t6g(sch_1):hpdb_hsc_pwrgd_iso';
NODE_NAME     Q145 3
 '@T6G_MB_LIB.T6G(SCH_1):PAGE364_I58@PURE_QUANTA.MOSFET_NCH_DUAL(CHIPS)':
 'D2': CDS_PINID='D2';
NODE_NAME     R4554 2
 '@T6G_MB_LIB.T6G(SCH_1):PAGE364_I59@PURE_QUANTA.Q_RES(CHIPS)':
 'B': CDS_PINID='B';
NODE_NAME     C70 1
 '@T6G_MB_LIB.T6G(SCH_1):PAGE364_I62@PURE_QUANTA.Q_CAP(CHIPS)':
 'A': CDS_PINID='A';
NODE_NAME     R4557 1
 '@T6G_MB_LIB.T6G(SCH_1):PAGE80_I301@PURE_QUANTA.Q_RES(CHIPS)':
 'A': CDS_PINID='A';
NET_NAME
'HPDB_HSC_PWRGD_ISO_R'
 '@T6G_MB_LIB.T6G(SCH_1):HPDB_HSC_PWRGD_ISO_R':
 C_SIGNAL='@t6g_mb_lib.t6g(sch_1):hpdb_hsc_pwrgd_iso_r';
NODE_NAME     U18 T12
 '@T6G_MB_LIB.T6G(SCH_1):PAGE80_I216@PURE_QUANTA.LCMXO3LF9400C5BG484C(CHIPS)':
 'PB27B': CDS_PINID='PB27B';
NODE_NAME     R4557 2
 '@T6G_MB_LIB.T6G(SCH_1):PAGE80_I301@PURE_QUANTA.Q_RES(CHIPS)':
 'B': CDS_PINID='B';
NET_NAME
'HPDB_HSC_PWRGD_N'
 '@T6G_MB_LIB.T6G(SCH_1):HPDB_HSC_PWRGD_N':
 C_SIGNAL='@t6g_mb_lib.t6g(sch_1):hpdb_hsc_pwrgd_n';
NODE_NAME     Q145 6
 '@T6G_MB_LIB.T6G(SCH_1):PAGE364_I53@PURE_QUANTA.MOSFET_NCH_DUAL(CHIPS)':
 'D1': CDS_PINID='D1';
NODE_NAME     R4553 2
 '@T6G_MB_LIB.T6G(SCH_1):PAGE364_I55@PURE_QUANTA.Q_RES(CHIPS)':
 'B': CDS_PINID='B';
NODE_NAME     Q145 5
 '@T6G_MB_LIB.T6G(SCH_1):PAGE364_I58@PURE_QUANTA.MOSFET_NCH_DUAL(CHIPS)':
 'G2': CDS_PINID='G2';
NET_NAME
'HPDB_HSC_PWRGD_R'
 '@T6G_MB_LIB.T6G(SCH_1):HPDB_HSC_PWRGD_R':
 C_SIGNAL='@t6g_mb_lib.t6g(sch_1):hpdb_hsc_pwrgd_r';
NODE_NAME     R2802 1
 '@T6G_MB_LIB.T6G(SCH_1):PAGE363_I387@PURE_QUANTA.Q_RES(CHIPS)':
 'A': CDS_PINID='A';
NODE_NAME     C65 1
 '@T6G_MB_LIB.T6G(SCH_1):PAGE363_I454@PURE_QUANTA.Q_CAP(CHIPS)':
 'A': CDS_PINID='A';
NODE_NAME     J45 C3
 '@T6G_MB_LIB.T6G(SCH_1):PAGE363_I466@PURE_QUANTA.CONN60_101062636003K02LF(CHIPS)':
 'C3': CDS_PINID='C3';
NET_NAME
'HP_LVC3_E1S_0_HSC_PWRGD'
 '@T6G_MB_LIB.T6G(SCH_1):HP_LVC3_E1S_0_HSC_PWRGD':
 C_SIGNAL='@t6g_mb_lib.t6g(sch_1):hp_lvc3_e1s_0_hsc_pwrgd';
NODE_NAME     R3948 2
 '@T6G_MB_LIB.T6G(SCH_1):PAGE323_I37@PURE_QUANTA.Q_RES(CHIPS)':
 'B': CDS_PINID='B';
NODE_NAME     R3972 2
 '@T6G_MB_LIB.T6G(SCH_1):PAGE324_I71@PURE_QUANTA.Q_RES(CHIPS)':
 'B': CDS_PINID='B';
NODE_NAME     R6048 1
 '@T6G_MB_LIB.T6G(SCH_1):PAGE80_I28@PURE_QUANTA.Q_RES(CHIPS)':
 'A': CDS_PINID='A';
NODE_NAME     R3978 2
 '@T6G_MB_LIB.T6G(SCH_1):PAGE324_I86@PURE_QUANTA.Q_RES(CHIPS)':
 'B': CDS_PINID='B';
NODE_NAME     PU292 10
 '@T6G_MB_LIB.T6G(SCH_1):PAGE323_I76@PURE_QUANTA.RS31312R(CHIPS)':
 'PG': CDS_PINID='PG';
NET_NAME
'HP_LVC3_OCP_SFF_PRSNT2'
 '@T6G_MB_LIB.T6G(SCH_1):HP_LVC3_OCP_SFF_PRSNT2':
 C_SIGNAL='@t6g_mb_lib.t6g(sch_1):hp_lvc3_ocp_sff_prsnt2';
NODE_NAME     U24 D
 '@T6G_MB_LIB.T6G(SCH_1):PAGE340_I31@PURE_QUANTA.MOSFET_N(CHIPS)':
 'DRAIN': CDS_PINID='DRAIN';
NODE_NAME     R1128 2
 '@T6G_MB_LIB.T6G(SCH_1):PAGE340_I34@PURE_QUANTA.Q_RES(CHIPS)':
 'B': CDS_PINID='B';
NODE_NAME     U23 2
 '@T6G_MB_LIB.T6G(SCH_1):PAGE340_I36@PURE_QUANTA.74LVC1G08W57(CHIPS)':
 'B': CDS_PINID='B';
NET_NAME
'HP_LVC3_OCP_SFF_PRSNT2_N'
 '@T6G_MB_LIB.T6G(SCH_1):HP_LVC3_OCP_SFF_PRSNT2_N':
 C_SIGNAL='@t6g_mb_lib.t6g(sch_1):hp_lvc3_ocp_sff_prsnt2_n';
NODE_NAME     R576 2
 '@T6G_MB_LIB.T6G(SCH_1):PAGE338_I116@PURE_QUANTA.Q_RES(CHIPS)':
 'B': CDS_PINID='B';
NODE_NAME     R577 2
 '@T6G_MB_LIB.T6G(SCH_1):PAGE338_I118@PURE_QUANTA.Q_RES(CHIPS)':
 'B': CDS_PINID='B';
NODE_NAME     U24 G
 '@T6G_MB_LIB.T6G(SCH_1):PAGE340_I31@PURE_QUANTA.MOSFET_N(CHIPS)':
 'GATE': CDS_PINID='GATE';
NET_NAME
'HP_LVC3_OCP_SFF_PRSNT2_PLD_N'
 '@T6G_MB_LIB.T6G(SCH_1):HP_LVC3_OCP_SFF_PRSNT2_PLD_N':
 C_SIGNAL='@t6g_mb_lib.t6g(sch_1):hp_lvc3_ocp_sff_prsnt2_pld_n';
NODE_NAME     R6046 1
 '@T6G_MB_LIB.T6G(SCH_1):PAGE80_I64@PURE_QUANTA.Q_RES(CHIPS)':
 'A': CDS_PINID='A';
NODE_NAME     R1148 2
 '@T6G_MB_LIB.T6G(SCH_1):PAGE338_I46@PURE_QUANTA.Q_RES(CHIPS)':
 'B': CDS_PINID='B';
NODE_NAME     R1150 2
 '@T6G_MB_LIB.T6G(SCH_1):PAGE338_I71@PURE_QUANTA.Q_RES(CHIPS)':
 'B': CDS_PINID='B';
NET_NAME
'HP_LVC3_OCP_V3_1_P12V_PWRGD'
 '@T6G_MB_LIB.T6G(SCH_1):HP_LVC3_OCP_V3_1_P12V_PWRGD':
 C_SIGNAL='@t6g_mb_lib.t6g(sch_1):hp_lvc3_ocp_v3_1_p12v_pwrgd';
NODE_NAME     R3144 2
 '@T6G_MB_LIB.T6G(SCH_1):PAGE338_I75@PURE_QUANTA.Q_RES(CHIPS)':
 'B': CDS_PINID='B';
NODE_NAME     R3797 2
 '@T6G_MB_LIB.T6G(SCH_1):PAGE338_I85@PURE_QUANTA.Q_RES(CHIPS)':
 'B': CDS_PINID='B';
NODE_NAME     R4532 2
 '@T6G_MB_LIB.T6G(SCH_1):PAGE339_I75@PURE_QUANTA.Q_RES(CHIPS)':
 'B': CDS_PINID='B';
NODE_NAME     R1129 1
 '@T6G_MB_LIB.T6G(SCH_1):PAGE340_I57@PURE_QUANTA.Q_RES(CHIPS)':
 'A': CDS_PINID='A';
NODE_NAME     R1135 2
 '@T6G_MB_LIB.T6G(SCH_1):PAGE248_I41@PURE_QUANTA.Q_RES(CHIPS)':
 'B': CDS_PINID='B';
NODE_NAME     R1136 1
 '@T6G_MB_LIB.T6G(SCH_1):PAGE338_I133@PURE_QUANTA.Q_RES(CHIPS)':
 'A': CDS_PINID='A';
NODE_NAME     R1137 1
 '@T6G_MB_LIB.T6G(SCH_1):PAGE339_I135@PURE_QUANTA.Q_RES(CHIPS)':
 'A': CDS_PINID='A';
NODE_NAME     R1509 1
 '@T6G_MB_LIB.T6G(SCH_1):PAGE340_I96@PURE_QUANTA.Q_RES(CHIPS)':
 'A': CDS_PINID='A';
NODE_NAME     PU204 10
 '@T6G_MB_LIB.T6G(SCH_1):PAGE339_I137@PURE_QUANTA.RS31312R(CHIPS)':
 'PG': CDS_PINID='PG';
NET_NAME
'HP_LVC3_OCP_V3_1_P12V_R2_PWRGD'
 '@T6G_MB_LIB.T6G(SCH_1):HP_LVC3_OCP_V3_1_P12V_R2_PWRGD':
 C_SIGNAL='@t6g_mb_lib.t6g(sch_1):hp_lvc3_ocp_v3_1_p12v_r2_pwrgd';
NODE_NAME     U9050 2
 '@T6G_MB_LIB.T6G(SCH_1):PAGE340_I91@PURE_QUANTA.74LVC1G08W57(CHIPS)':
 'B': CDS_PINID='B';
NODE_NAME     R1509 2
 '@T6G_MB_LIB.T6G(SCH_1):PAGE340_I96@PURE_QUANTA.Q_RES(CHIPS)':
 'B': CDS_PINID='B';
NET_NAME
'HP_LVC3_OCP_V3_1_P12V_R_PWRGD'
 '@T6G_MB_LIB.T6G(SCH_1):HP_LVC3_OCP_V3_1_P12V_R_PWRGD':
 C_SIGNAL='@t6g_mb_lib.t6g(sch_1):hp_lvc3_ocp_v3_1_p12v_r_pwrgd';
NODE_NAME     U28 2
 '@T6G_MB_LIB.T6G(SCH_1):PAGE340_I51@PURE_QUANTA.SN74LVC1G07DBVR(CHIPS)':
 'A': CDS_PINID='A';
NODE_NAME     R1129 2
 '@T6G_MB_LIB.T6G(SCH_1):PAGE340_I57@PURE_QUANTA.Q_RES(CHIPS)':
 'B': CDS_PINID='B';
NET_NAME
'HP_LVC3_OCP_V3_1_PRSNT2_N_R'
 '@T6G_MB_LIB.T6G(SCH_1):HP_LVC3_OCP_V3_1_PRSNT2_N_R':
 C_SIGNAL='@t6g_mb_lib.t6g(sch_1):hp_lvc3_ocp_v3_1_prsnt2_n_r';
NODE_NAME     U8 6
 '@T6G_MB_LIB.T6G(SCH_1):PAGE338_I26@PURE_QUANTA.74LVC2G07DW7(CHIPS)':
 '1Y': CDS_PINID='\1y\';
NODE_NAME     U8 4
 '@T6G_MB_LIB.T6G(SCH_1):PAGE338_I26@PURE_QUANTA.74LVC2G07DW7(CHIPS)':
 '2Y': CDS_PINID='\2y\';
NODE_NAME     U211 6
 '@T6G_MB_LIB.T6G(SCH_1):PAGE338_I29@PURE_QUANTA.74LVC2G07DW7(CHIPS)':
 '1Y': CDS_PINID='\1y\';
NODE_NAME     U211 4
 '@T6G_MB_LIB.T6G(SCH_1):PAGE338_I29@PURE_QUANTA.74LVC2G07DW7(CHIPS)':
 '2Y': CDS_PINID='\2y\';
NODE_NAME     R1148 1
 '@T6G_MB_LIB.T6G(SCH_1):PAGE338_I46@PURE_QUANTA.Q_RES(CHIPS)':
 'A': CDS_PINID='A';
NODE_NAME     R576 1
 '@T6G_MB_LIB.T6G(SCH_1):PAGE338_I116@PURE_QUANTA.Q_RES(CHIPS)':
 'A': CDS_PINID='A';
NET_NAME
'HP_LVC3_OCP_V3_1_PWRGD'
 '@T6G_MB_LIB.T6G(SCH_1):HP_LVC3_OCP_V3_1_PWRGD':
 C_SIGNAL='@t6g_mb_lib.t6g(sch_1):hp_lvc3_ocp_v3_1_pwrgd';
NODE_NAME     R9022 2
 '@T6G_MB_LIB.T6G(SCH_1):PAGE340_I13@PURE_QUANTA.Q_RES(CHIPS)':
 'B': CDS_PINID='B';
NODE_NAME     U9001 2
 '@T6G_MB_LIB.T6G(SCH_1):PAGE340_I25@PURE_QUANTA.74LVC1G08W57(CHIPS)':
 'B': CDS_PINID='B';
NET_NAME
'HP_LVC3_OCP_V3_1_PWRGD_R1'
 '@T6G_MB_LIB.T6G(SCH_1):HP_LVC3_OCP_V3_1_PWRGD_R1':
 C_SIGNAL='@t6g_mb_lib.t6g(sch_1):hp_lvc3_ocp_v3_1_pwrgd_r1';
NODE_NAME     R9034 2
 '@T6G_MB_LIB.T6G(SCH_1):PAGE340_I3@PURE_QUANTA.Q_RES(CHIPS)':
 'B': CDS_PINID='B';
NODE_NAME     R9029 2
 '@T6G_MB_LIB.T6G(SCH_1):PAGE340_I18@PURE_QUANTA.Q_RES(CHIPS)':
 'B': CDS_PINID='B';
NODE_NAME     U9002 1
 '@T6G_MB_LIB.T6G(SCH_1):PAGE340_I74@PURE_QUANTA.74LVC1G32GW(CHIPS)':
 'I0': CDS_PINID='I0';
NET_NAME
'HP_LVC3_OCP_V3_1_PWRGD_R2'
 '@T6G_MB_LIB.T6G(SCH_1):HP_LVC3_OCP_V3_1_PWRGD_R2':
 C_SIGNAL='@t6g_mb_lib.t6g(sch_1):hp_lvc3_ocp_v3_1_pwrgd_r2';
NODE_NAME     U9050 4
 '@T6G_MB_LIB.T6G(SCH_1):PAGE340_I91@PURE_QUANTA.74LVC1G08W57(CHIPS)':
 'Y': CDS_PINID='Y';
NODE_NAME     R1518 1
 '@T6G_MB_LIB.T6G(SCH_1):PAGE340_I102@PURE_QUANTA.Q_RES(CHIPS)':
 'A': CDS_PINID='A';
NET_NAME
'HP_LVC3_OCP_V3_1_R_EN'
 '@T6G_MB_LIB.T6G(SCH_1):HP_LVC3_OCP_V3_1_R_EN':
 C_SIGNAL='@t6g_mb_lib.t6g(sch_1):hp_lvc3_ocp_v3_1_r_en';
NODE_NAME     U236 5
 '@T6G_MB_LIB.T6G(SCH_1):PAGE248_I14@PURE_QUANTA.PCA9617ADP(CHIPS)':
 'EN': CDS_PINID='EN';
NODE_NAME     R3263 1
 '@T6G_MB_LIB.T6G(SCH_1):PAGE248_I35@PURE_QUANTA.Q_RES(CHIPS)':
 'A': CDS_PINID='A';
NODE_NAME     R1135 1
 '@T6G_MB_LIB.T6G(SCH_1):PAGE248_I41@PURE_QUANTA.Q_RES(CHIPS)':
 'A': CDS_PINID='A';
NODE_NAME     R1500 1
 '@T6G_MB_LIB.T6G(SCH_1):PAGE248_I43@PURE_QUANTA.Q_RES(CHIPS)':
 'A': CDS_PINID='A';
NET_NAME
'HP_LVC3_OCP_V3_2_P12V_PWRGD'
 '@T6G_MB_LIB.T6G(SCH_1):HP_LVC3_OCP_V3_2_P12V_PWRGD':
 C_SIGNAL='@t6g_mb_lib.t6g(sch_1):hp_lvc3_ocp_v3_2_p12v_pwrgd';
NODE_NAME     R3825 2
 '@T6G_MB_LIB.T6G(SCH_1):PAGE343_I80@PURE_QUANTA.Q_RES(CHIPS)':
 'B': CDS_PINID='B';
NODE_NAME     R3848 2
 '@T6G_MB_LIB.T6G(SCH_1):PAGE344_I27@PURE_QUANTA.Q_RES(CHIPS)':
 'B': CDS_PINID='B';
NODE_NAME     R3831 2
 '@T6G_MB_LIB.T6G(SCH_1):PAGE343_I77@PURE_QUANTA.Q_RES(CHIPS)':
 'B': CDS_PINID='B';
NODE_NAME     R1163 1
 '@T6G_MB_LIB.T6G(SCH_1):PAGE257_I3@PURE_QUANTA.Q_RES(CHIPS)':
 'A': CDS_PINID='A';
NODE_NAME     R1180 2
 '@T6G_MB_LIB.T6G(SCH_1):PAGE248_I45@PURE_QUANTA.Q_RES(CHIPS)':
 'B': CDS_PINID='B';
NODE_NAME     R1182 1
 '@T6G_MB_LIB.T6G(SCH_1):PAGE343_I129@PURE_QUANTA.Q_RES(CHIPS)':
 'A': CDS_PINID='A';
NODE_NAME     R1196 1
 '@T6G_MB_LIB.T6G(SCH_1):PAGE344_I79@PURE_QUANTA.Q_RES(CHIPS)':
 'A': CDS_PINID='A';
NODE_NAME     R1523 1
 '@T6G_MB_LIB.T6G(SCH_1):PAGE257_I84@PURE_QUANTA.Q_RES(CHIPS)':
 'A': CDS_PINID='A';
NODE_NAME     PU206 10
 '@T6G_MB_LIB.T6G(SCH_1):PAGE344_I82@PURE_QUANTA.RS31312R(CHIPS)':
 'PG': CDS_PINID='PG';
NET_NAME
'HP_LVC3_OCP_V3_2_P12V_PWRGD_R'
 '@T6G_MB_LIB.T6G(SCH_1):HP_LVC3_OCP_V3_2_P12V_PWRGD_R':
 C_SIGNAL='@t6g_mb_lib.t6g(sch_1):hp_lvc3_ocp_v3_2_p12v_pwrgd_r';
NODE_NAME     U18 E13
 '@T6G_MB_LIB.T6G(SCH_1):PAGE79_I94@PURE_QUANTA.LCMXO3LF9400C5BG484C(CHIPS)':
 'PT28C': CDS_PINID='PT28C';
NODE_NAME     R407 2
 '@T6G_MB_LIB.T6G(SCH_1):PAGE79_I139@PURE_QUANTA.Q_RES(CHIPS)':
 'B': CDS_PINID='B';
NET_NAME
'HP_LVC3_OCP_V3_2_P12V_PWRGD_R2'
 '@T6G_MB_LIB.T6G(SCH_1):HP_LVC3_OCP_V3_2_P12V_PWRGD_R2':
 C_SIGNAL='@t6g_mb_lib.t6g(sch_1):hp_lvc3_ocp_v3_2_p12v_pwrgd_r2';
NODE_NAME     U9051 2
 '@T6G_MB_LIB.T6G(SCH_1):PAGE257_I78@PURE_QUANTA.74LVC1G08W57(CHIPS)':
 'B': CDS_PINID='B';
NODE_NAME     R1523 2
 '@T6G_MB_LIB.T6G(SCH_1):PAGE257_I84@PURE_QUANTA.Q_RES(CHIPS)':
 'B': CDS_PINID='B';
NET_NAME
'HP_LVC3_OCP_V3_2_P12V_R_PWRGD'
 '@T6G_MB_LIB.T6G(SCH_1):HP_LVC3_OCP_V3_2_P12V_R_PWRGD':
 C_SIGNAL='@t6g_mb_lib.t6g(sch_1):hp_lvc3_ocp_v3_2_p12v_r_pwrgd';
NODE_NAME     R1163 2
 '@T6G_MB_LIB.T6G(SCH_1):PAGE257_I3@PURE_QUANTA.Q_RES(CHIPS)':
 'B': CDS_PINID='B';
NODE_NAME     U33 2
 '@T6G_MB_LIB.T6G(SCH_1):PAGE257_I64@PURE_QUANTA.SN74LVC1G07DBVR(CHIPS)':
 'A': CDS_PINID='A';
NET_NAME
'HP_LVC3_OCP_V3_2_PRSNT2'
 '@T6G_MB_LIB.T6G(SCH_1):HP_LVC3_OCP_V3_2_PRSNT2':
 C_SIGNAL='@t6g_mb_lib.t6g(sch_1):hp_lvc3_ocp_v3_2_prsnt2';
NODE_NAME     U32 D
 '@T6G_MB_LIB.T6G(SCH_1):PAGE257_I24@PURE_QUANTA.MOSFET_N(CHIPS)':
 'DRAIN': CDS_PINID='DRAIN';
NODE_NAME     R1149 2
 '@T6G_MB_LIB.T6G(SCH_1):PAGE257_I25@PURE_QUANTA.Q_RES(CHIPS)':
 'B': CDS_PINID='B';
NODE_NAME     U31 2
 '@T6G_MB_LIB.T6G(SCH_1):PAGE257_I31@PURE_QUANTA.74LVC1G08W57(CHIPS)':
 'B': CDS_PINID='B';
NET_NAME
'HP_LVC3_OCP_V3_2_PRSNT2_N'
 '@T6G_MB_LIB.T6G(SCH_1):HP_LVC3_OCP_V3_2_PRSNT2_N':
 C_SIGNAL='@t6g_mb_lib.t6g(sch_1):hp_lvc3_ocp_v3_2_prsnt2_n';
NODE_NAME     U32 G
 '@T6G_MB_LIB.T6G(SCH_1):PAGE257_I24@PURE_QUANTA.MOSFET_N(CHIPS)':
 'GATE': CDS_PINID='GATE';
NODE_NAME     R1191 2
 '@T6G_MB_LIB.T6G(SCH_1):PAGE343_I116@PURE_QUANTA.Q_RES(CHIPS)':
 'B': CDS_PINID='B';
NODE_NAME     R1192 2
 '@T6G_MB_LIB.T6G(SCH_1):PAGE343_I118@PURE_QUANTA.Q_RES(CHIPS)':
 'B': CDS_PINID='B';
NET_NAME
'HP_LVC3_OCP_V3_2_PRSNT2_N_R'
 '@T6G_MB_LIB.T6G(SCH_1):HP_LVC3_OCP_V3_2_PRSNT2_N_R':
 C_SIGNAL='@t6g_mb_lib.t6g(sch_1):hp_lvc3_ocp_v3_2_prsnt2_n_r';
NODE_NAME     U58 6
 '@T6G_MB_LIB.T6G(SCH_1):PAGE343_I28@PURE_QUANTA.74LVC2G07DW7(CHIPS)':
 '1Y': CDS_PINID='\1y\';
NODE_NAME     U58 4
 '@T6G_MB_LIB.T6G(SCH_1):PAGE343_I28@PURE_QUANTA.74LVC2G07DW7(CHIPS)':
 '2Y': CDS_PINID='\2y\';
NODE_NAME     R3142 1
 '@T6G_MB_LIB.T6G(SCH_1):PAGE343_I59@PURE_QUANTA.Q_RES(CHIPS)':
 'A': CDS_PINID='A';
NODE_NAME     U59 6
 '@T6G_MB_LIB.T6G(SCH_1):PAGE343_I22@PURE_QUANTA.74LVC2G07DW7(CHIPS)':
 '1Y': CDS_PINID='\1y\';
NODE_NAME     U59 4
 '@T6G_MB_LIB.T6G(SCH_1):PAGE343_I22@PURE_QUANTA.74LVC2G07DW7(CHIPS)':
 '2Y': CDS_PINID='\2y\';
NODE_NAME     R1191 1
 '@T6G_MB_LIB.T6G(SCH_1):PAGE343_I116@PURE_QUANTA.Q_RES(CHIPS)':
 'A': CDS_PINID='A';
NET_NAME
'HP_LVC3_OCP_V3_2_PRSNT2_PLD_N'
 '@T6G_MB_LIB.T6G(SCH_1):HP_LVC3_OCP_V3_2_PRSNT2_PLD_N':
 C_SIGNAL='@t6g_mb_lib.t6g(sch_1):hp_lvc3_ocp_v3_2_prsnt2_pld_n';
NODE_NAME     R3142 2
 '@T6G_MB_LIB.T6G(SCH_1):PAGE343_I59@PURE_QUANTA.Q_RES(CHIPS)':
 'B': CDS_PINID='B';
NODE_NAME     R3147 2
 '@T6G_MB_LIB.T6G(SCH_1):PAGE343_I69@PURE_QUANTA.Q_RES(CHIPS)':
 'B': CDS_PINID='B';
NODE_NAME     R6117 1
 '@T6G_MB_LIB.T6G(SCH_1):PAGE79_I131@PURE_QUANTA.Q_RES(CHIPS)':
 'A': CDS_PINID='A';
NET_NAME
'HP_LVC3_OCP_V3_2_PWRGD'
 '@T6G_MB_LIB.T6G(SCH_1):HP_LVC3_OCP_V3_2_PWRGD':
 C_SIGNAL='@t6g_mb_lib.t6g(sch_1):hp_lvc3_ocp_v3_2_pwrgd';
NODE_NAME     R1173 2
 '@T6G_MB_LIB.T6G(SCH_1):PAGE257_I16@PURE_QUANTA.Q_RES(CHIPS)':
 'B': CDS_PINID='B';
NODE_NAME     U35 2
 '@T6G_MB_LIB.T6G(SCH_1):PAGE257_I63@PURE_QUANTA.74LVC1G08W57(CHIPS)':
 'B': CDS_PINID='B';
NET_NAME
'HP_LVC3_OCP_V3_2_PWRGD_R1'
 '@T6G_MB_LIB.T6G(SCH_1):HP_LVC3_OCP_V3_2_PWRGD_R1':
 C_SIGNAL='@t6g_mb_lib.t6g(sch_1):hp_lvc3_ocp_v3_2_pwrgd_r1';
NODE_NAME     R1178 2
 '@T6G_MB_LIB.T6G(SCH_1):PAGE257_I12@PURE_QUANTA.Q_RES(CHIPS)':
 'B': CDS_PINID='B';
NODE_NAME     U37 1
 '@T6G_MB_LIB.T6G(SCH_1):PAGE257_I40@PURE_QUANTA.74LVC1G32GW(CHIPS)':
 'I0': CDS_PINID='I0';
NODE_NAME     R1146 2
 '@T6G_MB_LIB.T6G(SCH_1):PAGE257_I41@PURE_QUANTA.Q_RES(CHIPS)':
 'B': CDS_PINID='B';
NET_NAME
'HP_LVC3_OCP_V3_2_PWRGD_R2'
 '@T6G_MB_LIB.T6G(SCH_1):HP_LVC3_OCP_V3_2_PWRGD_R2':
 C_SIGNAL='@t6g_mb_lib.t6g(sch_1):hp_lvc3_ocp_v3_2_pwrgd_r2';
NODE_NAME     U9051 4
 '@T6G_MB_LIB.T6G(SCH_1):PAGE257_I78@PURE_QUANTA.74LVC1G08W57(CHIPS)':
 'Y': CDS_PINID='Y';
NODE_NAME     R1524 1
 '@T6G_MB_LIB.T6G(SCH_1):PAGE257_I89@PURE_QUANTA.Q_RES(CHIPS)':
 'A': CDS_PINID='A';
NET_NAME
'HP_LVC3_OCP_V3_2_R_EN'
 '@T6G_MB_LIB.T6G(SCH_1):HP_LVC3_OCP_V3_2_R_EN':
 C_SIGNAL='@t6g_mb_lib.t6g(sch_1):hp_lvc3_ocp_v3_2_r_en';
NODE_NAME     U235 5
 '@T6G_MB_LIB.T6G(SCH_1):PAGE248_I6@PURE_QUANTA.PCA9617ADP(CHIPS)':
 'EN': CDS_PINID='EN';
NODE_NAME     R3264 1
 '@T6G_MB_LIB.T6G(SCH_1):PAGE248_I38@PURE_QUANTA.Q_RES(CHIPS)':
 'A': CDS_PINID='A';
NODE_NAME     R1522 1
 '@T6G_MB_LIB.T6G(SCH_1):PAGE248_I44@PURE_QUANTA.Q_RES(CHIPS)':
 'A': CDS_PINID='A';
NODE_NAME     R1180 1
 '@T6G_MB_LIB.T6G(SCH_1):PAGE248_I45@PURE_QUANTA.Q_RES(CHIPS)':
 'A': CDS_PINID='A';
NET_NAME
'HP_LVC3_SCM_HSC_PWRGD'
 '@T6G_MB_LIB.T6G(SCH_1):HP_LVC3_SCM_HSC_PWRGD':
 C_SIGNAL='@t6g_mb_lib.t6g(sch_1):hp_lvc3_scm_hsc_pwrgd';
NODE_NAME     PR4012 2
 '@T6G_MB_LIB.T6G(SCH_1):PAGE350_I73@PURE_QUANTA.Q_RES(CHIPS)':
 'B': CDS_PINID='B';
NODE_NAME     R4015 2
 '@T6G_MB_LIB.T6G(SCH_1):PAGE350_I78@PURE_QUANTA.Q_RES(CHIPS)':
 'B': CDS_PINID='B';
NODE_NAME     R6055 1
 '@T6G_MB_LIB.T6G(SCH_1):PAGE80_I60@PURE_QUANTA.Q_RES(CHIPS)':
 'A': CDS_PINID='A';
NODE_NAME     R8012 2
 '@T6G_MB_LIB.T6G(SCH_1):PAGE350_I89@PURE_QUANTA.Q_RES(CHIPS)':
 'B': CDS_PINID='B';
NET_NAME
'HP_LVC3_SCM_HSC_PWRGD_R'
 '@T6G_MB_LIB.T6G(SCH_1):HP_LVC3_SCM_HSC_PWRGD_R':
 C_SIGNAL='@t6g_mb_lib.t6g(sch_1):hp_lvc3_scm_hsc_pwrgd_r';
NODE_NAME     R3836 2
 '@T6G_MB_LIB.T6G(SCH_1):PAGE350_I43@PURE_QUANTA.Q_RES(CHIPS)':
 'B': CDS_PINID='B';
NODE_NAME     R8012 1
 '@T6G_MB_LIB.T6G(SCH_1):PAGE350_I89@PURE_QUANTA.Q_RES(CHIPS)':
 'A': CDS_PINID='A';
NODE_NAME     PU299 10
 '@T6G_MB_LIB.T6G(SCH_1):PAGE350_I95@PURE_QUANTA.RS31312R(CHIPS)':
 'PG': CDS_PINID='PG';
NET_NAME
'HSC_ADDR'
 '@T6G_MB_LIB.T6G(SCH_1):HSC_ADDR':
 C_SIGNAL='@t6g_mb_lib.t6g(sch_1):hsc_addr';
NODE_NAME     PR3930 2
 '@T6G_MB_LIB.T6G(SCH_1):PAGE267_I52@PURE_QUANTA.Q_RES(CHIPS)':
 'B': CDS_PINID='B';
NODE_NAME     PR3929 1
 '@T6G_MB_LIB.T6G(SCH_1):PAGE267_I53@PURE_QUANTA.Q_RES(CHIPS)':
 'A': CDS_PINID='A';
NODE_NAME     PU289 23
 '@T6G_MB_LIB.T6G(SCH_1):PAGE267_I58@PURE_QUANTA.MP5990GMA1111Z(CHIPS)':
 'ADDR': CDS_PINID='ADDR';
NET_NAME
'HSC_CS'
 '@T6G_MB_LIB.T6G(SCH_1):HSC_CS':
 C_SIGNAL='@t6g_mb_lib.t6g(sch_1):hsc_cs';
NODE_NAME     PU289 20
 '@T6G_MB_LIB.T6G(SCH_1):PAGE267_I58@PURE_QUANTA.MP5990GMA1111Z(CHIPS)':
 'CS': CDS_PINID='CS';
NODE_NAME     PR1131 1
 '@T6G_MB_LIB.T6G(SCH_1):PAGE267_I65@PURE_QUANTA.Q_RES(CHIPS)':
 'A': CDS_PINID='A';
NET_NAME
'HSC_CSOUT'
 '@T6G_MB_LIB.T6G(SCH_1):HSC_CSOUT':
 C_SIGNAL='@t6g_mb_lib.t6g(sch_1):hsc_csout';
NODE_NAME     PJ38 16
 '@T6G_MB_LIB.T6G(SCH_1):PAGE371_I42@PURE_QUANTA.SCONN21_9193031121LF(CHIPS)':
 '16': CDS_PINID='\16\';
NODE_NAME     R6234 1
 '@T6G_MB_LIB.T6G(SCH_1):PAGE371_I55@PURE_QUANTA.Q_RES(CHIPS)':
 'A': CDS_PINID='A';
NODE_NAME     R6232 1
 '@T6G_MB_LIB.T6G(SCH_1):PAGE371_I56@PURE_QUANTA.Q_RES(CHIPS)':
 'A': CDS_PINID='A';
NODE_NAME     R6210 1
 '@T6G_MB_LIB.T6G(SCH_1):PAGE371_I73@PURE_QUANTA.Q_RES(CHIPS)':
 'A': CDS_PINID='A';
NODE_NAME     R8108 1
 '@T6G_MB_LIB.T6G(SCH_1):PAGE371_I84@PURE_QUANTA.Q_RES(CHIPS)':
 'A': CDS_PINID='A';
NET_NAME
'HSC_CS_1'
 '@T6G_MB_LIB.T6G(SCH_1):HSC_CS_1':
 C_SIGNAL='@t6g_mb_lib.t6g(sch_1):hsc_cs_1';
NODE_NAME     PR3914 1
 '@T6G_MB_LIB.T6G(SCH_1):PAGE301_I31@PURE_QUANTA.Q_RES(CHIPS)':
 'A': CDS_PINID='A';
NODE_NAME     PU287 23
 '@T6G_MB_LIB.T6G(SCH_1):PAGE301_I35@PURE_QUANTA.MP5991GLUZ(CHIPS)':
 'CS': CDS_PINID='CS';
NET_NAME
'HSC_CS_2'
 '@T6G_MB_LIB.T6G(SCH_1):HSC_CS_2':
 C_SIGNAL='@t6g_mb_lib.t6g(sch_1):hsc_cs_2';
NODE_NAME     PR3915 1
 '@T6G_MB_LIB.T6G(SCH_1):PAGE301_I13@PURE_QUANTA.Q_RES(CHIPS)':
 'A': CDS_PINID='A';
NODE_NAME     PU288 23
 '@T6G_MB_LIB.T6G(SCH_1):PAGE301_I16@PURE_QUANTA.MP5991GLUZ(CHIPS)':
 'CS': CDS_PINID='CS';
NET_NAME
'HSC_CS_3'
 '@T6G_MB_LIB.T6G(SCH_1):HSC_CS_3':
 C_SIGNAL='@t6g_mb_lib.t6g(sch_1):hsc_cs_3';
NODE_NAME     PR3986 1
 '@T6G_MB_LIB.T6G(SCH_1):PAGE325_I31@PURE_QUANTA.Q_RES(CHIPS)':
 'A': CDS_PINID='A';
NODE_NAME     PU296 23
 '@T6G_MB_LIB.T6G(SCH_1):PAGE325_I35@PURE_QUANTA.MP5991GLUZ(CHIPS)':
 'CS': CDS_PINID='CS';
NET_NAME
'HSC_CS_4'
 '@T6G_MB_LIB.T6G(SCH_1):HSC_CS_4':
 C_SIGNAL='@t6g_mb_lib.t6g(sch_1):hsc_cs_4';
NODE_NAME     PR3987 1
 '@T6G_MB_LIB.T6G(SCH_1):PAGE325_I13@PURE_QUANTA.Q_RES(CHIPS)':
 'A': CDS_PINID='A';
NODE_NAME     PU297 23
 '@T6G_MB_LIB.T6G(SCH_1):PAGE325_I17@PURE_QUANTA.MP5991GLUZ(CHIPS)':
 'CS': CDS_PINID='CS';
NET_NAME
'HSC_D_OC'
 '@T6G_MB_LIB.T6G(SCH_1):HSC_D_OC':
 C_SIGNAL='@t6g_mb_lib.t6g(sch_1):hsc_d_oc';
NODE_NAME     R6039 2
 '@T6G_MB_LIB.T6G(SCH_1):PAGE79_I20@PURE_QUANTA.Q_RES(CHIPS)':
 'B': CDS_PINID='B';
NODE_NAME     R3934 2
 '@T6G_MB_LIB.T6G(SCH_1):PAGE267_I80@PURE_QUANTA.Q_RES(CHIPS)':
 'B': CDS_PINID='B';
NODE_NAME     R3936 2
 '@T6G_MB_LIB.T6G(SCH_1):PAGE267_I91@PURE_QUANTA.Q_RES(CHIPS)':
 'B': CDS_PINID='B';
NODE_NAME     U142 6
 '@T6G_MB_LIB.T6G(SCH_1):PAGE371_I50@PURE_QUANTA.LT6700CS61TRPBF(CHIPS)':
 'OUTB': CDS_PINID='OUTB';
NODE_NAME     R6239 2
 '@T6G_MB_LIB.T6G(SCH_1):PAGE371_I70@PURE_QUANTA.Q_RES(CHIPS)':
 'B': CDS_PINID='B';
NODE_NAME     R6238 2
 '@T6G_MB_LIB.T6G(SCH_1):PAGE371_I72@PURE_QUANTA.Q_RES(CHIPS)':
 'B': CDS_PINID='B';
NODE_NAME     R6210 2
 '@T6G_MB_LIB.T6G(SCH_1):PAGE371_I73@PURE_QUANTA.Q_RES(CHIPS)':
 'B': CDS_PINID='B';
NET_NAME
'HSC_D_OC_1'
 '@T6G_MB_LIB.T6G(SCH_1):HSC_D_OC_1':
 C_SIGNAL='@t6g_mb_lib.t6g(sch_1):hsc_d_oc_1';
NODE_NAME     PU287 3
 '@T6G_MB_LIB.T6G(SCH_1):PAGE301_I35@PURE_QUANTA.MP5991GLUZ(CHIPS)':
 'D_OC': CDS_PINID='D_OC';
NODE_NAME     PR3919 1
 '@T6G_MB_LIB.T6G(SCH_1):PAGE301_I50@PURE_QUANTA.Q_RES(CHIPS)':
 'A': CDS_PINID='A';
NET_NAME
'HSC_D_OC_2'
 '@T6G_MB_LIB.T6G(SCH_1):HSC_D_OC_2':
 C_SIGNAL='@t6g_mb_lib.t6g(sch_1):hsc_d_oc_2';
NODE_NAME     PU288 3
 '@T6G_MB_LIB.T6G(SCH_1):PAGE301_I16@PURE_QUANTA.MP5991GLUZ(CHIPS)':
 'D_OC': CDS_PINID='D_OC';
NODE_NAME     PR3921 1
 '@T6G_MB_LIB.T6G(SCH_1):PAGE301_I40@PURE_QUANTA.Q_RES(CHIPS)':
 'A': CDS_PINID='A';
NET_NAME
'HSC_D_OC_3'
 '@T6G_MB_LIB.T6G(SCH_1):HSC_D_OC_3':
 C_SIGNAL='@t6g_mb_lib.t6g(sch_1):hsc_d_oc_3';
NODE_NAME     PU296 3
 '@T6G_MB_LIB.T6G(SCH_1):PAGE325_I35@PURE_QUANTA.MP5991GLUZ(CHIPS)':
 'D_OC': CDS_PINID='D_OC';
NODE_NAME     PR3992 1
 '@T6G_MB_LIB.T6G(SCH_1):PAGE325_I50@PURE_QUANTA.Q_RES(CHIPS)':
 'A': CDS_PINID='A';
NET_NAME
'HSC_D_OC_4'
 '@T6G_MB_LIB.T6G(SCH_1):HSC_D_OC_4':
 C_SIGNAL='@t6g_mb_lib.t6g(sch_1):hsc_d_oc_4';
NODE_NAME     PU297 3
 '@T6G_MB_LIB.T6G(SCH_1):PAGE325_I17@PURE_QUANTA.MP5991GLUZ(CHIPS)':
 'D_OC': CDS_PINID='D_OC';
NODE_NAME     PR3994 1
 '@T6G_MB_LIB.T6G(SCH_1):PAGE325_I40@PURE_QUANTA.Q_RES(CHIPS)':
 'A': CDS_PINID='A';
NET_NAME
'HSC_D_OC_R'
 '@T6G_MB_LIB.T6G(SCH_1):HSC_D_OC_R':
 C_SIGNAL='@t6g_mb_lib.t6g(sch_1):hsc_d_oc_r';
NODE_NAME     PR3921 2
 '@T6G_MB_LIB.T6G(SCH_1):PAGE301_I40@PURE_QUANTA.Q_RES(CHIPS)':
 'B': CDS_PINID='B';
NODE_NAME     PR3919 2
 '@T6G_MB_LIB.T6G(SCH_1):PAGE301_I50@PURE_QUANTA.Q_RES(CHIPS)':
 'B': CDS_PINID='B';
NODE_NAME     PR3994 2
 '@T6G_MB_LIB.T6G(SCH_1):PAGE325_I40@PURE_QUANTA.Q_RES(CHIPS)':
 'B': CDS_PINID='B';
NODE_NAME     PR3992 2
 '@T6G_MB_LIB.T6G(SCH_1):PAGE325_I50@PURE_QUANTA.Q_RES(CHIPS)':
 'B': CDS_PINID='B';
NODE_NAME     PU289 37
 '@T6G_MB_LIB.T6G(SCH_1):PAGE267_I58@PURE_QUANTA.MP5990GMA1111Z(CHIPS)':
 'D_OC': CDS_PINID='D_OC';
NODE_NAME     R3934 1
 '@T6G_MB_LIB.T6G(SCH_1):PAGE267_I80@PURE_QUANTA.Q_RES(CHIPS)':
 'A': CDS_PINID='A';
NET_NAME
'HSC_D_OC_R2'
 '@T6G_MB_LIB.T6G(SCH_1):HSC_D_OC_R2':
 C_SIGNAL='@t6g_mb_lib.t6g(sch_1):hsc_d_oc_r2';
NODE_NAME     R8110 1
 '@T6G_MB_LIB.T6G(SCH_1):PAGE371_I96@PURE_QUANTA.Q_RES(CHIPS)':
 'A': CDS_PINID='A';
NODE_NAME     R8112 2
 '@T6G_MB_LIB.T6G(SCH_1):PAGE371_I103@PURE_QUANTA.Q_RES(CHIPS)':
 'B': CDS_PINID='B';
NODE_NAME     U8006 4
 '@T6G_MB_LIB.T6G(SCH_1):PAGE371_I104@PURE_QUANTA.AP331AWG7(CHIPS)':
 'OUTPUT': CDS_PINID='OUTPUT';
NET_NAME
'HSC_EN'
 '@T6G_MB_LIB.T6G(SCH_1):HSC_EN':
 C_SIGNAL='@t6g_mb_lib.t6g(sch_1):hsc_en';
NODE_NAME     R2586 1
 '@T6G_MB_LIB.T6G(SCH_1):PAGE267_I54@PURE_QUANTA.Q_RES(CHIPS)':
 'A': CDS_PINID='A';
NODE_NAME     U290 D
 '@T6G_MB_LIB.T6G(SCH_1):PAGE372_I11@PURE_QUANTA.MOSFET_NCH_GDS_ESD_PROTECTED(CHIPS)':
 'D': CDS_PINID='D';
NODE_NAME     R2585 1
 '@T6G_MB_LIB.T6G(SCH_1):PAGE372_I13@PURE_QUANTA.Q_RES(CHIPS)':
 'A': CDS_PINID='A';
NODE_NAME     R4901 2
 '@T6G_MB_LIB.T6G(SCH_1):PAGE372_I19@PURE_QUANTA.Q_RES(CHIPS)':
 'B': CDS_PINID='B';
NODE_NAME     C2179 1
 '@T6G_MB_LIB.T6G(SCH_1):PAGE372_I22@PURE_QUANTA.Q_CAP(CHIPS)':
 'A': CDS_PINID='A';
NODE_NAME     PJ38 14
 '@T6G_MB_LIB.T6G(SCH_1):PAGE371_I42@PURE_QUANTA.SCONN21_9193031121LF(CHIPS)':
 '14': CDS_PINID='\14\';
NET_NAME
'HSC_EN_R'
 '@T6G_MB_LIB.T6G(SCH_1):HSC_EN_R':
 C_SIGNAL='@t6g_mb_lib.t6g(sch_1):hsc_en_r';
NODE_NAME     R2586 2
 '@T6G_MB_LIB.T6G(SCH_1):PAGE267_I54@PURE_QUANTA.Q_RES(CHIPS)':
 'B': CDS_PINID='B';
NODE_NAME     PU289 26
 '@T6G_MB_LIB.T6G(SCH_1):PAGE267_I58@PURE_QUANTA.MP5990GMA1111Z(CHIPS)':
 'EN': CDS_PINID='EN';
NET_NAME
'HSC_FAULT'
 '@T6G_MB_LIB.T6G(SCH_1):HSC_FAULT':
 C_SIGNAL='@t6g_mb_lib.t6g(sch_1):hsc_fault';
NODE_NAME     PU288 5
 '@T6G_MB_LIB.T6G(SCH_1):PAGE301_I16@PURE_QUANTA.MP5991GLUZ(CHIPS)':
 'GOK': CDS_PINID='GOK';
NODE_NAME     PU287 5
 '@T6G_MB_LIB.T6G(SCH_1):PAGE301_I35@PURE_QUANTA.MP5991GLUZ(CHIPS)':
 'GOK': CDS_PINID='GOK';
NODE_NAME     PU297 5
 '@T6G_MB_LIB.T6G(SCH_1):PAGE325_I17@PURE_QUANTA.MP5991GLUZ(CHIPS)':
 'GOK': CDS_PINID='GOK';
NODE_NAME     PU296 5
 '@T6G_MB_LIB.T6G(SCH_1):PAGE325_I35@PURE_QUANTA.MP5991GLUZ(CHIPS)':
 'GOK': CDS_PINID='GOK';
NODE_NAME     PU289 39
 '@T6G_MB_LIB.T6G(SCH_1):PAGE267_I58@PURE_QUANTA.MP5990GMA1111Z(CHIPS)':
 'GOK': CDS_PINID='GOK';
NODE_NAME     R2588 1
 '@T6G_MB_LIB.T6G(SCH_1):PAGE267_I79@PURE_QUANTA.Q_RES(CHIPS)':
 'A': CDS_PINID='A';
NET_NAME
'HSC_FLT_TYPE'
 '@T6G_MB_LIB.T6G(SCH_1):HSC_FLT_TYPE':
 C_SIGNAL='@t6g_mb_lib.t6g(sch_1):hsc_flt_type';
NODE_NAME     PR3922 2
 '@T6G_MB_LIB.T6G(SCH_1):PAGE301_I39@PURE_QUANTA.Q_RES(CHIPS)':
 'B': CDS_PINID='B';
NODE_NAME     PR3920 2
 '@T6G_MB_LIB.T6G(SCH_1):PAGE301_I49@PURE_QUANTA.Q_RES(CHIPS)':
 'B': CDS_PINID='B';
NODE_NAME     PR3995 2
 '@T6G_MB_LIB.T6G(SCH_1):PAGE325_I39@PURE_QUANTA.Q_RES(CHIPS)':
 'B': CDS_PINID='B';
NODE_NAME     PR3993 2
 '@T6G_MB_LIB.T6G(SCH_1):PAGE325_I49@PURE_QUANTA.Q_RES(CHIPS)':
 'B': CDS_PINID='B';
NODE_NAME     PU289 40
 '@T6G_MB_LIB.T6G(SCH_1):PAGE267_I58@PURE_QUANTA.MP5990GMA1111Z(CHIPS)':
 'FLT_TYPE': CDS_PINID='FLT_TYPE';
NET_NAME
'HSC_FLT_TYPE_1'
 '@T6G_MB_LIB.T6G(SCH_1):HSC_FLT_TYPE_1':
 C_SIGNAL='@t6g_mb_lib.t6g(sch_1):hsc_flt_type_1';
NODE_NAME     PU287 6
 '@T6G_MB_LIB.T6G(SCH_1):PAGE301_I35@PURE_QUANTA.MP5991GLUZ(CHIPS)':
 'FLT_TYPE': CDS_PINID='FLT_TYPE';
NODE_NAME     PR3920 1
 '@T6G_MB_LIB.T6G(SCH_1):PAGE301_I49@PURE_QUANTA.Q_RES(CHIPS)':
 'A': CDS_PINID='A';
NET_NAME
'HSC_FLT_TYPE_2'
 '@T6G_MB_LIB.T6G(SCH_1):HSC_FLT_TYPE_2':
 C_SIGNAL='@t6g_mb_lib.t6g(sch_1):hsc_flt_type_2';
NODE_NAME     PU288 6
 '@T6G_MB_LIB.T6G(SCH_1):PAGE301_I16@PURE_QUANTA.MP5991GLUZ(CHIPS)':
 'FLT_TYPE': CDS_PINID='FLT_TYPE';
NODE_NAME     PR3922 1
 '@T6G_MB_LIB.T6G(SCH_1):PAGE301_I39@PURE_QUANTA.Q_RES(CHIPS)':
 'A': CDS_PINID='A';
NET_NAME
'HSC_FLT_TYPE_3'
 '@T6G_MB_LIB.T6G(SCH_1):HSC_FLT_TYPE_3':
 C_SIGNAL='@t6g_mb_lib.t6g(sch_1):hsc_flt_type_3';
NODE_NAME     PU296 6
 '@T6G_MB_LIB.T6G(SCH_1):PAGE325_I35@PURE_QUANTA.MP5991GLUZ(CHIPS)':
 'FLT_TYPE': CDS_PINID='FLT_TYPE';
NODE_NAME     PR3993 1
 '@T6G_MB_LIB.T6G(SCH_1):PAGE325_I49@PURE_QUANTA.Q_RES(CHIPS)':
 'A': CDS_PINID='A';
NET_NAME
'HSC_FLT_TYPE_4'
 '@T6G_MB_LIB.T6G(SCH_1):HSC_FLT_TYPE_4':
 C_SIGNAL='@t6g_mb_lib.t6g(sch_1):hsc_flt_type_4';
NODE_NAME     PU297 6
 '@T6G_MB_LIB.T6G(SCH_1):PAGE325_I17@PURE_QUANTA.MP5991GLUZ(CHIPS)':
 'FLT_TYPE': CDS_PINID='FLT_TYPE';
NODE_NAME     PR3995 1
 '@T6G_MB_LIB.T6G(SCH_1):PAGE325_I39@PURE_QUANTA.Q_RES(CHIPS)':
 'A': CDS_PINID='A';
NET_NAME
'HSC_IMON'
 '@T6G_MB_LIB.T6G(SCH_1):HSC_IMON':
 C_SIGNAL='@t6g_mb_lib.t6g(sch_1):hsc_imon';
NODE_NAME     PR1101 1
 '@T6G_MB_LIB.T6G(SCH_1):PAGE301_I15@PURE_QUANTA.Q_RES(CHIPS)':
 'A': CDS_PINID='A';
NODE_NAME     PU288 22
 '@T6G_MB_LIB.T6G(SCH_1):PAGE301_I16@PURE_QUANTA.MP5991GLUZ(CHIPS)':
 'IMON': CDS_PINID='IMON';
NODE_NAME     PR3918 1
 '@T6G_MB_LIB.T6G(SCH_1):PAGE301_I34@PURE_QUANTA.Q_RES(CHIPS)':
 'A': CDS_PINID='A';
NODE_NAME     PU287 22
 '@T6G_MB_LIB.T6G(SCH_1):PAGE301_I35@PURE_QUANTA.MP5991GLUZ(CHIPS)':
 'IMON': CDS_PINID='IMON';
NODE_NAME     PR3991 1
 '@T6G_MB_LIB.T6G(SCH_1):PAGE325_I14@PURE_QUANTA.Q_RES(CHIPS)':
 'A': CDS_PINID='A';
NODE_NAME     PU297 22
 '@T6G_MB_LIB.T6G(SCH_1):PAGE325_I17@PURE_QUANTA.MP5991GLUZ(CHIPS)':
 'IMON': CDS_PINID='IMON';
NODE_NAME     PR3990 1
 '@T6G_MB_LIB.T6G(SCH_1):PAGE325_I34@PURE_QUANTA.Q_RES(CHIPS)':
 'A': CDS_PINID='A';
NODE_NAME     PU296 22
 '@T6G_MB_LIB.T6G(SCH_1):PAGE325_I35@PURE_QUANTA.MP5991GLUZ(CHIPS)':
 'IMON': CDS_PINID='IMON';
NODE_NAME     PU289 21
 '@T6G_MB_LIB.T6G(SCH_1):PAGE267_I58@PURE_QUANTA.MP5990GMA1111Z(CHIPS)':
 'IMON': CDS_PINID='IMON';
NODE_NAME     PC2193 1
 '@T6G_MB_LIB.T6G(SCH_1):PAGE267_I84@PURE_QUANTA.Q_CAP(CHIPS)':
 'A': CDS_PINID='A';
NODE_NAME     PR1133 1
 '@T6G_MB_LIB.T6G(SCH_1):PAGE267_I86@PURE_QUANTA.Q_RES(CHIPS)':
 'A': CDS_PINID='A';
NET_NAME
'HSC_MODE'
 '@T6G_MB_LIB.T6G(SCH_1):HSC_MODE':
 C_SIGNAL='@t6g_mb_lib.t6g(sch_1):hsc_mode';
NODE_NAME     PU289 41
 '@T6G_MB_LIB.T6G(SCH_1):PAGE267_I58@PURE_QUANTA.MP5990GMA1111Z(CHIPS)':
 'MODE': CDS_PINID='MODE';
NODE_NAME     PR3937 1
 '@T6G_MB_LIB.T6G(SCH_1):PAGE267_I85@PURE_QUANTA.Q_RES(CHIPS)':
 'A': CDS_PINID='A';
NET_NAME
'HSC_MODE_1'
 '@T6G_MB_LIB.T6G(SCH_1):HSC_MODE_1':
 C_SIGNAL='@t6g_mb_lib.t6g(sch_1):hsc_mode_1';
NODE_NAME     PR1134 2
 '@T6G_MB_LIB.T6G(SCH_1):PAGE301_I29@PURE_QUANTA.Q_RES(CHIPS)':
 'B': CDS_PINID='B';
NODE_NAME     PU287 8
 '@T6G_MB_LIB.T6G(SCH_1):PAGE301_I35@PURE_QUANTA.MP5991GLUZ(CHIPS)':
 'MODE': CDS_PINID='MODE';
NET_NAME
'HSC_MODE_2'
 '@T6G_MB_LIB.T6G(SCH_1):HSC_MODE_2':
 C_SIGNAL='@t6g_mb_lib.t6g(sch_1):hsc_mode_2';
NODE_NAME     PR3912 2
 '@T6G_MB_LIB.T6G(SCH_1):PAGE301_I11@PURE_QUANTA.Q_RES(CHIPS)':
 'B': CDS_PINID='B';
NODE_NAME     PU288 8
 '@T6G_MB_LIB.T6G(SCH_1):PAGE301_I16@PURE_QUANTA.MP5991GLUZ(CHIPS)':
 'MODE': CDS_PINID='MODE';
NET_NAME
'HSC_MODE_3'
 '@T6G_MB_LIB.T6G(SCH_1):HSC_MODE_3':
 C_SIGNAL='@t6g_mb_lib.t6g(sch_1):hsc_mode_3';
NODE_NAME     PR3982 2
 '@T6G_MB_LIB.T6G(SCH_1):PAGE325_I28@PURE_QUANTA.Q_RES(CHIPS)':
 'B': CDS_PINID='B';
NODE_NAME     PU296 8
 '@T6G_MB_LIB.T6G(SCH_1):PAGE325_I35@PURE_QUANTA.MP5991GLUZ(CHIPS)':
 'MODE': CDS_PINID='MODE';
NET_NAME
'HSC_MODE_4'
 '@T6G_MB_LIB.T6G(SCH_1):HSC_MODE_4':
 C_SIGNAL='@t6g_mb_lib.t6g(sch_1):hsc_mode_4';
NODE_NAME     PR3984 2
 '@T6G_MB_LIB.T6G(SCH_1):PAGE325_I11@PURE_QUANTA.Q_RES(CHIPS)':
 'B': CDS_PINID='B';
NODE_NAME     PU297 8
 '@T6G_MB_LIB.T6G(SCH_1):PAGE325_I17@PURE_QUANTA.MP5991GLUZ(CHIPS)':
 'MODE': CDS_PINID='MODE';
NET_NAME
'HSC_NC1_1'
 '@T6G_MB_LIB.T6G(SCH_1):HSC_NC1_1':
 C_SIGNAL='@t6g_mb_lib.t6g(sch_1):hsc_nc1_1';
NODE_NAME     PU287 7
 '@T6G_MB_LIB.T6G(SCH_1):PAGE301_I35@PURE_QUANTA.MP5991GLUZ(CHIPS)':
 'NC1': CDS_PINID='NC1';
NET_NAME
'HSC_NC1_2'
 '@T6G_MB_LIB.T6G(SCH_1):HSC_NC1_2':
 C_SIGNAL='@t6g_mb_lib.t6g(sch_1):hsc_nc1_2';
NODE_NAME     PU288 7
 '@T6G_MB_LIB.T6G(SCH_1):PAGE301_I16@PURE_QUANTA.MP5991GLUZ(CHIPS)':
 'NC1': CDS_PINID='NC1';
NET_NAME
'HSC_NC1_3'
 '@T6G_MB_LIB.T6G(SCH_1):HSC_NC1_3':
 C_SIGNAL='@t6g_mb_lib.t6g(sch_1):hsc_nc1_3';
NODE_NAME     PU296 7
 '@T6G_MB_LIB.T6G(SCH_1):PAGE325_I35@PURE_QUANTA.MP5991GLUZ(CHIPS)':
 'NC1': CDS_PINID='NC1';
NET_NAME
'HSC_NC1_4'
 '@T6G_MB_LIB.T6G(SCH_1):HSC_NC1_4':
 C_SIGNAL='@t6g_mb_lib.t6g(sch_1):hsc_nc1_4';
NODE_NAME     PU297 7
 '@T6G_MB_LIB.T6G(SCH_1):PAGE325_I17@PURE_QUANTA.MP5991GLUZ(CHIPS)':
 'NC1': CDS_PINID='NC1';
NET_NAME
'HSC_OCREF'
 '@T6G_MB_LIB.T6G(SCH_1):HSC_OCREF':
 C_SIGNAL='@t6g_mb_lib.t6g(sch_1):hsc_ocref';
NODE_NAME     PC2348 1
 '@T6G_MB_LIB.T6G(SCH_1):PAGE301_I12@PURE_QUANTA.Q_CAP(CHIPS)':
 'A': CDS_PINID='A';
NODE_NAME     PU288 24
 '@T6G_MB_LIB.T6G(SCH_1):PAGE301_I16@PURE_QUANTA.MP5991GLUZ(CHIPS)':
 'OCREF': CDS_PINID='OCREF';
NODE_NAME     PC2347 1
 '@T6G_MB_LIB.T6G(SCH_1):PAGE301_I30@PURE_QUANTA.Q_CAP(CHIPS)':
 'A': CDS_PINID='A';
NODE_NAME     PU287 24
 '@T6G_MB_LIB.T6G(SCH_1):PAGE301_I35@PURE_QUANTA.MP5991GLUZ(CHIPS)':
 'OCREF': CDS_PINID='OCREF';
NODE_NAME     PC2349 1
 '@T6G_MB_LIB.T6G(SCH_1):PAGE325_I12@PURE_QUANTA.Q_CAP(CHIPS)':
 'A': CDS_PINID='A';
NODE_NAME     PU297 24
 '@T6G_MB_LIB.T6G(SCH_1):PAGE325_I17@PURE_QUANTA.MP5991GLUZ(CHIPS)':
 'OCREF': CDS_PINID='OCREF';
NODE_NAME     PC2350 1
 '@T6G_MB_LIB.T6G(SCH_1):PAGE325_I30@PURE_QUANTA.Q_CAP(CHIPS)':
 'A': CDS_PINID='A';
NODE_NAME     PU296 24
 '@T6G_MB_LIB.T6G(SCH_1):PAGE325_I35@PURE_QUANTA.MP5991GLUZ(CHIPS)':
 'OCREF': CDS_PINID='OCREF';
NODE_NAME     PU289 22
 '@T6G_MB_LIB.T6G(SCH_1):PAGE267_I58@PURE_QUANTA.MP5990GMA1111Z(CHIPS)':
 'OCREF': CDS_PINID='OCREF';
NET_NAME
'HSC_OC_VOL'
 '@T6G_MB_LIB.T6G(SCH_1):HSC_OC_VOL':
 C_SIGNAL='@t6g_mb_lib.t6g(sch_1):hsc_oc_vol';
NODE_NAME     R8109 1
 '@T6G_MB_LIB.T6G(SCH_1):PAGE371_I82@PURE_QUANTA.Q_RES(CHIPS)':
 'A': CDS_PINID='A';
NODE_NAME     R8108 2
 '@T6G_MB_LIB.T6G(SCH_1):PAGE371_I84@PURE_QUANTA.Q_RES(CHIPS)':
 'B': CDS_PINID='B';
NODE_NAME     C8015 1
 '@T6G_MB_LIB.T6G(SCH_1):PAGE371_I89@PURE_QUANTA.Q_CAP(CHIPS)':
 'A': CDS_PINID='A';
NODE_NAME     R8112 1
 '@T6G_MB_LIB.T6G(SCH_1):PAGE371_I103@PURE_QUANTA.Q_RES(CHIPS)':
 'A': CDS_PINID='A';
NODE_NAME     U8006 3
 '@T6G_MB_LIB.T6G(SCH_1):PAGE371_I104@PURE_QUANTA.AP331AWG7(CHIPS)':
 'IN+': CDS_PINID='\in+\';
NET_NAME
'HSC_ON'
 '@T6G_MB_LIB.T6G(SCH_1):HSC_ON':
 C_SIGNAL='@t6g_mb_lib.t6g(sch_1):hsc_on';
NODE_NAME     PC2183 1
 '@T6G_MB_LIB.T6G(SCH_1):PAGE301_I2@PURE_QUANTA.Q_CAP(CHIPS)':
 'A': CDS_PINID='A';
NODE_NAME     PU288 4
 '@T6G_MB_LIB.T6G(SCH_1):PAGE301_I16@PURE_QUANTA.MP5991GLUZ(CHIPS)':
 'ON': CDS_PINID='\on\';
NODE_NAME     PC2182 1
 '@T6G_MB_LIB.T6G(SCH_1):PAGE301_I24@PURE_QUANTA.Q_CAP(CHIPS)':
 'A': CDS_PINID='A';
NODE_NAME     PU287 4
 '@T6G_MB_LIB.T6G(SCH_1):PAGE301_I35@PURE_QUANTA.MP5991GLUZ(CHIPS)':
 'ON': CDS_PINID='\on\';
NODE_NAME     PC2225 1
 '@T6G_MB_LIB.T6G(SCH_1):PAGE325_I2@PURE_QUANTA.Q_CAP(CHIPS)':
 'A': CDS_PINID='A';
NODE_NAME     PU297 4
 '@T6G_MB_LIB.T6G(SCH_1):PAGE325_I17@PURE_QUANTA.MP5991GLUZ(CHIPS)':
 'ON': CDS_PINID='\on\';
NODE_NAME     PC2224 1
 '@T6G_MB_LIB.T6G(SCH_1):PAGE325_I24@PURE_QUANTA.Q_CAP(CHIPS)':
 'A': CDS_PINID='A';
NODE_NAME     PU296 4
 '@T6G_MB_LIB.T6G(SCH_1):PAGE325_I35@PURE_QUANTA.MP5991GLUZ(CHIPS)':
 'ON': CDS_PINID='\on\';
NODE_NAME     PR3928 1
 '@T6G_MB_LIB.T6G(SCH_1):PAGE267_I51@PURE_QUANTA.Q_RES(CHIPS)':
 'A': CDS_PINID='A';
NET_NAME
'HSC_ON_R'
 '@T6G_MB_LIB.T6G(SCH_1):HSC_ON_R':
 C_SIGNAL='@t6g_mb_lib.t6g(sch_1):hsc_on_r';
NODE_NAME     PR3928 2
 '@T6G_MB_LIB.T6G(SCH_1):PAGE267_I51@PURE_QUANTA.Q_RES(CHIPS)':
 'B': CDS_PINID='B';
NODE_NAME     PU289 38
 '@T6G_MB_LIB.T6G(SCH_1):PAGE267_I58@PURE_QUANTA.MP5990GMA1111Z(CHIPS)':
 'ON': CDS_PINID='\on\';
NET_NAME
'HSC_SCREF'
 '@T6G_MB_LIB.T6G(SCH_1):HSC_SCREF':
 C_SIGNAL='@t6g_mb_lib.t6g(sch_1):hsc_scref';
NODE_NAME     PR3917 1
 '@T6G_MB_LIB.T6G(SCH_1):PAGE301_I17@PURE_QUANTA.Q_RES(CHIPS)':
 'A': CDS_PINID='A';
NODE_NAME     PR3916 1
 '@T6G_MB_LIB.T6G(SCH_1):PAGE301_I33@PURE_QUANTA.Q_RES(CHIPS)':
 'A': CDS_PINID='A';
NODE_NAME     PR3989 1
 '@T6G_MB_LIB.T6G(SCH_1):PAGE325_I16@PURE_QUANTA.Q_RES(CHIPS)':
 'A': CDS_PINID='A';
NODE_NAME     PR3988 1
 '@T6G_MB_LIB.T6G(SCH_1):PAGE325_I33@PURE_QUANTA.Q_RES(CHIPS)':
 'A': CDS_PINID='A';
NODE_NAME     PU289 25
 '@T6G_MB_LIB.T6G(SCH_1):PAGE267_I58@PURE_QUANTA.MP5990GMA1111Z(CHIPS)':
 'SCREF_OCWREF': CDS_PINID='SCREF_OCWREF';
NET_NAME
'HSC_SCREF_1'
 '@T6G_MB_LIB.T6G(SCH_1):HSC_SCREF_1':
 C_SIGNAL='@t6g_mb_lib.t6g(sch_1):hsc_scref_1';
NODE_NAME     PR3916 2
 '@T6G_MB_LIB.T6G(SCH_1):PAGE301_I33@PURE_QUANTA.Q_RES(CHIPS)':
 'B': CDS_PINID='B';
NODE_NAME     PU287 17
 '@T6G_MB_LIB.T6G(SCH_1):PAGE301_I35@PURE_QUANTA.MP5991GLUZ(CHIPS)':
 'SCREF_OCWREF': CDS_PINID='SCREF_OCWREF';
NET_NAME
'HSC_SCREF_2'
 '@T6G_MB_LIB.T6G(SCH_1):HSC_SCREF_2':
 C_SIGNAL='@t6g_mb_lib.t6g(sch_1):hsc_scref_2';
NODE_NAME     PU288 17
 '@T6G_MB_LIB.T6G(SCH_1):PAGE301_I16@PURE_QUANTA.MP5991GLUZ(CHIPS)':
 'SCREF_OCWREF': CDS_PINID='SCREF_OCWREF';
NODE_NAME     PR3917 2
 '@T6G_MB_LIB.T6G(SCH_1):PAGE301_I17@PURE_QUANTA.Q_RES(CHIPS)':
 'B': CDS_PINID='B';
NET_NAME
'HSC_SCREF_3'
 '@T6G_MB_LIB.T6G(SCH_1):HSC_SCREF_3':
 C_SIGNAL='@t6g_mb_lib.t6g(sch_1):hsc_scref_3';
NODE_NAME     PR3988 2
 '@T6G_MB_LIB.T6G(SCH_1):PAGE325_I33@PURE_QUANTA.Q_RES(CHIPS)':
 'B': CDS_PINID='B';
NODE_NAME     PU296 17
 '@T6G_MB_LIB.T6G(SCH_1):PAGE325_I35@PURE_QUANTA.MP5991GLUZ(CHIPS)':
 'SCREF_OCWREF': CDS_PINID='SCREF_OCWREF';
NET_NAME
'HSC_SCREF_4'
 '@T6G_MB_LIB.T6G(SCH_1):HSC_SCREF_4':
 C_SIGNAL='@t6g_mb_lib.t6g(sch_1):hsc_scref_4';
NODE_NAME     PR3989 2
 '@T6G_MB_LIB.T6G(SCH_1):PAGE325_I16@PURE_QUANTA.Q_RES(CHIPS)':
 'B': CDS_PINID='B';
NODE_NAME     PU297 17
 '@T6G_MB_LIB.T6G(SCH_1):PAGE325_I17@PURE_QUANTA.MP5991GLUZ(CHIPS)':
 'SCREF_OCWREF': CDS_PINID='SCREF_OCWREF';
NET_NAME
'HSC_SS'
 '@T6G_MB_LIB.T6G(SCH_1):HSC_SS':
 C_SIGNAL='@t6g_mb_lib.t6g(sch_1):hsc_ss';
NODE_NAME     PU288 19
 '@T6G_MB_LIB.T6G(SCH_1):PAGE301_I16@PURE_QUANTA.MP5991GLUZ(CHIPS)':
 'SS': CDS_PINID='SS';
NODE_NAME     PU287 19
 '@T6G_MB_LIB.T6G(SCH_1):PAGE301_I35@PURE_QUANTA.MP5991GLUZ(CHIPS)':
 'SS': CDS_PINID='SS';
NODE_NAME     PC2185 1
 '@T6G_MB_LIB.T6G(SCH_1):PAGE301_I38@PURE_QUANTA.Q_CAP(CHIPS)':
 'A': CDS_PINID='A';
NODE_NAME     PC2184 1
 '@T6G_MB_LIB.T6G(SCH_1):PAGE301_I47@PURE_QUANTA.Q_CAP(CHIPS)':
 'A': CDS_PINID='A';
NODE_NAME     PU297 19
 '@T6G_MB_LIB.T6G(SCH_1):PAGE325_I17@PURE_QUANTA.MP5991GLUZ(CHIPS)':
 'SS': CDS_PINID='SS';
NODE_NAME     PU296 19
 '@T6G_MB_LIB.T6G(SCH_1):PAGE325_I35@PURE_QUANTA.MP5991GLUZ(CHIPS)':
 'SS': CDS_PINID='SS';
NODE_NAME     PC2227 1
 '@T6G_MB_LIB.T6G(SCH_1):PAGE325_I38@PURE_QUANTA.Q_CAP(CHIPS)':
 'A': CDS_PINID='A';
NODE_NAME     PC2226 1
 '@T6G_MB_LIB.T6G(SCH_1):PAGE325_I47@PURE_QUANTA.Q_CAP(CHIPS)':
 'A': CDS_PINID='A';
NODE_NAME     PU289 16
 '@T6G_MB_LIB.T6G(SCH_1):PAGE267_I58@PURE_QUANTA.MP5990GMA1111Z(CHIPS)':
 'SS': CDS_PINID='SS';
NODE_NAME     PC2191 1
 '@T6G_MB_LIB.T6G(SCH_1):PAGE267_I75@PURE_QUANTA.Q_CAP(CHIPS)':
 'A': CDS_PINID='A';
NET_NAME
'HSC_TYPE_ADC'
 '@T6G_MB_LIB.T6G(SCH_1):HSC_TYPE_ADC':
 C_SIGNAL='@t6g_mb_lib.t6g(sch_1):hsc_type_adc';
NODE_NAME     PJ38 17
 '@T6G_MB_LIB.T6G(SCH_1):PAGE371_I42@PURE_QUANTA.SCONN21_9193031121LF(CHIPS)':
 '17': CDS_PINID='\17\';
NODE_NAME     C6086 1
 '@T6G_MB_LIB.T6G(SCH_1):PAGE271_I11@PURE_QUANTA.Q_CAP(CHIPS)':
 'A': CDS_PINID='A';
NODE_NAME     U6005 11
 '@T6G_MB_LIB.T6G(SCH_1):PAGE271_I28@PURE_QUANTA.ISL28022FRZT(CHIPS)':
 'VBUS': CDS_PINID='VBUS';
NET_NAME
'HSC_TYPE_ADC_A0'
 '@T6G_MB_LIB.T6G(SCH_1):HSC_TYPE_ADC_A0':
 C_SIGNAL='@t6g_mb_lib.t6g(sch_1):hsc_type_adc_a0';
NODE_NAME     R6251 2
 '@T6G_MB_LIB.T6G(SCH_1):PAGE271_I14@PURE_QUANTA.Q_RES(CHIPS)':
 'B': CDS_PINID='B';
NODE_NAME     U6005 2
 '@T6G_MB_LIB.T6G(SCH_1):PAGE271_I28@PURE_QUANTA.ISL28022FRZT(CHIPS)':
 'A0': CDS_PINID='A0';
NODE_NAME     R6254 1
 '@T6G_MB_LIB.T6G(SCH_1):PAGE271_I29@PURE_QUANTA.Q_RES(CHIPS)':
 'A': CDS_PINID='A';
NET_NAME
'HSC_TYPE_ADC_A1'
 '@T6G_MB_LIB.T6G(SCH_1):HSC_TYPE_ADC_A1':
 C_SIGNAL='@t6g_mb_lib.t6g(sch_1):hsc_type_adc_a1';
NODE_NAME     U6005 1
 '@T6G_MB_LIB.T6G(SCH_1):PAGE271_I28@PURE_QUANTA.ISL28022FRZT(CHIPS)':
 'A1': CDS_PINID='A1';
NODE_NAME     R6250 2
 '@T6G_MB_LIB.T6G(SCH_1):PAGE271_I30@PURE_QUANTA.Q_RES(CHIPS)':
 'B': CDS_PINID='B';
NET_NAME
'HSC_TYPE_ADC_ALERT'
 '@T6G_MB_LIB.T6G(SCH_1):HSC_TYPE_ADC_ALERT':
 C_SIGNAL='@t6g_mb_lib.t6g(sch_1):hsc_type_adc_alert';
NODE_NAME     R6247 2
 '@T6G_MB_LIB.T6G(SCH_1):PAGE271_I25@PURE_QUANTA.Q_RES(CHIPS)':
 'B': CDS_PINID='B';
NODE_NAME     U6005 3
 '@T6G_MB_LIB.T6G(SCH_1):PAGE271_I28@PURE_QUANTA.ISL28022FRZT(CHIPS)':
 'EXT_CLK||INT': CDS_PINID='\ext_clk||int\';
NET_NAME
'HSC_VDD'
 '@T6G_MB_LIB.T6G(SCH_1):HSC_VDD':
 C_SIGNAL='@t6g_mb_lib.t6g(sch_1):hsc_vdd',
 CDS_GLOBAL_NET='TRUE';
NODE_NAME     PR3911 2
 '@T6G_MB_LIB.T6G(SCH_1):PAGE301_I5@PURE_QUANTA.Q_RES(CHIPS)':
 'B': CDS_PINID='B';
NODE_NAME     PR3910 2
 '@T6G_MB_LIB.T6G(SCH_1):PAGE301_I21@PURE_QUANTA.Q_RES(CHIPS)':
 'B': CDS_PINID='B';
NODE_NAME     PR3981 2
 '@T6G_MB_LIB.T6G(SCH_1):PAGE325_I6@PURE_QUANTA.Q_RES(CHIPS)':
 'B': CDS_PINID='B';
NODE_NAME     PR3980 2
 '@T6G_MB_LIB.T6G(SCH_1):PAGE325_I21@PURE_QUANTA.Q_RES(CHIPS)':
 'B': CDS_PINID='B';
NODE_NAME     PR2149 2
 '@T6G_MB_LIB.T6G(SCH_1):PAGE267_I39@PURE_QUANTA.Q_RES(CHIPS)':
 'B': CDS_PINID='B';
NODE_NAME     PR2106 1
 '@T6G_MB_LIB.T6G(SCH_1):PAGE267_I56@PURE_QUANTA.Q_RES(CHIPS)':
 'A': CDS_PINID='A';
NODE_NAME     R3936 1
 '@T6G_MB_LIB.T6G(SCH_1):PAGE267_I91@PURE_QUANTA.Q_RES(CHIPS)':
 'A': CDS_PINID='A';
NODE_NAME     R2587 2
 '@T6G_MB_LIB.T6G(SCH_1):PAGE267_I99@PURE_QUANTA.Q_RES(CHIPS)':
 'B': CDS_PINID='B';
NET_NAME
'HSC_VDD18'
 '@T6G_MB_LIB.T6G(SCH_1):HSC_VDD18':
 C_SIGNAL='@t6g_mb_lib.t6g(sch_1):hsc_vdd18';
NODE_NAME     PC2103 1
 '@T6G_MB_LIB.T6G(SCH_1):PAGE267_I50@PURE_QUANTA.Q_CAP(CHIPS)':
 'A': CDS_PINID='A';
NODE_NAME     PR3929 2
 '@T6G_MB_LIB.T6G(SCH_1):PAGE267_I53@PURE_QUANTA.Q_RES(CHIPS)':
 'B': CDS_PINID='B';
NODE_NAME     PU289 19
 '@T6G_MB_LIB.T6G(SCH_1):PAGE267_I58@PURE_QUANTA.MP5990GMA1111Z(CHIPS)':
 'VDD18': CDS_PINID='VDD18';
NET_NAME
'HSC_VDD_R'
 '@T6G_MB_LIB.T6G(SCH_1):HSC_VDD_R':
 C_SIGNAL='@t6g_mb_lib.t6g(sch_1):hsc_vdd_r';
NODE_NAME     PC2186 1
 '@T6G_MB_LIB.T6G(SCH_1):PAGE267_I27@PURE_QUANTA.Q_CAP(CHIPS)':
 'A': CDS_PINID='A';
NODE_NAME     PC2187 1
 '@T6G_MB_LIB.T6G(SCH_1):PAGE267_I30@PURE_QUANTA.Q_CAP(CHIPS)':
 'A': CDS_PINID='A';
NODE_NAME     PR2149 1
 '@T6G_MB_LIB.T6G(SCH_1):PAGE267_I39@PURE_QUANTA.Q_RES(CHIPS)':
 'A': CDS_PINID='A';
NODE_NAME     PU289 17
 '@T6G_MB_LIB.T6G(SCH_1):PAGE267_I58@PURE_QUANTA.MP5990GMA1111Z(CHIPS)':
 'VDD33_1': CDS_PINID='VDD33_1';
NODE_NAME     PU289 45
 '@T6G_MB_LIB.T6G(SCH_1):PAGE267_I58@PURE_QUANTA.MP5990GMA1111Z(CHIPS)':
 'VDD33_2': CDS_PINID='VDD33_2';
NET_NAME
'HSC_VDD_R_1'
 '@T6G_MB_LIB.T6G(SCH_1):HSC_VDD_R_1':
 C_SIGNAL='@t6g_mb_lib.t6g(sch_1):hsc_vdd_r_1';
NODE_NAME     PC1525 1
 '@T6G_MB_LIB.T6G(SCH_1):PAGE301_I20@PURE_QUANTA.Q_CAP(CHIPS)':
 'A': CDS_PINID='A';
NODE_NAME     PR3910 1
 '@T6G_MB_LIB.T6G(SCH_1):PAGE301_I21@PURE_QUANTA.Q_RES(CHIPS)':
 'A': CDS_PINID='A';
NODE_NAME     PU287 21
 '@T6G_MB_LIB.T6G(SCH_1):PAGE301_I35@PURE_QUANTA.MP5991GLUZ(CHIPS)':
 'VDD33': CDS_PINID='VDD33';
NET_NAME
'HSC_VDD_R_2'
 '@T6G_MB_LIB.T6G(SCH_1):HSC_VDD_R_2':
 C_SIGNAL='@t6g_mb_lib.t6g(sch_1):hsc_vdd_r_2';
NODE_NAME     PC2181 1
 '@T6G_MB_LIB.T6G(SCH_1):PAGE301_I4@PURE_QUANTA.Q_CAP(CHIPS)':
 'A': CDS_PINID='A';
NODE_NAME     PR3911 1
 '@T6G_MB_LIB.T6G(SCH_1):PAGE301_I5@PURE_QUANTA.Q_RES(CHIPS)':
 'A': CDS_PINID='A';
NODE_NAME     PU288 21
 '@T6G_MB_LIB.T6G(SCH_1):PAGE301_I16@PURE_QUANTA.MP5991GLUZ(CHIPS)':
 'VDD33': CDS_PINID='VDD33';
NET_NAME
'HSC_VDD_R_3'
 '@T6G_MB_LIB.T6G(SCH_1):HSC_VDD_R_3':
 C_SIGNAL='@t6g_mb_lib.t6g(sch_1):hsc_vdd_r_3';
NODE_NAME     PC3272 1
 '@T6G_MB_LIB.T6G(SCH_1):PAGE325_I20@PURE_QUANTA.Q_CAP(CHIPS)':
 'A': CDS_PINID='A';
NODE_NAME     PR3980 1
 '@T6G_MB_LIB.T6G(SCH_1):PAGE325_I21@PURE_QUANTA.Q_RES(CHIPS)':
 'A': CDS_PINID='A';
NODE_NAME     PU296 21
 '@T6G_MB_LIB.T6G(SCH_1):PAGE325_I35@PURE_QUANTA.MP5991GLUZ(CHIPS)':
 'VDD33': CDS_PINID='VDD33';
NET_NAME
'HSC_VDD_R_4'
 '@T6G_MB_LIB.T6G(SCH_1):HSC_VDD_R_4':
 C_SIGNAL='@t6g_mb_lib.t6g(sch_1):hsc_vdd_r_4';
NODE_NAME     PC2223 1
 '@T6G_MB_LIB.T6G(SCH_1):PAGE325_I4@PURE_QUANTA.Q_CAP(CHIPS)':
 'A': CDS_PINID='A';
NODE_NAME     PR3981 1
 '@T6G_MB_LIB.T6G(SCH_1):PAGE325_I6@PURE_QUANTA.Q_RES(CHIPS)':
 'A': CDS_PINID='A';
NODE_NAME     PU297 21
 '@T6G_MB_LIB.T6G(SCH_1):PAGE325_I17@PURE_QUANTA.MP5991GLUZ(CHIPS)':
 'VDD33': CDS_PINID='VDD33';
NET_NAME
'HSC_VIN_UVW_N'
 '@T6G_MB_LIB.T6G(SCH_1):HSC_VIN_UVW_N':
 C_SIGNAL='@t6g_mb_lib.t6g(sch_1):hsc_vin_uvw_n';
NODE_NAME     PR2106 2
 '@T6G_MB_LIB.T6G(SCH_1):PAGE267_I56@PURE_QUANTA.Q_RES(CHIPS)':
 'B': CDS_PINID='B';
NODE_NAME     PU289 14
 '@T6G_MB_LIB.T6G(SCH_1):PAGE267_I58@PURE_QUANTA.MP5990GMA1111Z(CHIPS)':
 'VIN_UVW#': CDS_PINID='\vin_uvw#\';
NET_NAME
'HSC_VOSEN'
 '@T6G_MB_LIB.T6G(SCH_1):HSC_VOSEN':
 C_SIGNAL='@t6g_mb_lib.t6g(sch_1):hsc_vosen';
NODE_NAME     PU289 24
 '@T6G_MB_LIB.T6G(SCH_1):PAGE267_I58@PURE_QUANTA.MP5990GMA1111Z(CHIPS)':
 'VOSEN': CDS_PINID='VOSEN';
NODE_NAME     PR3932 1
 '@T6G_MB_LIB.T6G(SCH_1):PAGE267_I70@PURE_QUANTA.Q_RES(CHIPS)':
 'A': CDS_PINID='A';
NODE_NAME     PR3931 2
 '@T6G_MB_LIB.T6G(SCH_1):PAGE267_I71@PURE_QUANTA.Q_RES(CHIPS)':
 'B': CDS_PINID='B';
NODE_NAME     PC2190 1
 '@T6G_MB_LIB.T6G(SCH_1):PAGE267_I72@PURE_QUANTA.Q_CAP(CHIPS)':
 'A': CDS_PINID='A';
NET_NAME
'HSC_VSENSE'
 '@T6G_MB_LIB.T6G(SCH_1):HSC_VSENSE':
 C_SIGNAL='@t6g_mb_lib.t6g(sch_1):hsc_vsense';
NODE_NAME     PR3927 1
 '@T6G_MB_LIB.T6G(SCH_1):PAGE267_I47@PURE_QUANTA.Q_RES(CHIPS)':
 'A': CDS_PINID='A';
NODE_NAME     PR3926 2
 '@T6G_MB_LIB.T6G(SCH_1):PAGE267_I48@PURE_QUANTA.Q_RES(CHIPS)':
 'B': CDS_PINID='B';
NODE_NAME     PU289 9
 '@T6G_MB_LIB.T6G(SCH_1):PAGE267_I58@PURE_QUANTA.MP5990GMA1111Z(CHIPS)':
 'VINSEN': CDS_PINID='VINSEN';
NODE_NAME     PC2189 1
 '@T6G_MB_LIB.T6G(SCH_1):PAGE267_I59@PURE_QUANTA.Q_CAP(CHIPS)':
 'A': CDS_PINID='A';
NET_NAME
'HSC_VTEMP'
 '@T6G_MB_LIB.T6G(SCH_1):HSC_VTEMP':
 C_SIGNAL='@t6g_mb_lib.t6g(sch_1):hsc_vtemp';
NODE_NAME     PU288 18
 '@T6G_MB_LIB.T6G(SCH_1):PAGE301_I16@PURE_QUANTA.MP5991GLUZ(CHIPS)':
 'VTEMP': CDS_PINID='VTEMP';
NODE_NAME     PU287 18
 '@T6G_MB_LIB.T6G(SCH_1):PAGE301_I35@PURE_QUANTA.MP5991GLUZ(CHIPS)':
 'VTEMP': CDS_PINID='VTEMP';
NODE_NAME     PU297 18
 '@T6G_MB_LIB.T6G(SCH_1):PAGE325_I17@PURE_QUANTA.MP5991GLUZ(CHIPS)':
 'VTEMP': CDS_PINID='VTEMP';
NODE_NAME     PU296 18
 '@T6G_MB_LIB.T6G(SCH_1):PAGE325_I35@PURE_QUANTA.MP5991GLUZ(CHIPS)':
 'VTEMP': CDS_PINID='VTEMP';
NODE_NAME     PU289 15
 '@T6G_MB_LIB.T6G(SCH_1):PAGE267_I58@PURE_QUANTA.MP5990GMA1111Z(CHIPS)':
 'VTEMP': CDS_PINID='VTEMP';
NODE_NAME     PC2192 1
 '@T6G_MB_LIB.T6G(SCH_1):PAGE267_I78@PURE_QUANTA.Q_CAP(CHIPS)':
 'A': CDS_PINID='A';
NODE_NAME     PR3935 1
 '@T6G_MB_LIB.T6G(SCH_1):PAGE267_I81@PURE_QUANTA.Q_RES(CHIPS)':
 'A': CDS_PINID='A';
NET_NAME
'I3C_0_SPD_DDRAF_CPU0_R_SCL'
 '@T6G_MB_LIB.T6G(SCH_1):I3C_0_SPD_DDRAF_CPU0_R_SCL':
 C_SIGNAL='@t6g_mb_lib.t6g(sch_1):i3c_0_spd_ddraf_cpu0_r_scl';
NODE_NAME     R426 2
 '@T6G_MB_LIB.T6G(SCH_1):PAGE136_I99@PURE_QUANTA.Q_RES(CHIPS)':
 'B': CDS_PINID='B';
NODE_NAME     R2310 1
 '@T6G_MB_LIB.T6G(SCH_1):PAGE136_I123@PURE_QUANTA.Q_RES(CHIPS)':
 'A': CDS_PINID='A';
NODE_NAME     R425 2
 '@T6G_MB_LIB.T6G(SCH_1):PAGE28_I25@PURE_QUANTA.Q_RES(CHIPS)':
 'B': CDS_PINID='B';
NODE_NAME     U25 A71
 '@T6G_MB_LIB.T6G(SCH_1):PAGE28_I188@PURE_QUANTA.GENOA_SP5(CHIPS)':
 'I3C0_SCL||I2C0_SCL||SPD0_SCL||SMBUS0_SCL||AGPIO145': CDS_PINID='\i3c0_scl||i2c0_scl||spd0_scl||smbus0_scl||agpio145\';
NET_NAME
'I3C_0_SPD_DDRAF_CPU0_R_SDA'
 '@T6G_MB_LIB.T6G(SCH_1):I3C_0_SPD_DDRAF_CPU0_R_SDA':
 C_SIGNAL='@t6g_mb_lib.t6g(sch_1):i3c_0_spd_ddraf_cpu0_r_sda';
NODE_NAME     R427 2
 '@T6G_MB_LIB.T6G(SCH_1):PAGE136_I100@PURE_QUANTA.Q_RES(CHIPS)':
 'B': CDS_PINID='B';
NODE_NAME     R2311 1
 '@T6G_MB_LIB.T6G(SCH_1):PAGE136_I124@PURE_QUANTA.Q_RES(CHIPS)':
 'A': CDS_PINID='A';
NODE_NAME     R423 2
 '@T6G_MB_LIB.T6G(SCH_1):PAGE28_I24@PURE_QUANTA.Q_RES(CHIPS)':
 'B': CDS_PINID='B';
NODE_NAME     U25 B71
 '@T6G_MB_LIB.T6G(SCH_1):PAGE28_I188@PURE_QUANTA.GENOA_SP5(CHIPS)':
 'I3C0_SDA||I2C0_SDA||SPD0_SDA||SMBUS0_SDA||AGPIO146': CDS_PINID='\i3c0_sda||i2c0_sda||spd0_sda||smbus0_sda||agpio146\';
NET_NAME
'I3C_0_SPD_DDRAF_CPU0_SCL'
 '@T6G_MB_LIB.T6G(SCH_1):I3C_0_SPD_DDRAF_CPU0_SCL':
 C_SIGNAL='@t6g_mb_lib.t6g(sch_1):i3c_0_spd_ddraf_cpu0_scl';
NODE_NAME     U105 1
 '@T6G_MB_LIB.T6G(SCH_1):PAGE136_I47@PURE_QUANTA.PI3CSW12ZUAEX(CHIPS)':
 '1D+': CDS_PINID='\1d+\';
NODE_NAME     R426 1
 '@T6G_MB_LIB.T6G(SCH_1):PAGE136_I99@PURE_QUANTA.Q_RES(CHIPS)':
 'A': CDS_PINID='A';
NET_NAME
'I3C_0_SPD_DDRAF_CPU0_SDA'
 '@T6G_MB_LIB.T6G(SCH_1):I3C_0_SPD_DDRAF_CPU0_SDA':
 C_SIGNAL='@t6g_mb_lib.t6g(sch_1):i3c_0_spd_ddraf_cpu0_sda';
NODE_NAME     U105 2
 '@T6G_MB_LIB.T6G(SCH_1):PAGE136_I47@PURE_QUANTA.PI3CSW12ZUAEX(CHIPS)':
 '1D-': CDS_PINID='\1d-\';
NODE_NAME     R427 1
 '@T6G_MB_LIB.T6G(SCH_1):PAGE136_I100@PURE_QUANTA.Q_RES(CHIPS)':
 'A': CDS_PINID='A';
NET_NAME
'I3C_0_SPD_DDRAF_CPU1_R_SCL'
 '@T6G_MB_LIB.T6G(SCH_1):I3C_0_SPD_DDRAF_CPU1_R_SCL':
 C_SIGNAL='@t6g_mb_lib.t6g(sch_1):i3c_0_spd_ddraf_cpu1_r_scl';
NODE_NAME     U26 A71
 '@T6G_MB_LIB.T6G(SCH_1):PAGE55_I182@PURE_QUANTA.GENOA_SP5(CHIPS)':
 'I3C0_SCL||I2C0_SCL||SPD0_SCL||SMBUS0_SCL||AGPIO145': CDS_PINID='\i3c0_scl||i2c0_scl||spd0_scl||smbus0_scl||agpio145\';
NODE_NAME     R564 2
 '@T6G_MB_LIB.T6G(SCH_1):PAGE136_I108@PURE_QUANTA.Q_RES(CHIPS)':
 'B': CDS_PINID='B';
NODE_NAME     R988 1
 '@T6G_MB_LIB.T6G(SCH_1):PAGE136_I138@PURE_QUANTA.Q_RES(CHIPS)':
 'A': CDS_PINID='A';
NODE_NAME     R563 2
 '@T6G_MB_LIB.T6G(SCH_1):PAGE55_I368@PURE_QUANTA.Q_RES(CHIPS)':
 'B': CDS_PINID='B';
NET_NAME
'I3C_0_SPD_DDRAF_CPU1_R_SDA'
 '@T6G_MB_LIB.T6G(SCH_1):I3C_0_SPD_DDRAF_CPU1_R_SDA':
 C_SIGNAL='@t6g_mb_lib.t6g(sch_1):i3c_0_spd_ddraf_cpu1_r_sda';
NODE_NAME     U26 B71
 '@T6G_MB_LIB.T6G(SCH_1):PAGE55_I182@PURE_QUANTA.GENOA_SP5(CHIPS)':
 'I3C0_SDA||I2C0_SDA||SPD0_SDA||SMBUS0_SDA||AGPIO146': CDS_PINID='\i3c0_sda||i2c0_sda||spd0_sda||smbus0_sda||agpio146\';
NODE_NAME     R565 2
 '@T6G_MB_LIB.T6G(SCH_1):PAGE136_I107@PURE_QUANTA.Q_RES(CHIPS)':
 'B': CDS_PINID='B';
NODE_NAME     R989 1
 '@T6G_MB_LIB.T6G(SCH_1):PAGE136_I137@PURE_QUANTA.Q_RES(CHIPS)':
 'A': CDS_PINID='A';
NODE_NAME     R543 2
 '@T6G_MB_LIB.T6G(SCH_1):PAGE55_I367@PURE_QUANTA.Q_RES(CHIPS)':
 'B': CDS_PINID='B';
NET_NAME
'I3C_0_SPD_DDRAF_CPU1_SCL'
 '@T6G_MB_LIB.T6G(SCH_1):I3C_0_SPD_DDRAF_CPU1_SCL':
 C_SIGNAL='@t6g_mb_lib.t6g(sch_1):i3c_0_spd_ddraf_cpu1_scl';
NODE_NAME     U107 1
 '@T6G_MB_LIB.T6G(SCH_1):PAGE136_I63@PURE_QUANTA.PI3CSW12ZUAEX(CHIPS)':
 '1D+': CDS_PINID='\1d+\';
NODE_NAME     R564 1
 '@T6G_MB_LIB.T6G(SCH_1):PAGE136_I108@PURE_QUANTA.Q_RES(CHIPS)':
 'A': CDS_PINID='A';
NET_NAME
'I3C_0_SPD_DDRAF_CPU1_SDA'
 '@T6G_MB_LIB.T6G(SCH_1):I3C_0_SPD_DDRAF_CPU1_SDA':
 C_SIGNAL='@t6g_mb_lib.t6g(sch_1):i3c_0_spd_ddraf_cpu1_sda';
NODE_NAME     U107 2
 '@T6G_MB_LIB.T6G(SCH_1):PAGE136_I63@PURE_QUANTA.PI3CSW12ZUAEX(CHIPS)':
 '1D-': CDS_PINID='\1d-\';
NODE_NAME     R565 1
 '@T6G_MB_LIB.T6G(SCH_1):PAGE136_I107@PURE_QUANTA.Q_RES(CHIPS)':
 'A': CDS_PINID='A';
NET_NAME
'I3C_1_SPD_DDRGL_CPU0_R_SCL'
 '@T6G_MB_LIB.T6G(SCH_1):I3C_1_SPD_DDRGL_CPU0_R_SCL':
 C_SIGNAL='@t6g_mb_lib.t6g(sch_1):i3c_1_spd_ddrgl_cpu0_r_scl';
NODE_NAME     R428 2
 '@T6G_MB_LIB.T6G(SCH_1):PAGE136_I103@PURE_QUANTA.Q_RES(CHIPS)':
 'B': CDS_PINID='B';
NODE_NAME     R986 1
 '@T6G_MB_LIB.T6G(SCH_1):PAGE136_I135@PURE_QUANTA.Q_RES(CHIPS)':
 'A': CDS_PINID='A';
NODE_NAME     R421 2
 '@T6G_MB_LIB.T6G(SCH_1):PAGE28_I23@PURE_QUANTA.Q_RES(CHIPS)':
 'B': CDS_PINID='B';
NODE_NAME     U25 C7
 '@T6G_MB_LIB.T6G(SCH_1):PAGE28_I188@PURE_QUANTA.GENOA_SP5(CHIPS)':
 'I3C1_SCL||I2C1_SCL||SPD1_SCL||AGPIO147': CDS_PINID='\i3c1_scl||i2c1_scl||spd1_scl||agpio147\';
NET_NAME
'I3C_1_SPD_DDRGL_CPU0_R_SDA'
 '@T6G_MB_LIB.T6G(SCH_1):I3C_1_SPD_DDRGL_CPU0_R_SDA':
 C_SIGNAL='@t6g_mb_lib.t6g(sch_1):i3c_1_spd_ddrgl_cpu0_r_sda';
NODE_NAME     R429 2
 '@T6G_MB_LIB.T6G(SCH_1):PAGE136_I104@PURE_QUANTA.Q_RES(CHIPS)':
 'B': CDS_PINID='B';
NODE_NAME     R987 1
 '@T6G_MB_LIB.T6G(SCH_1):PAGE136_I136@PURE_QUANTA.Q_RES(CHIPS)':
 'A': CDS_PINID='A';
NODE_NAME     R420 2
 '@T6G_MB_LIB.T6G(SCH_1):PAGE28_I22@PURE_QUANTA.Q_RES(CHIPS)':
 'B': CDS_PINID='B';
NODE_NAME     U25 A5
 '@T6G_MB_LIB.T6G(SCH_1):PAGE28_I188@PURE_QUANTA.GENOA_SP5(CHIPS)':
 'I3C1_SDA||I2C1_SDA||SPD1_SDA||AGPIO148': CDS_PINID='\i3c1_sda||i2c1_sda||spd1_sda||agpio148\';
NET_NAME
'I3C_1_SPD_DDRGL_CPU0_SCL'
 '@T6G_MB_LIB.T6G(SCH_1):I3C_1_SPD_DDRGL_CPU0_SCL':
 C_SIGNAL='@t6g_mb_lib.t6g(sch_1):i3c_1_spd_ddrgl_cpu0_scl';
NODE_NAME     U106 1
 '@T6G_MB_LIB.T6G(SCH_1):PAGE136_I54@PURE_QUANTA.PI3CSW12ZUAEX(CHIPS)':
 '1D+': CDS_PINID='\1d+\';
NODE_NAME     R428 1
 '@T6G_MB_LIB.T6G(SCH_1):PAGE136_I103@PURE_QUANTA.Q_RES(CHIPS)':
 'A': CDS_PINID='A';
NET_NAME
'I3C_1_SPD_DDRGL_CPU0_SDA'
 '@T6G_MB_LIB.T6G(SCH_1):I3C_1_SPD_DDRGL_CPU0_SDA':
 C_SIGNAL='@t6g_mb_lib.t6g(sch_1):i3c_1_spd_ddrgl_cpu0_sda';
NODE_NAME     U106 2
 '@T6G_MB_LIB.T6G(SCH_1):PAGE136_I54@PURE_QUANTA.PI3CSW12ZUAEX(CHIPS)':
 '1D-': CDS_PINID='\1d-\';
NODE_NAME     R429 1
 '@T6G_MB_LIB.T6G(SCH_1):PAGE136_I104@PURE_QUANTA.Q_RES(CHIPS)':
 'A': CDS_PINID='A';
NET_NAME
'I3C_1_SPD_DDRGL_CPU1_R_SCL'
 '@T6G_MB_LIB.T6G(SCH_1):I3C_1_SPD_DDRGL_CPU1_R_SCL':
 C_SIGNAL='@t6g_mb_lib.t6g(sch_1):i3c_1_spd_ddrgl_cpu1_r_scl';
NODE_NAME     U26 C7
 '@T6G_MB_LIB.T6G(SCH_1):PAGE55_I182@PURE_QUANTA.GENOA_SP5(CHIPS)':
 'I3C1_SCL||I2C1_SCL||SPD1_SCL||AGPIO147': CDS_PINID='\i3c1_scl||i2c1_scl||spd1_scl||agpio147\';
NODE_NAME     R566 2
 '@T6G_MB_LIB.T6G(SCH_1):PAGE136_I111@PURE_QUANTA.Q_RES(CHIPS)':
 'B': CDS_PINID='B';
NODE_NAME     R990 1
 '@T6G_MB_LIB.T6G(SCH_1):PAGE136_I142@PURE_QUANTA.Q_RES(CHIPS)':
 'A': CDS_PINID='A';
NODE_NAME     R542 2
 '@T6G_MB_LIB.T6G(SCH_1):PAGE55_I366@PURE_QUANTA.Q_RES(CHIPS)':
 'B': CDS_PINID='B';
NET_NAME
'I3C_1_SPD_DDRGL_CPU1_R_SDA'
 '@T6G_MB_LIB.T6G(SCH_1):I3C_1_SPD_DDRGL_CPU1_R_SDA':
 C_SIGNAL='@t6g_mb_lib.t6g(sch_1):i3c_1_spd_ddrgl_cpu1_r_sda';
NODE_NAME     U26 A5
 '@T6G_MB_LIB.T6G(SCH_1):PAGE55_I182@PURE_QUANTA.GENOA_SP5(CHIPS)':
 'I3C1_SDA||I2C1_SDA||SPD1_SDA||AGPIO148': CDS_PINID='\i3c1_sda||i2c1_sda||spd1_sda||agpio148\';
NODE_NAME     R567 2
 '@T6G_MB_LIB.T6G(SCH_1):PAGE136_I112@PURE_QUANTA.Q_RES(CHIPS)':
 'B': CDS_PINID='B';
NODE_NAME     R991 1
 '@T6G_MB_LIB.T6G(SCH_1):PAGE136_I141@PURE_QUANTA.Q_RES(CHIPS)':
 'A': CDS_PINID='A';
NODE_NAME     R541 2
 '@T6G_MB_LIB.T6G(SCH_1):PAGE55_I365@PURE_QUANTA.Q_RES(CHIPS)':
 'B': CDS_PINID='B';
NET_NAME
'I3C_1_SPD_DDRGL_CPU1_SCL'
 '@T6G_MB_LIB.T6G(SCH_1):I3C_1_SPD_DDRGL_CPU1_SCL':
 C_SIGNAL='@t6g_mb_lib.t6g(sch_1):i3c_1_spd_ddrgl_cpu1_scl';
NODE_NAME     U108 1
 '@T6G_MB_LIB.T6G(SCH_1):PAGE136_I68@PURE_QUANTA.PI3CSW12ZUAEX(CHIPS)':
 '1D+': CDS_PINID='\1d+\';
NODE_NAME     R566 1
 '@T6G_MB_LIB.T6G(SCH_1):PAGE136_I111@PURE_QUANTA.Q_RES(CHIPS)':
 'A': CDS_PINID='A';
NET_NAME
'I3C_1_SPD_DDRGL_CPU1_SDA'
 '@T6G_MB_LIB.T6G(SCH_1):I3C_1_SPD_DDRGL_CPU1_SDA':
 C_SIGNAL='@t6g_mb_lib.t6g(sch_1):i3c_1_spd_ddrgl_cpu1_sda';
NODE_NAME     U108 2
 '@T6G_MB_LIB.T6G(SCH_1):PAGE136_I68@PURE_QUANTA.PI3CSW12ZUAEX(CHIPS)':
 '1D-': CDS_PINID='\1d-\';
NODE_NAME     R567 1
 '@T6G_MB_LIB.T6G(SCH_1):PAGE136_I112@PURE_QUANTA.Q_RES(CHIPS)':
 'A': CDS_PINID='A';
NET_NAME
'I3C_BMC_SWB_BUF_R_SCL'
 '@T6G_MB_LIB.T6G(SCH_1):I3C_BMC_SWB_BUF_R_SCL':
 C_SIGNAL='@t6g_mb_lib.t6g(sch_1):i3c_bmc_swb_buf_r_scl';
NODE_NAME     R2725 2
 '@T6G_MB_LIB.T6G(SCH_1):PAGE249_I28@PURE_QUANTA.Q_RES(CHIPS)':
 'B': CDS_PINID='B';
NODE_NAME     U176 2
 '@T6G_MB_LIB.T6G(SCH_1):PAGE249_I30@PURE_QUANTA.LTC4307CMS8(CHIPS)':
 'SCL_OUT': CDS_PINID='SCL_OUT';
NODE_NAME     R2670 2
 '@T6G_MB_LIB.T6G(SCH_1):PAGE249_I63@PURE_QUANTA.Q_RES(CHIPS)':
 'B': CDS_PINID='B';
NODE_NAME     R2675 1
 '@T6G_MB_LIB.T6G(SCH_1):PAGE249_I69@PURE_QUANTA.Q_RES(CHIPS)':
 'A': CDS_PINID='A';
NET_NAME
'I3C_BMC_SWB_BUF_R_SDA'
 '@T6G_MB_LIB.T6G(SCH_1):I3C_BMC_SWB_BUF_R_SDA':
 C_SIGNAL='@t6g_mb_lib.t6g(sch_1):i3c_bmc_swb_buf_r_sda';
NODE_NAME     R2706 2
 '@T6G_MB_LIB.T6G(SCH_1):PAGE249_I27@PURE_QUANTA.Q_RES(CHIPS)':
 'B': CDS_PINID='B';
NODE_NAME     U176 7
 '@T6G_MB_LIB.T6G(SCH_1):PAGE249_I30@PURE_QUANTA.LTC4307CMS8(CHIPS)':
 'SDA_OUT': CDS_PINID='SDA_OUT';
NODE_NAME     R2668 2
 '@T6G_MB_LIB.T6G(SCH_1):PAGE249_I62@PURE_QUANTA.Q_RES(CHIPS)':
 'B': CDS_PINID='B';
NODE_NAME     R2674 1
 '@T6G_MB_LIB.T6G(SCH_1):PAGE249_I86@PURE_QUANTA.Q_RES(CHIPS)':
 'A': CDS_PINID='A';
NET_NAME
'I3C_BMC_SWB_BUF_SCL'
 '@T6G_MB_LIB.T6G(SCH_1):I3C_BMC_SWB_BUF_SCL':
 C_SIGNAL='@t6g_mb_lib.t6g(sch_1):i3c_bmc_swb_buf_scl';
NODE_NAME     R2675 2
 '@T6G_MB_LIB.T6G(SCH_1):PAGE249_I69@PURE_QUANTA.Q_RES(CHIPS)':
 'B': CDS_PINID='B';
NODE_NAME     J106 N4
 '@T6G_MB_LIB.T6G(SCH_1):PAGE327_I74@PURE_QUANTA.CONN112_10137002101LF(CHIPS)':
 'N4': CDS_PINID='N4';
NET_NAME
'I3C_BMC_SWB_BUF_SDA'
 '@T6G_MB_LIB.T6G(SCH_1):I3C_BMC_SWB_BUF_SDA':
 C_SIGNAL='@t6g_mb_lib.t6g(sch_1):i3c_bmc_swb_buf_sda';
NODE_NAME     J106 N2
 '@T6G_MB_LIB.T6G(SCH_1):PAGE327_I74@PURE_QUANTA.CONN112_10137002101LF(CHIPS)':
 'N2': CDS_PINID='N2';
NODE_NAME     R2674 2
 '@T6G_MB_LIB.T6G(SCH_1):PAGE249_I86@PURE_QUANTA.Q_RES(CHIPS)':
 'B': CDS_PINID='B';
NET_NAME
'I3C_BMC_SWB_R_SCL'
 '@T6G_MB_LIB.T6G(SCH_1):I3C_BMC_SWB_R_SCL':
 C_SIGNAL='@t6g_mb_lib.t6g(sch_1):i3c_bmc_swb_r_scl';
NODE_NAME     R3112 2
 '@T6G_MB_LIB.T6G(SCH_1):PAGE249_I25@PURE_QUANTA.Q_RES(CHIPS)':
 'B': CDS_PINID='B';
NODE_NAME     R2725 1
 '@T6G_MB_LIB.T6G(SCH_1):PAGE249_I28@PURE_QUANTA.Q_RES(CHIPS)':
 'A': CDS_PINID='A';
NODE_NAME     U176 3
 '@T6G_MB_LIB.T6G(SCH_1):PAGE249_I30@PURE_QUANTA.LTC4307CMS8(CHIPS)':
 'SCL_IN': CDS_PINID='SCL_IN';
NET_NAME
'I3C_BMC_SWB_R_SDA'
 '@T6G_MB_LIB.T6G(SCH_1):I3C_BMC_SWB_R_SDA':
 C_SIGNAL='@t6g_mb_lib.t6g(sch_1):i3c_bmc_swb_r_sda';
NODE_NAME     R2706 1
 '@T6G_MB_LIB.T6G(SCH_1):PAGE249_I27@PURE_QUANTA.Q_RES(CHIPS)':
 'A': CDS_PINID='A';
NODE_NAME     U176 6
 '@T6G_MB_LIB.T6G(SCH_1):PAGE249_I30@PURE_QUANTA.LTC4307CMS8(CHIPS)':
 'SDA_IN': CDS_PINID='SDA_IN';
NODE_NAME     R3111 2
 '@T6G_MB_LIB.T6G(SCH_1):PAGE249_I85@PURE_QUANTA.Q_RES(CHIPS)':
 'B': CDS_PINID='B';
NET_NAME
'I3C_BMC_SWB_SCL'
 '@T6G_MB_LIB.T6G(SCH_1):I3C_BMC_SWB_SCL':
 C_SIGNAL='@t6g_mb_lib.t6g(sch_1):i3c_bmc_swb_scl';
NODE_NAME     J41 A9
 '@T6G_MB_LIB.T6G(SCH_1):PAGE348_I176@PURE_QUANTA.SCONN168_ME1016810202011(CHIPS)':
 'SMRST#': CDS_PINID='\smrst#\';
NODE_NAME     R332 1
 '@T6G_MB_LIB.T6G(SCH_1):PAGE349_I128@PURE_QUANTA.Q_RES(CHIPS)':
 'A': CDS_PINID='A';
NODE_NAME     R3112 1
 '@T6G_MB_LIB.T6G(SCH_1):PAGE249_I25@PURE_QUANTA.Q_RES(CHIPS)':
 'A': CDS_PINID='A';
NET_NAME
'I3C_BMC_SWB_SDA'
 '@T6G_MB_LIB.T6G(SCH_1):I3C_BMC_SWB_SDA':
 C_SIGNAL='@t6g_mb_lib.t6g(sch_1):i3c_bmc_swb_sda';
NODE_NAME     J41 A10
 '@T6G_MB_LIB.T6G(SCH_1):PAGE348_I176@PURE_QUANTA.SCONN168_ME1016810202011(CHIPS)':
 'PRSNTA#': CDS_PINID='\prsnta#\';
NODE_NAME     R1460 1
 '@T6G_MB_LIB.T6G(SCH_1):PAGE349_I127@PURE_QUANTA.Q_RES(CHIPS)':
 'A': CDS_PINID='A';
NODE_NAME     R3111 1
 '@T6G_MB_LIB.T6G(SCH_1):PAGE249_I85@PURE_QUANTA.Q_RES(CHIPS)':
 'A': CDS_PINID='A';
NET_NAME
'I3C_MUX_CPU0_VIO'
 '@T6G_MB_LIB.T6G(SCH_1):I3C_MUX_CPU0_VIO':
 C_SIGNAL='@t6g_mb_lib.t6g(sch_1):i3c_mux_cpu0_vio';
NODE_NAME     R139 1
 '@T6G_MB_LIB.T6G(SCH_1):PAGE138_I30@PURE_QUANTA.Q_RES(CHIPS)':
 'A': CDS_PINID='A';
NODE_NAME     U213 7
 '@T6G_MB_LIB.T6G(SCH_1):PAGE138_I111@PURE_QUANTA.IML3112Y2B000NCG8(CHIPS)':
 'VIO': CDS_PINID='VIO';
NODE_NAME     C9 1
 '@T6G_MB_LIB.T6G(SCH_1):PAGE138_I113@PURE_QUANTA.Q_CAP(CHIPS)':
 'A': CDS_PINID='A';
NET_NAME
'I3C_SCM_0_R_SCL'
 '@T6G_MB_LIB.T6G(SCH_1):I3C_SCM_0_R_SCL':
 C_SIGNAL='@t6g_mb_lib.t6g(sch_1):i3c_scm_0_r_scl';
NODE_NAME     U105 3
 '@T6G_MB_LIB.T6G(SCH_1):PAGE136_I47@PURE_QUANTA.PI3CSW12ZUAEX(CHIPS)':
 '2D+': CDS_PINID='\2d+\';
NODE_NAME     R5014 2
 '@T6G_MB_LIB.T6G(SCH_1):PAGE136_I159@PURE_QUANTA.Q_RES(CHIPS)':
 'B': CDS_PINID='B';
NODE_NAME     R6000 2
 '@T6G_MB_LIB.T6G(SCH_1):PAGE348_I123@PURE_QUANTA.Q_RES(CHIPS)':
 'B': CDS_PINID='B';
NET_NAME
'I3C_SCM_0_R_SDA'
 '@T6G_MB_LIB.T6G(SCH_1):I3C_SCM_0_R_SDA':
 C_SIGNAL='@t6g_mb_lib.t6g(sch_1):i3c_scm_0_r_sda';
NODE_NAME     U105 4
 '@T6G_MB_LIB.T6G(SCH_1):PAGE136_I47@PURE_QUANTA.PI3CSW12ZUAEX(CHIPS)':
 '2D-': CDS_PINID='\2d-\';
NODE_NAME     R5015 2
 '@T6G_MB_LIB.T6G(SCH_1):PAGE136_I157@PURE_QUANTA.Q_RES(CHIPS)':
 'B': CDS_PINID='B';
NODE_NAME     R6001 2
 '@T6G_MB_LIB.T6G(SCH_1):PAGE348_I124@PURE_QUANTA.Q_RES(CHIPS)':
 'B': CDS_PINID='B';
NET_NAME
'I3C_SCM_0_SCL'
 '@T6G_MB_LIB.T6G(SCH_1):I3C_SCM_0_SCL':
 C_SIGNAL='@t6g_mb_lib.t6g(sch_1):i3c_scm_0_scl';
NODE_NAME     J41 OA5
 '@T6G_MB_LIB.T6G(SCH_1):PAGE348_I176@PURE_QUANTA.SCONN168_ME1016810202011(CHIPS)':
 'RBT_ARB_OUT': CDS_PINID='RBT_ARB_OUT';
NODE_NAME     R6000 1
 '@T6G_MB_LIB.T6G(SCH_1):PAGE348_I123@PURE_QUANTA.Q_RES(CHIPS)':
 'A': CDS_PINID='A';
NET_NAME
'I3C_SCM_0_SDA'
 '@T6G_MB_LIB.T6G(SCH_1):I3C_SCM_0_SDA':
 C_SIGNAL='@t6g_mb_lib.t6g(sch_1):i3c_scm_0_sda';
NODE_NAME     R6001 1
 '@T6G_MB_LIB.T6G(SCH_1):PAGE348_I124@PURE_QUANTA.Q_RES(CHIPS)':
 'A': CDS_PINID='A';
NODE_NAME     J41 OA6
 '@T6G_MB_LIB.T6G(SCH_1):PAGE348_I176@PURE_QUANTA.SCONN168_ME1016810202011(CHIPS)':
 'SLOT_ID1': CDS_PINID='SLOT_ID1';
NET_NAME
'I3C_SCM_1_R_SCL'
 '@T6G_MB_LIB.T6G(SCH_1):I3C_SCM_1_R_SCL':
 C_SIGNAL='@t6g_mb_lib.t6g(sch_1):i3c_scm_1_r_scl';
NODE_NAME     U106 3
 '@T6G_MB_LIB.T6G(SCH_1):PAGE136_I54@PURE_QUANTA.PI3CSW12ZUAEX(CHIPS)':
 '2D+': CDS_PINID='\2d+\';
NODE_NAME     R5016 2
 '@T6G_MB_LIB.T6G(SCH_1):PAGE136_I162@PURE_QUANTA.Q_RES(CHIPS)':
 'B': CDS_PINID='B';
NODE_NAME     R6002 2
 '@T6G_MB_LIB.T6G(SCH_1):PAGE348_I122@PURE_QUANTA.Q_RES(CHIPS)':
 'B': CDS_PINID='B';
NET_NAME
'I3C_SCM_1_R_SDA'
 '@T6G_MB_LIB.T6G(SCH_1):I3C_SCM_1_R_SDA':
 C_SIGNAL='@t6g_mb_lib.t6g(sch_1):i3c_scm_1_r_sda';
NODE_NAME     U106 4
 '@T6G_MB_LIB.T6G(SCH_1):PAGE136_I54@PURE_QUANTA.PI3CSW12ZUAEX(CHIPS)':
 '2D-': CDS_PINID='\2d-\';
NODE_NAME     R5017 2
 '@T6G_MB_LIB.T6G(SCH_1):PAGE136_I161@PURE_QUANTA.Q_RES(CHIPS)':
 'B': CDS_PINID='B';
NODE_NAME     R6003 2
 '@T6G_MB_LIB.T6G(SCH_1):PAGE348_I121@PURE_QUANTA.Q_RES(CHIPS)':
 'B': CDS_PINID='B';
NET_NAME
'I3C_SCM_1_SCL'
 '@T6G_MB_LIB.T6G(SCH_1):I3C_SCM_1_SCL':
 C_SIGNAL='@t6g_mb_lib.t6g(sch_1):i3c_scm_1_scl';
NODE_NAME     R6002 1
 '@T6G_MB_LIB.T6G(SCH_1):PAGE348_I122@PURE_QUANTA.Q_RES(CHIPS)':
 'A': CDS_PINID='A';
NODE_NAME     J41 OA7
 '@T6G_MB_LIB.T6G(SCH_1):PAGE348_I176@PURE_QUANTA.SCONN168_ME1016810202011(CHIPS)':
 'RBT_TX_EN': CDS_PINID='RBT_TX_EN';
NET_NAME
'I3C_SCM_1_SDA'
 '@T6G_MB_LIB.T6G(SCH_1):I3C_SCM_1_SDA':
 C_SIGNAL='@t6g_mb_lib.t6g(sch_1):i3c_scm_1_sda';
NODE_NAME     R6003 1
 '@T6G_MB_LIB.T6G(SCH_1):PAGE348_I121@PURE_QUANTA.Q_RES(CHIPS)':
 'A': CDS_PINID='A';
NODE_NAME     J41 OA8
 '@T6G_MB_LIB.T6G(SCH_1):PAGE348_I176@PURE_QUANTA.SCONN168_ME1016810202011(CHIPS)':
 'RBT_TXD1': CDS_PINID='RBT_TXD1';
NET_NAME
'I3C_SCM_2_R_SCL'
 '@T6G_MB_LIB.T6G(SCH_1):I3C_SCM_2_R_SCL':
 C_SIGNAL='@t6g_mb_lib.t6g(sch_1):i3c_scm_2_r_scl';
NODE_NAME     U107 3
 '@T6G_MB_LIB.T6G(SCH_1):PAGE136_I63@PURE_QUANTA.PI3CSW12ZUAEX(CHIPS)':
 '2D+': CDS_PINID='\2d+\';
NODE_NAME     R5018 2
 '@T6G_MB_LIB.T6G(SCH_1):PAGE136_I163@PURE_QUANTA.Q_RES(CHIPS)':
 'B': CDS_PINID='B';
NODE_NAME     R6004 2
 '@T6G_MB_LIB.T6G(SCH_1):PAGE348_I120@PURE_QUANTA.Q_RES(CHIPS)':
 'B': CDS_PINID='B';
NET_NAME
'I3C_SCM_2_R_SDA'
 '@T6G_MB_LIB.T6G(SCH_1):I3C_SCM_2_R_SDA':
 C_SIGNAL='@t6g_mb_lib.t6g(sch_1):i3c_scm_2_r_sda';
NODE_NAME     U107 4
 '@T6G_MB_LIB.T6G(SCH_1):PAGE136_I63@PURE_QUANTA.PI3CSW12ZUAEX(CHIPS)':
 '2D-': CDS_PINID='\2d-\';
NODE_NAME     R5019 2
 '@T6G_MB_LIB.T6G(SCH_1):PAGE136_I164@PURE_QUANTA.Q_RES(CHIPS)':
 'B': CDS_PINID='B';
NODE_NAME     R6005 2
 '@T6G_MB_LIB.T6G(SCH_1):PAGE348_I118@PURE_QUANTA.Q_RES(CHIPS)':
 'B': CDS_PINID='B';
NET_NAME
'I3C_SCM_2_SCL'
 '@T6G_MB_LIB.T6G(SCH_1):I3C_SCM_2_SCL':
 C_SIGNAL='@t6g_mb_lib.t6g(sch_1):i3c_scm_2_scl';
NODE_NAME     R6004 1
 '@T6G_MB_LIB.T6G(SCH_1):PAGE348_I120@PURE_QUANTA.Q_RES(CHIPS)':
 'A': CDS_PINID='A';
NODE_NAME     J41 OA9
 '@T6G_MB_LIB.T6G(SCH_1):PAGE348_I176@PURE_QUANTA.SCONN168_ME1016810202011(CHIPS)':
 'RBT_TXD0': CDS_PINID='RBT_TXD0';
NET_NAME
'I3C_SCM_2_SDA'
 '@T6G_MB_LIB.T6G(SCH_1):I3C_SCM_2_SDA':
 C_SIGNAL='@t6g_mb_lib.t6g(sch_1):i3c_scm_2_sda';
NODE_NAME     R6005 1
 '@T6G_MB_LIB.T6G(SCH_1):PAGE348_I118@PURE_QUANTA.Q_RES(CHIPS)':
 'A': CDS_PINID='A';
NODE_NAME     J41 OA10
 '@T6G_MB_LIB.T6G(SCH_1):PAGE348_I176@PURE_QUANTA.SCONN168_ME1016810202011(CHIPS)':
 'GND_OA10': CDS_PINID='GND_OA10';
NET_NAME
'I3C_SCM_3_R_SCL'
 '@T6G_MB_LIB.T6G(SCH_1):I3C_SCM_3_R_SCL':
 C_SIGNAL='@t6g_mb_lib.t6g(sch_1):i3c_scm_3_r_scl';
NODE_NAME     U108 3
 '@T6G_MB_LIB.T6G(SCH_1):PAGE136_I68@PURE_QUANTA.PI3CSW12ZUAEX(CHIPS)':
 '2D+': CDS_PINID='\2d+\';
NODE_NAME     R5020 2
 '@T6G_MB_LIB.T6G(SCH_1):PAGE136_I167@PURE_QUANTA.Q_RES(CHIPS)':
 'B': CDS_PINID='B';
NODE_NAME     R6006 2
 '@T6G_MB_LIB.T6G(SCH_1):PAGE348_I117@PURE_QUANTA.Q_RES(CHIPS)':
 'B': CDS_PINID='B';
NET_NAME
'I3C_SCM_3_R_SDA'
 '@T6G_MB_LIB.T6G(SCH_1):I3C_SCM_3_R_SDA':
 C_SIGNAL='@t6g_mb_lib.t6g(sch_1):i3c_scm_3_r_sda';
NODE_NAME     U108 4
 '@T6G_MB_LIB.T6G(SCH_1):PAGE136_I68@PURE_QUANTA.PI3CSW12ZUAEX(CHIPS)':
 '2D-': CDS_PINID='\2d-\';
NODE_NAME     R5021 2
 '@T6G_MB_LIB.T6G(SCH_1):PAGE136_I166@PURE_QUANTA.Q_RES(CHIPS)':
 'B': CDS_PINID='B';
NODE_NAME     R6007 2
 '@T6G_MB_LIB.T6G(SCH_1):PAGE348_I119@PURE_QUANTA.Q_RES(CHIPS)':
 'B': CDS_PINID='B';
NET_NAME
'I3C_SCM_3_SCL'
 '@T6G_MB_LIB.T6G(SCH_1):I3C_SCM_3_SCL':
 C_SIGNAL='@t6g_mb_lib.t6g(sch_1):i3c_scm_3_scl';
NODE_NAME     R6006 1
 '@T6G_MB_LIB.T6G(SCH_1):PAGE348_I117@PURE_QUANTA.Q_RES(CHIPS)':
 'A': CDS_PINID='A';
NODE_NAME     J41 OA11
 '@T6G_MB_LIB.T6G(SCH_1):PAGE348_I176@PURE_QUANTA.SCONN168_ME1016810202011(CHIPS)':
 'REFCLKN3': CDS_PINID='REFCLKN3';
NET_NAME
'I3C_SCM_3_SDA'
 '@T6G_MB_LIB.T6G(SCH_1):I3C_SCM_3_SDA':
 C_SIGNAL='@t6g_mb_lib.t6g(sch_1):i3c_scm_3_sda';
NODE_NAME     R6007 1
 '@T6G_MB_LIB.T6G(SCH_1):PAGE348_I119@PURE_QUANTA.Q_RES(CHIPS)':
 'A': CDS_PINID='A';
NODE_NAME     J41 OA12
 '@T6G_MB_LIB.T6G(SCH_1):PAGE348_I176@PURE_QUANTA.SCONN168_ME1016810202011(CHIPS)':
 'REFCLKP3': CDS_PINID='REFCLKP3';
NET_NAME
'I3C_SPD_DDRAF_CPU0_BYPASS_SCL'
 '@T6G_MB_LIB.T6G(SCH_1):I3C_SPD_DDRAF_CPU0_BYPASS_SCL':
 C_SIGNAL='@t6g_mb_lib.t6g(sch_1):i3c_spd_ddraf_cpu0_bypass_scl';
NODE_NAME     R2310 2
 '@T6G_MB_LIB.T6G(SCH_1):PAGE136_I123@PURE_QUANTA.Q_RES(CHIPS)':
 'B': CDS_PINID='B';
NODE_NAME     R1330 1
 '@T6G_MB_LIB.T6G(SCH_1):PAGE136_I131@PURE_QUANTA.Q_RES(CHIPS)':
 'A': CDS_PINID='A';
NET_NAME
'I3C_SPD_DDRAF_CPU0_BYPASS_SDA'
 '@T6G_MB_LIB.T6G(SCH_1):I3C_SPD_DDRAF_CPU0_BYPASS_SDA':
 C_SIGNAL='@t6g_mb_lib.t6g(sch_1):i3c_spd_ddraf_cpu0_bypass_sda';
NODE_NAME     R2311 2
 '@T6G_MB_LIB.T6G(SCH_1):PAGE136_I124@PURE_QUANTA.Q_RES(CHIPS)':
 'B': CDS_PINID='B';
NODE_NAME     R1331 1
 '@T6G_MB_LIB.T6G(SCH_1):PAGE136_I132@PURE_QUANTA.Q_RES(CHIPS)':
 'A': CDS_PINID='A';
NET_NAME
'I3C_SPD_DDRAF_CPU0_LVC1_SCL'
 '@T6G_MB_LIB.T6G(SCH_1):I3C_SPD_DDRAF_CPU0_LVC1_SCL':
 C_SIGNAL='@t6g_mb_lib.t6g(sch_1):i3c_spd_ddraf_cpu0_lvc1_scl';
NODE_NAME     R1297 2
 '@T6G_MB_LIB.T6G(SCH_1):PAGE136_I31@PURE_QUANTA.Q_RES(CHIPS)':
 'B': CDS_PINID='B';
NODE_NAME     U105 8
 '@T6G_MB_LIB.T6G(SCH_1):PAGE136_I47@PURE_QUANTA.PI3CSW12ZUAEX(CHIPS)':
 'D+': CDS_PINID='\d+\';
NODE_NAME     R5006 2
 '@T6G_MB_LIB.T6G(SCH_1):PAGE136_I145@PURE_QUANTA.Q_RES(CHIPS)':
 'B': CDS_PINID='B';
NET_NAME
'I3C_SPD_DDRAF_CPU0_LVC1_SDA'
 '@T6G_MB_LIB.T6G(SCH_1):I3C_SPD_DDRAF_CPU0_LVC1_SDA':
 C_SIGNAL='@t6g_mb_lib.t6g(sch_1):i3c_spd_ddraf_cpu0_lvc1_sda';
NODE_NAME     R1298 2
 '@T6G_MB_LIB.T6G(SCH_1):PAGE136_I32@PURE_QUANTA.Q_RES(CHIPS)':
 'B': CDS_PINID='B';
NODE_NAME     U105 7
 '@T6G_MB_LIB.T6G(SCH_1):PAGE136_I47@PURE_QUANTA.PI3CSW12ZUAEX(CHIPS)':
 'D-': CDS_PINID='\d-\';
NODE_NAME     R5007 2
 '@T6G_MB_LIB.T6G(SCH_1):PAGE136_I147@PURE_QUANTA.Q_RES(CHIPS)':
 'B': CDS_PINID='B';
NET_NAME
'I3C_SPD_DDRAF_CPU0_SCL'
 '@T6G_MB_LIB.T6G(SCH_1):I3C_SPD_DDRAF_CPU0_SCL':
 C_SIGNAL='@t6g_mb_lib.t6g(sch_1):i3c_spd_ddraf_cpu0_scl';
NODE_NAME     R1297 1
 '@T6G_MB_LIB.T6G(SCH_1):PAGE136_I31@PURE_QUANTA.Q_RES(CHIPS)':
 'A': CDS_PINID='A';
NODE_NAME     R1330 2
 '@T6G_MB_LIB.T6G(SCH_1):PAGE136_I131@PURE_QUANTA.Q_RES(CHIPS)':
 'B': CDS_PINID='B';
NODE_NAME     R1568 1
 '@T6G_MB_LIB.T6G(SCH_1):PAGE85_I539@PURE_QUANTA.Q_RES(CHIPS)':
 'A': CDS_PINID='A';
NODE_NAME     R1569 1
 '@T6G_MB_LIB.T6G(SCH_1):PAGE86_I372@PURE_QUANTA.Q_RES(CHIPS)':
 'A': CDS_PINID='A';
NODE_NAME     R1572 1
 '@T6G_MB_LIB.T6G(SCH_1):PAGE89_I416@PURE_QUANTA.Q_RES(CHIPS)':
 'A': CDS_PINID='A';
NODE_NAME     R1570 1
 '@T6G_MB_LIB.T6G(SCH_1):PAGE87_I417@PURE_QUANTA.Q_RES(CHIPS)':
 'A': CDS_PINID='A';
NODE_NAME     R1 1
 '@T6G_MB_LIB.T6G(SCH_1):PAGE88_I421@PURE_QUANTA.Q_RES(CHIPS)':
 'A': CDS_PINID='A';
NODE_NAME     R1573 1
 '@T6G_MB_LIB.T6G(SCH_1):PAGE90_I418@PURE_QUANTA.Q_RES(CHIPS)':
 'A': CDS_PINID='A';
NET_NAME
'I3C_SPD_DDRAF_CPU0_SDA'
 '@T6G_MB_LIB.T6G(SCH_1):I3C_SPD_DDRAF_CPU0_SDA':
 C_SIGNAL='@t6g_mb_lib.t6g(sch_1):i3c_spd_ddraf_cpu0_sda';
NODE_NAME     R1298 1
 '@T6G_MB_LIB.T6G(SCH_1):PAGE136_I32@PURE_QUANTA.Q_RES(CHIPS)':
 'A': CDS_PINID='A';
NODE_NAME     R1331 2
 '@T6G_MB_LIB.T6G(SCH_1):PAGE136_I132@PURE_QUANTA.Q_RES(CHIPS)':
 'B': CDS_PINID='B';
NODE_NAME     R1674 1
 '@T6G_MB_LIB.T6G(SCH_1):PAGE85_I554@PURE_QUANTA.Q_RES(CHIPS)':
 'A': CDS_PINID='A';
NODE_NAME     R1675 1
 '@T6G_MB_LIB.T6G(SCH_1):PAGE86_I373@PURE_QUANTA.Q_RES(CHIPS)':
 'A': CDS_PINID='A';
NODE_NAME     R1677 1
 '@T6G_MB_LIB.T6G(SCH_1):PAGE87_I418@PURE_QUANTA.Q_RES(CHIPS)':
 'A': CDS_PINID='A';
NODE_NAME     R1676 1
 '@T6G_MB_LIB.T6G(SCH_1):PAGE88_I422@PURE_QUANTA.Q_RES(CHIPS)':
 'A': CDS_PINID='A';
NODE_NAME     R1678 1
 '@T6G_MB_LIB.T6G(SCH_1):PAGE89_I418@PURE_QUANTA.Q_RES(CHIPS)':
 'A': CDS_PINID='A';
NODE_NAME     R1679 1
 '@T6G_MB_LIB.T6G(SCH_1):PAGE90_I419@PURE_QUANTA.Q_RES(CHIPS)':
 'A': CDS_PINID='A';
NET_NAME
'I3C_SPD_DDRAF_CPU1_BYPASS_SCL'
 '@T6G_MB_LIB.T6G(SCH_1):I3C_SPD_DDRAF_CPU1_BYPASS_SCL':
 C_SIGNAL='@t6g_mb_lib.t6g(sch_1):i3c_spd_ddraf_cpu1_bypass_scl';
NODE_NAME     R988 2
 '@T6G_MB_LIB.T6G(SCH_1):PAGE136_I138@PURE_QUANTA.Q_RES(CHIPS)':
 'B': CDS_PINID='B';
NODE_NAME     R1334 1
 '@T6G_MB_LIB.T6G(SCH_1):PAGE136_I139@PURE_QUANTA.Q_RES(CHIPS)':
 'A': CDS_PINID='A';
NET_NAME
'I3C_SPD_DDRAF_CPU1_BYPASS_SDA'
 '@T6G_MB_LIB.T6G(SCH_1):I3C_SPD_DDRAF_CPU1_BYPASS_SDA':
 C_SIGNAL='@t6g_mb_lib.t6g(sch_1):i3c_spd_ddraf_cpu1_bypass_sda';
NODE_NAME     R989 2
 '@T6G_MB_LIB.T6G(SCH_1):PAGE136_I137@PURE_QUANTA.Q_RES(CHIPS)':
 'B': CDS_PINID='B';
NODE_NAME     R1335 1
 '@T6G_MB_LIB.T6G(SCH_1):PAGE136_I140@PURE_QUANTA.Q_RES(CHIPS)':
 'A': CDS_PINID='A';
NET_NAME
'I3C_SPD_DDRAF_CPU1_LVC1_SCL'
 '@T6G_MB_LIB.T6G(SCH_1):I3C_SPD_DDRAF_CPU1_LVC1_SCL':
 C_SIGNAL='@t6g_mb_lib.t6g(sch_1):i3c_spd_ddraf_cpu1_lvc1_scl';
NODE_NAME     R1293 2
 '@T6G_MB_LIB.T6G(SCH_1):PAGE136_I35@PURE_QUANTA.Q_RES(CHIPS)':
 'B': CDS_PINID='B';
NODE_NAME     U107 8
 '@T6G_MB_LIB.T6G(SCH_1):PAGE136_I63@PURE_QUANTA.PI3CSW12ZUAEX(CHIPS)':
 'D+': CDS_PINID='\d+\';
NODE_NAME     R5010 2
 '@T6G_MB_LIB.T6G(SCH_1):PAGE136_I151@PURE_QUANTA.Q_RES(CHIPS)':
 'B': CDS_PINID='B';
NET_NAME
'I3C_SPD_DDRAF_CPU1_LVC1_SDA'
 '@T6G_MB_LIB.T6G(SCH_1):I3C_SPD_DDRAF_CPU1_LVC1_SDA':
 C_SIGNAL='@t6g_mb_lib.t6g(sch_1):i3c_spd_ddraf_cpu1_lvc1_sda';
NODE_NAME     R1294 2
 '@T6G_MB_LIB.T6G(SCH_1):PAGE136_I36@PURE_QUANTA.Q_RES(CHIPS)':
 'B': CDS_PINID='B';
NODE_NAME     U107 7
 '@T6G_MB_LIB.T6G(SCH_1):PAGE136_I63@PURE_QUANTA.PI3CSW12ZUAEX(CHIPS)':
 'D-': CDS_PINID='\d-\';
NODE_NAME     R5011 2
 '@T6G_MB_LIB.T6G(SCH_1):PAGE136_I152@PURE_QUANTA.Q_RES(CHIPS)':
 'B': CDS_PINID='B';
NET_NAME
'I3C_SPD_DDRAF_CPU1_SCL'
 '@T6G_MB_LIB.T6G(SCH_1):I3C_SPD_DDRAF_CPU1_SCL':
 C_SIGNAL='@t6g_mb_lib.t6g(sch_1):i3c_spd_ddraf_cpu1_scl';
NODE_NAME     R1293 1
 '@T6G_MB_LIB.T6G(SCH_1):PAGE136_I35@PURE_QUANTA.Q_RES(CHIPS)':
 'A': CDS_PINID='A';
NODE_NAME     R1334 2
 '@T6G_MB_LIB.T6G(SCH_1):PAGE136_I139@PURE_QUANTA.Q_RES(CHIPS)':
 'B': CDS_PINID='B';
NODE_NAME     R1582 1
 '@T6G_MB_LIB.T6G(SCH_1):PAGE99_I242@PURE_QUANTA.Q_RES(CHIPS)':
 'A': CDS_PINID='A';
NODE_NAME     R1581 1
 '@T6G_MB_LIB.T6G(SCH_1):PAGE98_I242@PURE_QUANTA.Q_RES(CHIPS)':
 'A': CDS_PINID='A';
NODE_NAME     R1580 1
 '@T6G_MB_LIB.T6G(SCH_1):PAGE97_I244@PURE_QUANTA.Q_RES(CHIPS)':
 'A': CDS_PINID='A';
NODE_NAME     R1584 1
 '@T6G_MB_LIB.T6G(SCH_1):PAGE101_I242@PURE_QUANTA.Q_RES(CHIPS)':
 'A': CDS_PINID='A';
NODE_NAME     R1583 1
 '@T6G_MB_LIB.T6G(SCH_1):PAGE100_I242@PURE_QUANTA.Q_RES(CHIPS)':
 'A': CDS_PINID='A';
NODE_NAME     R1585 1
 '@T6G_MB_LIB.T6G(SCH_1):PAGE102_I242@PURE_QUANTA.Q_RES(CHIPS)':
 'A': CDS_PINID='A';
NET_NAME
'I3C_SPD_DDRAF_CPU1_SDA'
 '@T6G_MB_LIB.T6G(SCH_1):I3C_SPD_DDRAF_CPU1_SDA':
 C_SIGNAL='@t6g_mb_lib.t6g(sch_1):i3c_spd_ddraf_cpu1_sda';
NODE_NAME     R1294 1
 '@T6G_MB_LIB.T6G(SCH_1):PAGE136_I36@PURE_QUANTA.Q_RES(CHIPS)':
 'A': CDS_PINID='A';
NODE_NAME     R1335 2
 '@T6G_MB_LIB.T6G(SCH_1):PAGE136_I140@PURE_QUANTA.Q_RES(CHIPS)':
 'B': CDS_PINID='B';
NODE_NAME     R1687 1
 '@T6G_MB_LIB.T6G(SCH_1):PAGE97_I256@PURE_QUANTA.Q_RES(CHIPS)':
 'A': CDS_PINID='A';
NODE_NAME     R1696 1
 '@T6G_MB_LIB.T6G(SCH_1):PAGE98_I243@PURE_QUANTA.Q_RES(CHIPS)':
 'A': CDS_PINID='A';
NODE_NAME     R1697 1
 '@T6G_MB_LIB.T6G(SCH_1):PAGE99_I243@PURE_QUANTA.Q_RES(CHIPS)':
 'A': CDS_PINID='A';
NODE_NAME     R1699 1
 '@T6G_MB_LIB.T6G(SCH_1):PAGE100_I243@PURE_QUANTA.Q_RES(CHIPS)':
 'A': CDS_PINID='A';
NODE_NAME     R1701 1
 '@T6G_MB_LIB.T6G(SCH_1):PAGE101_I243@PURE_QUANTA.Q_RES(CHIPS)':
 'A': CDS_PINID='A';
NODE_NAME     R1704 1
 '@T6G_MB_LIB.T6G(SCH_1):PAGE102_I243@PURE_QUANTA.Q_RES(CHIPS)':
 'A': CDS_PINID='A';
NET_NAME
'I3C_SPD_DDRA_CPU0_SCL'
 '@T6G_MB_LIB.T6G(SCH_1):I3C_SPD_DDRA_CPU0_SCL':
 C_SIGNAL='@t6g_mb_lib.t6g(sch_1):i3c_spd_ddra_cpu0_scl';
NODE_NAME     J1 4
 '@T6G_MB_LIB.T6G(SCH_1):PAGE85_I536@PURE_QUANTA.SCONN288_DDR506112002KQ(CHIPS)':
 'HSCL': CDS_PINID='HSCL';
NODE_NAME     R1568 2
 '@T6G_MB_LIB.T6G(SCH_1):PAGE85_I539@PURE_QUANTA.Q_RES(CHIPS)':
 'B': CDS_PINID='B';
NET_NAME
'I3C_SPD_DDRA_CPU0_SDA'
 '@T6G_MB_LIB.T6G(SCH_1):I3C_SPD_DDRA_CPU0_SDA':
 C_SIGNAL='@t6g_mb_lib.t6g(sch_1):i3c_spd_ddra_cpu0_sda';
NODE_NAME     J1 5
 '@T6G_MB_LIB.T6G(SCH_1):PAGE85_I536@PURE_QUANTA.SCONN288_DDR506112002KQ(CHIPS)':
 'HSDA': CDS_PINID='HSDA';
NODE_NAME     R1674 2
 '@T6G_MB_LIB.T6G(SCH_1):PAGE85_I554@PURE_QUANTA.Q_RES(CHIPS)':
 'B': CDS_PINID='B';
NET_NAME
'I3C_SPD_DDRA_CPU1_SCL'
 '@T6G_MB_LIB.T6G(SCH_1):I3C_SPD_DDRA_CPU1_SCL':
 C_SIGNAL='@t6g_mb_lib.t6g(sch_1):i3c_spd_ddra_cpu1_scl';
NODE_NAME     J24 4
 '@T6G_MB_LIB.T6G(SCH_1):PAGE97_I22@PURE_QUANTA.SCONN288_DDR506112002KQ(CHIPS)':
 'HSCL': CDS_PINID='HSCL';
NODE_NAME     R1580 2
 '@T6G_MB_LIB.T6G(SCH_1):PAGE97_I244@PURE_QUANTA.Q_RES(CHIPS)':
 'B': CDS_PINID='B';
NET_NAME
'I3C_SPD_DDRA_CPU1_SDA'
 '@T6G_MB_LIB.T6G(SCH_1):I3C_SPD_DDRA_CPU1_SDA':
 C_SIGNAL='@t6g_mb_lib.t6g(sch_1):i3c_spd_ddra_cpu1_sda';
NODE_NAME     J24 5
 '@T6G_MB_LIB.T6G(SCH_1):PAGE97_I22@PURE_QUANTA.SCONN288_DDR506112002KQ(CHIPS)':
 'HSDA': CDS_PINID='HSDA';
NODE_NAME     R1687 2
 '@T6G_MB_LIB.T6G(SCH_1):PAGE97_I256@PURE_QUANTA.Q_RES(CHIPS)':
 'B': CDS_PINID='B';
NET_NAME
'I3C_SPD_DDRB_CPU0_SCL'
 '@T6G_MB_LIB.T6G(SCH_1):I3C_SPD_DDRB_CPU0_SCL':
 C_SIGNAL='@t6g_mb_lib.t6g(sch_1):i3c_spd_ddrb_cpu0_scl';
NODE_NAME     J15 4
 '@T6G_MB_LIB.T6G(SCH_1):PAGE86_I350@PURE_QUANTA.SCONN288_DDR506112002KQ(CHIPS)':
 'HSCL': CDS_PINID='HSCL';
NODE_NAME     R1569 2
 '@T6G_MB_LIB.T6G(SCH_1):PAGE86_I372@PURE_QUANTA.Q_RES(CHIPS)':
 'B': CDS_PINID='B';
NET_NAME
'I3C_SPD_DDRB_CPU0_SDA'
 '@T6G_MB_LIB.T6G(SCH_1):I3C_SPD_DDRB_CPU0_SDA':
 C_SIGNAL='@t6g_mb_lib.t6g(sch_1):i3c_spd_ddrb_cpu0_sda';
NODE_NAME     J15 5
 '@T6G_MB_LIB.T6G(SCH_1):PAGE86_I350@PURE_QUANTA.SCONN288_DDR506112002KQ(CHIPS)':
 'HSDA': CDS_PINID='HSDA';
NODE_NAME     R1675 2
 '@T6G_MB_LIB.T6G(SCH_1):PAGE86_I373@PURE_QUANTA.Q_RES(CHIPS)':
 'B': CDS_PINID='B';
NET_NAME
'I3C_SPD_DDRB_CPU1_SCL'
 '@T6G_MB_LIB.T6G(SCH_1):I3C_SPD_DDRB_CPU1_SCL':
 C_SIGNAL='@t6g_mb_lib.t6g(sch_1):i3c_spd_ddrb_cpu1_scl';
NODE_NAME     J26 4
 '@T6G_MB_LIB.T6G(SCH_1):PAGE98_I22@PURE_QUANTA.SCONN288_DDR506112002KQ(CHIPS)':
 'HSCL': CDS_PINID='HSCL';
NODE_NAME     R1581 2
 '@T6G_MB_LIB.T6G(SCH_1):PAGE98_I242@PURE_QUANTA.Q_RES(CHIPS)':
 'B': CDS_PINID='B';
NET_NAME
'I3C_SPD_DDRB_CPU1_SDA'
 '@T6G_MB_LIB.T6G(SCH_1):I3C_SPD_DDRB_CPU1_SDA':
 C_SIGNAL='@t6g_mb_lib.t6g(sch_1):i3c_spd_ddrb_cpu1_sda';
NODE_NAME     J26 5
 '@T6G_MB_LIB.T6G(SCH_1):PAGE98_I22@PURE_QUANTA.SCONN288_DDR506112002KQ(CHIPS)':
 'HSDA': CDS_PINID='HSDA';
NODE_NAME     R1696 2
 '@T6G_MB_LIB.T6G(SCH_1):PAGE98_I243@PURE_QUANTA.Q_RES(CHIPS)':
 'B': CDS_PINID='B';
NET_NAME
'I3C_SPD_DDRC_CPU0_SCL'
 '@T6G_MB_LIB.T6G(SCH_1):I3C_SPD_DDRC_CPU0_SCL':
 C_SIGNAL='@t6g_mb_lib.t6g(sch_1):i3c_spd_ddrc_cpu0_scl';
NODE_NAME     J17 4
 '@T6G_MB_LIB.T6G(SCH_1):PAGE87_I350@PURE_QUANTA.SCONN288_DDR506112002KQ(CHIPS)':
 'HSCL': CDS_PINID='HSCL';
NODE_NAME     R1570 2
 '@T6G_MB_LIB.T6G(SCH_1):PAGE87_I417@PURE_QUANTA.Q_RES(CHIPS)':
 'B': CDS_PINID='B';
NET_NAME
'I3C_SPD_DDRC_CPU0_SDA'
 '@T6G_MB_LIB.T6G(SCH_1):I3C_SPD_DDRC_CPU0_SDA':
 C_SIGNAL='@t6g_mb_lib.t6g(sch_1):i3c_spd_ddrc_cpu0_sda';
NODE_NAME     J17 5
 '@T6G_MB_LIB.T6G(SCH_1):PAGE87_I350@PURE_QUANTA.SCONN288_DDR506112002KQ(CHIPS)':
 'HSDA': CDS_PINID='HSDA';
NODE_NAME     R1677 2
 '@T6G_MB_LIB.T6G(SCH_1):PAGE87_I418@PURE_QUANTA.Q_RES(CHIPS)':
 'B': CDS_PINID='B';
NET_NAME
'I3C_SPD_DDRC_CPU1_SCL'
 '@T6G_MB_LIB.T6G(SCH_1):I3C_SPD_DDRC_CPU1_SCL':
 C_SIGNAL='@t6g_mb_lib.t6g(sch_1):i3c_spd_ddrc_cpu1_scl';
NODE_NAME     J28 4
 '@T6G_MB_LIB.T6G(SCH_1):PAGE99_I22@PURE_QUANTA.SCONN288_DDR506112002KQ(CHIPS)':
 'HSCL': CDS_PINID='HSCL';
NODE_NAME     R1582 2
 '@T6G_MB_LIB.T6G(SCH_1):PAGE99_I242@PURE_QUANTA.Q_RES(CHIPS)':
 'B': CDS_PINID='B';
NET_NAME
'I3C_SPD_DDRC_CPU1_SDA'
 '@T6G_MB_LIB.T6G(SCH_1):I3C_SPD_DDRC_CPU1_SDA':
 C_SIGNAL='@t6g_mb_lib.t6g(sch_1):i3c_spd_ddrc_cpu1_sda';
NODE_NAME     J28 5
 '@T6G_MB_LIB.T6G(SCH_1):PAGE99_I22@PURE_QUANTA.SCONN288_DDR506112002KQ(CHIPS)':
 'HSDA': CDS_PINID='HSDA';
NODE_NAME     R1697 2
 '@T6G_MB_LIB.T6G(SCH_1):PAGE99_I243@PURE_QUANTA.Q_RES(CHIPS)':
 'B': CDS_PINID='B';
NET_NAME
'I3C_SPD_DDRD_CPU0_SCL'
 '@T6G_MB_LIB.T6G(SCH_1):I3C_SPD_DDRD_CPU0_SCL':
 C_SIGNAL='@t6g_mb_lib.t6g(sch_1):i3c_spd_ddrd_cpu0_scl';
NODE_NAME     J19 4
 '@T6G_MB_LIB.T6G(SCH_1):PAGE88_I350@PURE_QUANTA.SCONN288_DDR506112002KQ(CHIPS)':
 'HSCL': CDS_PINID='HSCL';
NODE_NAME     R1 2
 '@T6G_MB_LIB.T6G(SCH_1):PAGE88_I421@PURE_QUANTA.Q_RES(CHIPS)':
 'B': CDS_PINID='B';
NET_NAME
'I3C_SPD_DDRD_CPU0_SDA'
 '@T6G_MB_LIB.T6G(SCH_1):I3C_SPD_DDRD_CPU0_SDA':
 C_SIGNAL='@t6g_mb_lib.t6g(sch_1):i3c_spd_ddrd_cpu0_sda';
NODE_NAME     J19 5
 '@T6G_MB_LIB.T6G(SCH_1):PAGE88_I350@PURE_QUANTA.SCONN288_DDR506112002KQ(CHIPS)':
 'HSDA': CDS_PINID='HSDA';
NODE_NAME     R1676 2
 '@T6G_MB_LIB.T6G(SCH_1):PAGE88_I422@PURE_QUANTA.Q_RES(CHIPS)':
 'B': CDS_PINID='B';
NET_NAME
'I3C_SPD_DDRD_CPU1_SCL'
 '@T6G_MB_LIB.T6G(SCH_1):I3C_SPD_DDRD_CPU1_SCL':
 C_SIGNAL='@t6g_mb_lib.t6g(sch_1):i3c_spd_ddrd_cpu1_scl';
NODE_NAME     J30 4
 '@T6G_MB_LIB.T6G(SCH_1):PAGE100_I52@PURE_QUANTA.SCONN288_DDR506112002KQ(CHIPS)':
 'HSCL': CDS_PINID='HSCL';
NODE_NAME     R1583 2
 '@T6G_MB_LIB.T6G(SCH_1):PAGE100_I242@PURE_QUANTA.Q_RES(CHIPS)':
 'B': CDS_PINID='B';
NET_NAME
'I3C_SPD_DDRD_CPU1_SDA'
 '@T6G_MB_LIB.T6G(SCH_1):I3C_SPD_DDRD_CPU1_SDA':
 C_SIGNAL='@t6g_mb_lib.t6g(sch_1):i3c_spd_ddrd_cpu1_sda';
NODE_NAME     J30 5
 '@T6G_MB_LIB.T6G(SCH_1):PAGE100_I52@PURE_QUANTA.SCONN288_DDR506112002KQ(CHIPS)':
 'HSDA': CDS_PINID='HSDA';
NODE_NAME     R1699 2
 '@T6G_MB_LIB.T6G(SCH_1):PAGE100_I243@PURE_QUANTA.Q_RES(CHIPS)':
 'B': CDS_PINID='B';
NET_NAME
'I3C_SPD_DDRE_CPU0_SCL'
 '@T6G_MB_LIB.T6G(SCH_1):I3C_SPD_DDRE_CPU0_SCL':
 C_SIGNAL='@t6g_mb_lib.t6g(sch_1):i3c_spd_ddre_cpu0_scl';
NODE_NAME     J21 4
 '@T6G_MB_LIB.T6G(SCH_1):PAGE89_I348@PURE_QUANTA.SCONN288_DDR506112002KQ(CHIPS)':
 'HSCL': CDS_PINID='HSCL';
NODE_NAME     R1572 2
 '@T6G_MB_LIB.T6G(SCH_1):PAGE89_I416@PURE_QUANTA.Q_RES(CHIPS)':
 'B': CDS_PINID='B';
NET_NAME
'I3C_SPD_DDRE_CPU0_SDA'
 '@T6G_MB_LIB.T6G(SCH_1):I3C_SPD_DDRE_CPU0_SDA':
 C_SIGNAL='@t6g_mb_lib.t6g(sch_1):i3c_spd_ddre_cpu0_sda';
NODE_NAME     J21 5
 '@T6G_MB_LIB.T6G(SCH_1):PAGE89_I348@PURE_QUANTA.SCONN288_DDR506112002KQ(CHIPS)':
 'HSDA': CDS_PINID='HSDA';
NODE_NAME     R1678 2
 '@T6G_MB_LIB.T6G(SCH_1):PAGE89_I418@PURE_QUANTA.Q_RES(CHIPS)':
 'B': CDS_PINID='B';
NET_NAME
'I3C_SPD_DDRE_CPU1_SCL'
 '@T6G_MB_LIB.T6G(SCH_1):I3C_SPD_DDRE_CPU1_SCL':
 C_SIGNAL='@t6g_mb_lib.t6g(sch_1):i3c_spd_ddre_cpu1_scl';
NODE_NAME     J32 4
 '@T6G_MB_LIB.T6G(SCH_1):PAGE101_I52@PURE_QUANTA.SCONN288_DDR506112002KQ(CHIPS)':
 'HSCL': CDS_PINID='HSCL';
NODE_NAME     R1584 2
 '@T6G_MB_LIB.T6G(SCH_1):PAGE101_I242@PURE_QUANTA.Q_RES(CHIPS)':
 'B': CDS_PINID='B';
NET_NAME
'I3C_SPD_DDRE_CPU1_SDA'
 '@T6G_MB_LIB.T6G(SCH_1):I3C_SPD_DDRE_CPU1_SDA':
 C_SIGNAL='@t6g_mb_lib.t6g(sch_1):i3c_spd_ddre_cpu1_sda';
NODE_NAME     J32 5
 '@T6G_MB_LIB.T6G(SCH_1):PAGE101_I52@PURE_QUANTA.SCONN288_DDR506112002KQ(CHIPS)':
 'HSDA': CDS_PINID='HSDA';
NODE_NAME     R1701 2
 '@T6G_MB_LIB.T6G(SCH_1):PAGE101_I243@PURE_QUANTA.Q_RES(CHIPS)':
 'B': CDS_PINID='B';
NET_NAME
'I3C_SPD_DDRF_CPU0_SCL'
 '@T6G_MB_LIB.T6G(SCH_1):I3C_SPD_DDRF_CPU0_SCL':
 C_SIGNAL='@t6g_mb_lib.t6g(sch_1):i3c_spd_ddrf_cpu0_scl';
NODE_NAME     J23 4
 '@T6G_MB_LIB.T6G(SCH_1):PAGE90_I350@PURE_QUANTA.SCONN288_DDR506112002KQ(CHIPS)':
 'HSCL': CDS_PINID='HSCL';
NODE_NAME     R1573 2
 '@T6G_MB_LIB.T6G(SCH_1):PAGE90_I418@PURE_QUANTA.Q_RES(CHIPS)':
 'B': CDS_PINID='B';
NET_NAME
'I3C_SPD_DDRF_CPU0_SDA'
 '@T6G_MB_LIB.T6G(SCH_1):I3C_SPD_DDRF_CPU0_SDA':
 C_SIGNAL='@t6g_mb_lib.t6g(sch_1):i3c_spd_ddrf_cpu0_sda';
NODE_NAME     J23 5
 '@T6G_MB_LIB.T6G(SCH_1):PAGE90_I350@PURE_QUANTA.SCONN288_DDR506112002KQ(CHIPS)':
 'HSDA': CDS_PINID='HSDA';
NODE_NAME     R1679 2
 '@T6G_MB_LIB.T6G(SCH_1):PAGE90_I419@PURE_QUANTA.Q_RES(CHIPS)':
 'B': CDS_PINID='B';
NET_NAME
'I3C_SPD_DDRF_CPU1_SCL'
 '@T6G_MB_LIB.T6G(SCH_1):I3C_SPD_DDRF_CPU1_SCL':
 C_SIGNAL='@t6g_mb_lib.t6g(sch_1):i3c_spd_ddrf_cpu1_scl';
NODE_NAME     J33 4
 '@T6G_MB_LIB.T6G(SCH_1):PAGE102_I22@PURE_QUANTA.SCONN288_DDR506112002KQ(CHIPS)':
 'HSCL': CDS_PINID='HSCL';
NODE_NAME     R1585 2
 '@T6G_MB_LIB.T6G(SCH_1):PAGE102_I242@PURE_QUANTA.Q_RES(CHIPS)':
 'B': CDS_PINID='B';
NET_NAME
'I3C_SPD_DDRF_CPU1_SDA'
 '@T6G_MB_LIB.T6G(SCH_1):I3C_SPD_DDRF_CPU1_SDA':
 C_SIGNAL='@t6g_mb_lib.t6g(sch_1):i3c_spd_ddrf_cpu1_sda';
NODE_NAME     J33 5
 '@T6G_MB_LIB.T6G(SCH_1):PAGE102_I22@PURE_QUANTA.SCONN288_DDR506112002KQ(CHIPS)':
 'HSDA': CDS_PINID='HSDA';
NODE_NAME     R1704 2
 '@T6G_MB_LIB.T6G(SCH_1):PAGE102_I243@PURE_QUANTA.Q_RES(CHIPS)':
 'B': CDS_PINID='B';
NET_NAME
'I3C_SPD_DDRGL_CPU0_BYPASS_SCL'
 '@T6G_MB_LIB.T6G(SCH_1):I3C_SPD_DDRGL_CPU0_BYPASS_SCL':
 C_SIGNAL='@t6g_mb_lib.t6g(sch_1):i3c_spd_ddrgl_cpu0_bypass_scl';
NODE_NAME     R1332 1
 '@T6G_MB_LIB.T6G(SCH_1):PAGE136_I134@PURE_QUANTA.Q_RES(CHIPS)':
 'A': CDS_PINID='A';
NODE_NAME     R986 2
 '@T6G_MB_LIB.T6G(SCH_1):PAGE136_I135@PURE_QUANTA.Q_RES(CHIPS)':
 'B': CDS_PINID='B';
NET_NAME
'I3C_SPD_DDRGL_CPU0_BYPASS_SDA'
 '@T6G_MB_LIB.T6G(SCH_1):I3C_SPD_DDRGL_CPU0_BYPASS_SDA':
 C_SIGNAL='@t6g_mb_lib.t6g(sch_1):i3c_spd_ddrgl_cpu0_bypass_sda';
NODE_NAME     R1333 1
 '@T6G_MB_LIB.T6G(SCH_1):PAGE136_I133@PURE_QUANTA.Q_RES(CHIPS)':
 'A': CDS_PINID='A';
NODE_NAME     R987 2
 '@T6G_MB_LIB.T6G(SCH_1):PAGE136_I136@PURE_QUANTA.Q_RES(CHIPS)':
 'B': CDS_PINID='B';
NET_NAME
'I3C_SPD_DDRGL_CPU0_LVC1_SCL'
 '@T6G_MB_LIB.T6G(SCH_1):I3C_SPD_DDRGL_CPU0_LVC1_SCL':
 C_SIGNAL='@t6g_mb_lib.t6g(sch_1):i3c_spd_ddrgl_cpu0_lvc1_scl';
NODE_NAME     R1299 2
 '@T6G_MB_LIB.T6G(SCH_1):PAGE136_I33@PURE_QUANTA.Q_RES(CHIPS)':
 'B': CDS_PINID='B';
NODE_NAME     U106 8
 '@T6G_MB_LIB.T6G(SCH_1):PAGE136_I54@PURE_QUANTA.PI3CSW12ZUAEX(CHIPS)':
 'D+': CDS_PINID='\d+\';
NODE_NAME     R5008 2
 '@T6G_MB_LIB.T6G(SCH_1):PAGE136_I148@PURE_QUANTA.Q_RES(CHIPS)':
 'B': CDS_PINID='B';
NET_NAME
'I3C_SPD_DDRGL_CPU0_LVC1_SDA'
 '@T6G_MB_LIB.T6G(SCH_1):I3C_SPD_DDRGL_CPU0_LVC1_SDA':
 C_SIGNAL='@t6g_mb_lib.t6g(sch_1):i3c_spd_ddrgl_cpu0_lvc1_sda';
NODE_NAME     R1300 2
 '@T6G_MB_LIB.T6G(SCH_1):PAGE136_I34@PURE_QUANTA.Q_RES(CHIPS)':
 'B': CDS_PINID='B';
NODE_NAME     U106 7
 '@T6G_MB_LIB.T6G(SCH_1):PAGE136_I54@PURE_QUANTA.PI3CSW12ZUAEX(CHIPS)':
 'D-': CDS_PINID='\d-\';
NODE_NAME     R5009 2
 '@T6G_MB_LIB.T6G(SCH_1):PAGE136_I150@PURE_QUANTA.Q_RES(CHIPS)':
 'B': CDS_PINID='B';
NET_NAME
'I3C_SPD_DDRGL_CPU0_SCL'
 '@T6G_MB_LIB.T6G(SCH_1):I3C_SPD_DDRGL_CPU0_SCL':
 C_SIGNAL='@t6g_mb_lib.t6g(sch_1):i3c_spd_ddrgl_cpu0_scl';
NODE_NAME     R1299 1
 '@T6G_MB_LIB.T6G(SCH_1):PAGE136_I33@PURE_QUANTA.Q_RES(CHIPS)':
 'A': CDS_PINID='A';
NODE_NAME     R1332 2
 '@T6G_MB_LIB.T6G(SCH_1):PAGE136_I134@PURE_QUANTA.Q_RES(CHIPS)':
 'B': CDS_PINID='B';
NODE_NAME     R1579 1
 '@T6G_MB_LIB.T6G(SCH_1):PAGE96_I242@PURE_QUANTA.Q_RES(CHIPS)':
 'A': CDS_PINID='A';
NODE_NAME     R1575 1
 '@T6G_MB_LIB.T6G(SCH_1):PAGE92_I243@PURE_QUANTA.Q_RES(CHIPS)':
 'A': CDS_PINID='A';
NODE_NAME     R1576 1
 '@T6G_MB_LIB.T6G(SCH_1):PAGE93_I242@PURE_QUANTA.Q_RES(CHIPS)':
 'A': CDS_PINID='A';
NODE_NAME     R1574 1
 '@T6G_MB_LIB.T6G(SCH_1):PAGE91_I242@PURE_QUANTA.Q_RES(CHIPS)':
 'A': CDS_PINID='A';
NODE_NAME     R1577 1
 '@T6G_MB_LIB.T6G(SCH_1):PAGE94_I242@PURE_QUANTA.Q_RES(CHIPS)':
 'A': CDS_PINID='A';
NODE_NAME     R1578 1
 '@T6G_MB_LIB.T6G(SCH_1):PAGE95_I242@PURE_QUANTA.Q_RES(CHIPS)':
 'A': CDS_PINID='A';
NET_NAME
'I3C_SPD_DDRGL_CPU0_SDA'
 '@T6G_MB_LIB.T6G(SCH_1):I3C_SPD_DDRGL_CPU0_SDA':
 C_SIGNAL='@t6g_mb_lib.t6g(sch_1):i3c_spd_ddrgl_cpu0_sda';
NODE_NAME     R1300 1
 '@T6G_MB_LIB.T6G(SCH_1):PAGE136_I34@PURE_QUANTA.Q_RES(CHIPS)':
 'A': CDS_PINID='A';
NODE_NAME     R1333 2
 '@T6G_MB_LIB.T6G(SCH_1):PAGE136_I133@PURE_QUANTA.Q_RES(CHIPS)':
 'B': CDS_PINID='B';
NODE_NAME     R1680 1
 '@T6G_MB_LIB.T6G(SCH_1):PAGE91_I254@PURE_QUANTA.Q_RES(CHIPS)':
 'A': CDS_PINID='A';
NODE_NAME     R1681 1
 '@T6G_MB_LIB.T6G(SCH_1):PAGE92_I244@PURE_QUANTA.Q_RES(CHIPS)':
 'A': CDS_PINID='A';
NODE_NAME     R1683 1
 '@T6G_MB_LIB.T6G(SCH_1):PAGE93_I243@PURE_QUANTA.Q_RES(CHIPS)':
 'A': CDS_PINID='A';
NODE_NAME     R1684 1
 '@T6G_MB_LIB.T6G(SCH_1):PAGE94_I243@PURE_QUANTA.Q_RES(CHIPS)':
 'A': CDS_PINID='A';
NODE_NAME     R1685 1
 '@T6G_MB_LIB.T6G(SCH_1):PAGE95_I243@PURE_QUANTA.Q_RES(CHIPS)':
 'A': CDS_PINID='A';
NODE_NAME     R1686 1
 '@T6G_MB_LIB.T6G(SCH_1):PAGE96_I243@PURE_QUANTA.Q_RES(CHIPS)':
 'A': CDS_PINID='A';
NET_NAME
'I3C_SPD_DDRGL_CPU1_BYPASS_SCL'
 '@T6G_MB_LIB.T6G(SCH_1):I3C_SPD_DDRGL_CPU1_BYPASS_SCL':
 C_SIGNAL='@t6g_mb_lib.t6g(sch_1):i3c_spd_ddrgl_cpu1_bypass_scl';
NODE_NAME     R990 2
 '@T6G_MB_LIB.T6G(SCH_1):PAGE136_I142@PURE_QUANTA.Q_RES(CHIPS)':
 'B': CDS_PINID='B';
NODE_NAME     R1336 1
 '@T6G_MB_LIB.T6G(SCH_1):PAGE136_I143@PURE_QUANTA.Q_RES(CHIPS)':
 'A': CDS_PINID='A';
NET_NAME
'I3C_SPD_DDRGL_CPU1_BYPASS_SDA'
 '@T6G_MB_LIB.T6G(SCH_1):I3C_SPD_DDRGL_CPU1_BYPASS_SDA':
 C_SIGNAL='@t6g_mb_lib.t6g(sch_1):i3c_spd_ddrgl_cpu1_bypass_sda';
NODE_NAME     R991 2
 '@T6G_MB_LIB.T6G(SCH_1):PAGE136_I141@PURE_QUANTA.Q_RES(CHIPS)':
 'B': CDS_PINID='B';
NODE_NAME     R1337 1
 '@T6G_MB_LIB.T6G(SCH_1):PAGE136_I144@PURE_QUANTA.Q_RES(CHIPS)':
 'A': CDS_PINID='A';
NET_NAME
'I3C_SPD_DDRGL_CPU1_LVC1_SCL'
 '@T6G_MB_LIB.T6G(SCH_1):I3C_SPD_DDRGL_CPU1_LVC1_SCL':
 C_SIGNAL='@t6g_mb_lib.t6g(sch_1):i3c_spd_ddrgl_cpu1_lvc1_scl';
NODE_NAME     R1295 2
 '@T6G_MB_LIB.T6G(SCH_1):PAGE136_I37@PURE_QUANTA.Q_RES(CHIPS)':
 'B': CDS_PINID='B';
NODE_NAME     U108 8
 '@T6G_MB_LIB.T6G(SCH_1):PAGE136_I68@PURE_QUANTA.PI3CSW12ZUAEX(CHIPS)':
 'D+': CDS_PINID='\d+\';
NODE_NAME     R5012 2
 '@T6G_MB_LIB.T6G(SCH_1):PAGE136_I156@PURE_QUANTA.Q_RES(CHIPS)':
 'B': CDS_PINID='B';
NET_NAME
'I3C_SPD_DDRGL_CPU1_LVC1_SDA'
 '@T6G_MB_LIB.T6G(SCH_1):I3C_SPD_DDRGL_CPU1_LVC1_SDA':
 C_SIGNAL='@t6g_mb_lib.t6g(sch_1):i3c_spd_ddrgl_cpu1_lvc1_sda';
NODE_NAME     R1296 2
 '@T6G_MB_LIB.T6G(SCH_1):PAGE136_I38@PURE_QUANTA.Q_RES(CHIPS)':
 'B': CDS_PINID='B';
NODE_NAME     U108 7
 '@T6G_MB_LIB.T6G(SCH_1):PAGE136_I68@PURE_QUANTA.PI3CSW12ZUAEX(CHIPS)':
 'D-': CDS_PINID='\d-\';
NODE_NAME     R5013 2
 '@T6G_MB_LIB.T6G(SCH_1):PAGE136_I154@PURE_QUANTA.Q_RES(CHIPS)':
 'B': CDS_PINID='B';
NET_NAME
'I3C_SPD_DDRGL_CPU1_SCL'
 '@T6G_MB_LIB.T6G(SCH_1):I3C_SPD_DDRGL_CPU1_SCL':
 C_SIGNAL='@t6g_mb_lib.t6g(sch_1):i3c_spd_ddrgl_cpu1_scl';
NODE_NAME     R1295 1
 '@T6G_MB_LIB.T6G(SCH_1):PAGE136_I37@PURE_QUANTA.Q_RES(CHIPS)':
 'A': CDS_PINID='A';
NODE_NAME     R1336 2
 '@T6G_MB_LIB.T6G(SCH_1):PAGE136_I143@PURE_QUANTA.Q_RES(CHIPS)':
 'B': CDS_PINID='B';
NODE_NAME     R1591 1
 '@T6G_MB_LIB.T6G(SCH_1):PAGE108_I241@PURE_QUANTA.Q_RES(CHIPS)':
 'A': CDS_PINID='A';
NODE_NAME     R1586 1
 '@T6G_MB_LIB.T6G(SCH_1):PAGE103_I244@PURE_QUANTA.Q_RES(CHIPS)':
 'A': CDS_PINID='A';
NODE_NAME     R1587 1
 '@T6G_MB_LIB.T6G(SCH_1):PAGE104_I244@PURE_QUANTA.Q_RES(CHIPS)':
 'A': CDS_PINID='A';
NODE_NAME     R1588 1
 '@T6G_MB_LIB.T6G(SCH_1):PAGE105_I242@PURE_QUANTA.Q_RES(CHIPS)':
 'A': CDS_PINID='A';
NODE_NAME     R1589 1
 '@T6G_MB_LIB.T6G(SCH_1):PAGE106_I242@PURE_QUANTA.Q_RES(CHIPS)':
 'A': CDS_PINID='A';
NODE_NAME     R1590 1
 '@T6G_MB_LIB.T6G(SCH_1):PAGE107_I241@PURE_QUANTA.Q_RES(CHIPS)':
 'A': CDS_PINID='A';
NET_NAME
'I3C_SPD_DDRGL_CPU1_SDA'
 '@T6G_MB_LIB.T6G(SCH_1):I3C_SPD_DDRGL_CPU1_SDA':
 C_SIGNAL='@t6g_mb_lib.t6g(sch_1):i3c_spd_ddrgl_cpu1_sda';
NODE_NAME     R1296 1
 '@T6G_MB_LIB.T6G(SCH_1):PAGE136_I38@PURE_QUANTA.Q_RES(CHIPS)':
 'A': CDS_PINID='A';
NODE_NAME     R1337 2
 '@T6G_MB_LIB.T6G(SCH_1):PAGE136_I144@PURE_QUANTA.Q_RES(CHIPS)':
 'B': CDS_PINID='B';
NODE_NAME     R1705 1
 '@T6G_MB_LIB.T6G(SCH_1):PAGE103_I256@PURE_QUANTA.Q_RES(CHIPS)':
 'A': CDS_PINID='A';
NODE_NAME     R1707 1
 '@T6G_MB_LIB.T6G(SCH_1):PAGE104_I245@PURE_QUANTA.Q_RES(CHIPS)':
 'A': CDS_PINID='A';
NODE_NAME     R1708 1
 '@T6G_MB_LIB.T6G(SCH_1):PAGE105_I243@PURE_QUANTA.Q_RES(CHIPS)':
 'A': CDS_PINID='A';
NODE_NAME     R1709 1
 '@T6G_MB_LIB.T6G(SCH_1):PAGE106_I243@PURE_QUANTA.Q_RES(CHIPS)':
 'A': CDS_PINID='A';
NODE_NAME     R1710 1
 '@T6G_MB_LIB.T6G(SCH_1):PAGE107_I242@PURE_QUANTA.Q_RES(CHIPS)':
 'A': CDS_PINID='A';
NODE_NAME     R1711 1
 '@T6G_MB_LIB.T6G(SCH_1):PAGE108_I242@PURE_QUANTA.Q_RES(CHIPS)':
 'A': CDS_PINID='A';
NET_NAME
'I3C_SPD_DDRG_CPU0_SCL'
 '@T6G_MB_LIB.T6G(SCH_1):I3C_SPD_DDRG_CPU0_SCL':
 C_SIGNAL='@t6g_mb_lib.t6g(sch_1):i3c_spd_ddrg_cpu0_scl';
NODE_NAME     J16 4
 '@T6G_MB_LIB.T6G(SCH_1):PAGE91_I22@PURE_QUANTA.SCONN288_DDR506112002KQ(CHIPS)':
 'HSCL': CDS_PINID='HSCL';
NODE_NAME     R1574 2
 '@T6G_MB_LIB.T6G(SCH_1):PAGE91_I242@PURE_QUANTA.Q_RES(CHIPS)':
 'B': CDS_PINID='B';
NET_NAME
'I3C_SPD_DDRG_CPU0_SDA'
 '@T6G_MB_LIB.T6G(SCH_1):I3C_SPD_DDRG_CPU0_SDA':
 C_SIGNAL='@t6g_mb_lib.t6g(sch_1):i3c_spd_ddrg_cpu0_sda';
NODE_NAME     J16 5
 '@T6G_MB_LIB.T6G(SCH_1):PAGE91_I22@PURE_QUANTA.SCONN288_DDR506112002KQ(CHIPS)':
 'HSDA': CDS_PINID='HSDA';
NODE_NAME     R1680 2
 '@T6G_MB_LIB.T6G(SCH_1):PAGE91_I254@PURE_QUANTA.Q_RES(CHIPS)':
 'B': CDS_PINID='B';
NET_NAME
'I3C_SPD_DDRG_CPU1_SCL'
 '@T6G_MB_LIB.T6G(SCH_1):I3C_SPD_DDRG_CPU1_SCL':
 C_SIGNAL='@t6g_mb_lib.t6g(sch_1):i3c_spd_ddrg_cpu1_scl';
NODE_NAME     J102 4
 '@T6G_MB_LIB.T6G(SCH_1):PAGE103_I22@PURE_QUANTA.SCONN288_DDR506112002KQ(CHIPS)':
 'HSCL': CDS_PINID='HSCL';
NODE_NAME     R1586 2
 '@T6G_MB_LIB.T6G(SCH_1):PAGE103_I244@PURE_QUANTA.Q_RES(CHIPS)':
 'B': CDS_PINID='B';
NET_NAME
'I3C_SPD_DDRG_CPU1_SDA'
 '@T6G_MB_LIB.T6G(SCH_1):I3C_SPD_DDRG_CPU1_SDA':
 C_SIGNAL='@t6g_mb_lib.t6g(sch_1):i3c_spd_ddrg_cpu1_sda';
NODE_NAME     J102 5
 '@T6G_MB_LIB.T6G(SCH_1):PAGE103_I22@PURE_QUANTA.SCONN288_DDR506112002KQ(CHIPS)':
 'HSDA': CDS_PINID='HSDA';
NODE_NAME     R1705 2
 '@T6G_MB_LIB.T6G(SCH_1):PAGE103_I256@PURE_QUANTA.Q_RES(CHIPS)':
 'B': CDS_PINID='B';
NET_NAME
'I3C_SPD_DDRH_CPU0_SCL'
 '@T6G_MB_LIB.T6G(SCH_1):I3C_SPD_DDRH_CPU0_SCL':
 C_SIGNAL='@t6g_mb_lib.t6g(sch_1):i3c_spd_ddrh_cpu0_scl';
NODE_NAME     J69 4
 '@T6G_MB_LIB.T6G(SCH_1):PAGE92_I22@PURE_QUANTA.SCONN288_DDR506112002KQ(CHIPS)':
 'HSCL': CDS_PINID='HSCL';
NODE_NAME     R1575 2
 '@T6G_MB_LIB.T6G(SCH_1):PAGE92_I243@PURE_QUANTA.Q_RES(CHIPS)':
 'B': CDS_PINID='B';
NET_NAME
'I3C_SPD_DDRH_CPU0_SDA'
 '@T6G_MB_LIB.T6G(SCH_1):I3C_SPD_DDRH_CPU0_SDA':
 C_SIGNAL='@t6g_mb_lib.t6g(sch_1):i3c_spd_ddrh_cpu0_sda';
NODE_NAME     J69 5
 '@T6G_MB_LIB.T6G(SCH_1):PAGE92_I22@PURE_QUANTA.SCONN288_DDR506112002KQ(CHIPS)':
 'HSDA': CDS_PINID='HSDA';
NODE_NAME     R1681 2
 '@T6G_MB_LIB.T6G(SCH_1):PAGE92_I244@PURE_QUANTA.Q_RES(CHIPS)':
 'B': CDS_PINID='B';
NET_NAME
'I3C_SPD_DDRH_CPU1_SCL'
 '@T6G_MB_LIB.T6G(SCH_1):I3C_SPD_DDRH_CPU1_SCL':
 C_SIGNAL='@t6g_mb_lib.t6g(sch_1):i3c_spd_ddrh_cpu1_scl';
NODE_NAME     J27 4
 '@T6G_MB_LIB.T6G(SCH_1):PAGE104_I22@PURE_QUANTA.SCONN288_DDR506112002KQ(CHIPS)':
 'HSCL': CDS_PINID='HSCL';
NODE_NAME     R1587 2
 '@T6G_MB_LIB.T6G(SCH_1):PAGE104_I244@PURE_QUANTA.Q_RES(CHIPS)':
 'B': CDS_PINID='B';
NET_NAME
'I3C_SPD_DDRH_CPU1_SDA'
 '@T6G_MB_LIB.T6G(SCH_1):I3C_SPD_DDRH_CPU1_SDA':
 C_SIGNAL='@t6g_mb_lib.t6g(sch_1):i3c_spd_ddrh_cpu1_sda';
NODE_NAME     J27 5
 '@T6G_MB_LIB.T6G(SCH_1):PAGE104_I22@PURE_QUANTA.SCONN288_DDR506112002KQ(CHIPS)':
 'HSDA': CDS_PINID='HSDA';
NODE_NAME     R1707 2
 '@T6G_MB_LIB.T6G(SCH_1):PAGE104_I245@PURE_QUANTA.Q_RES(CHIPS)':
 'B': CDS_PINID='B';
NET_NAME
'I3C_SPD_DDRI_CPU0_SCL'
 '@T6G_MB_LIB.T6G(SCH_1):I3C_SPD_DDRI_CPU0_SCL':
 C_SIGNAL='@t6g_mb_lib.t6g(sch_1):i3c_spd_ddri_cpu0_scl';
NODE_NAME     J18 4
 '@T6G_MB_LIB.T6G(SCH_1):PAGE93_I22@PURE_QUANTA.SCONN288_DDR506112002KQ(CHIPS)':
 'HSCL': CDS_PINID='HSCL';
NODE_NAME     R1576 2
 '@T6G_MB_LIB.T6G(SCH_1):PAGE93_I242@PURE_QUANTA.Q_RES(CHIPS)':
 'B': CDS_PINID='B';
NET_NAME
'I3C_SPD_DDRI_CPU0_SDA'
 '@T6G_MB_LIB.T6G(SCH_1):I3C_SPD_DDRI_CPU0_SDA':
 C_SIGNAL='@t6g_mb_lib.t6g(sch_1):i3c_spd_ddri_cpu0_sda';
NODE_NAME     J18 5
 '@T6G_MB_LIB.T6G(SCH_1):PAGE93_I22@PURE_QUANTA.SCONN288_DDR506112002KQ(CHIPS)':
 'HSDA': CDS_PINID='HSDA';
NODE_NAME     R1683 2
 '@T6G_MB_LIB.T6G(SCH_1):PAGE93_I243@PURE_QUANTA.Q_RES(CHIPS)':
 'B': CDS_PINID='B';
NET_NAME
'I3C_SPD_DDRI_CPU1_SCL'
 '@T6G_MB_LIB.T6G(SCH_1):I3C_SPD_DDRI_CPU1_SCL':
 C_SIGNAL='@t6g_mb_lib.t6g(sch_1):i3c_spd_ddri_cpu1_scl';
NODE_NAME     J100 4
 '@T6G_MB_LIB.T6G(SCH_1):PAGE105_I22@PURE_QUANTA.SCONN288_DDR506112002KQ(CHIPS)':
 'HSCL': CDS_PINID='HSCL';
NODE_NAME     R1588 2
 '@T6G_MB_LIB.T6G(SCH_1):PAGE105_I242@PURE_QUANTA.Q_RES(CHIPS)':
 'B': CDS_PINID='B';
NET_NAME
'I3C_SPD_DDRI_CPU1_SDA'
 '@T6G_MB_LIB.T6G(SCH_1):I3C_SPD_DDRI_CPU1_SDA':
 C_SIGNAL='@t6g_mb_lib.t6g(sch_1):i3c_spd_ddri_cpu1_sda';
NODE_NAME     J100 5
 '@T6G_MB_LIB.T6G(SCH_1):PAGE105_I22@PURE_QUANTA.SCONN288_DDR506112002KQ(CHIPS)':
 'HSDA': CDS_PINID='HSDA';
NODE_NAME     R1708 2
 '@T6G_MB_LIB.T6G(SCH_1):PAGE105_I243@PURE_QUANTA.Q_RES(CHIPS)':
 'B': CDS_PINID='B';
NET_NAME
'I3C_SPD_DDRJ_CPU0_SCL'
 '@T6G_MB_LIB.T6G(SCH_1):I3C_SPD_DDRJ_CPU0_SCL':
 C_SIGNAL='@t6g_mb_lib.t6g(sch_1):i3c_spd_ddrj_cpu0_scl';
NODE_NAME     J68 4
 '@T6G_MB_LIB.T6G(SCH_1):PAGE94_I22@PURE_QUANTA.SCONN288_DDR506112002KQ(CHIPS)':
 'HSCL': CDS_PINID='HSCL';
NODE_NAME     R1577 2
 '@T6G_MB_LIB.T6G(SCH_1):PAGE94_I242@PURE_QUANTA.Q_RES(CHIPS)':
 'B': CDS_PINID='B';
NET_NAME
'I3C_SPD_DDRJ_CPU0_SDA'
 '@T6G_MB_LIB.T6G(SCH_1):I3C_SPD_DDRJ_CPU0_SDA':
 C_SIGNAL='@t6g_mb_lib.t6g(sch_1):i3c_spd_ddrj_cpu0_sda';
NODE_NAME     J68 5
 '@T6G_MB_LIB.T6G(SCH_1):PAGE94_I22@PURE_QUANTA.SCONN288_DDR506112002KQ(CHIPS)':
 'HSDA': CDS_PINID='HSDA';
NODE_NAME     R1684 2
 '@T6G_MB_LIB.T6G(SCH_1):PAGE94_I243@PURE_QUANTA.Q_RES(CHIPS)':
 'B': CDS_PINID='B';
NET_NAME
'I3C_SPD_DDRJ_CPU1_SCL'
 '@T6G_MB_LIB.T6G(SCH_1):I3C_SPD_DDRJ_CPU1_SCL':
 C_SIGNAL='@t6g_mb_lib.t6g(sch_1):i3c_spd_ddrj_cpu1_scl';
NODE_NAME     J29 4
 '@T6G_MB_LIB.T6G(SCH_1):PAGE106_I22@PURE_QUANTA.SCONN288_DDR506112002KQ(CHIPS)':
 'HSCL': CDS_PINID='HSCL';
NODE_NAME     R1589 2
 '@T6G_MB_LIB.T6G(SCH_1):PAGE106_I242@PURE_QUANTA.Q_RES(CHIPS)':
 'B': CDS_PINID='B';
NET_NAME
'I3C_SPD_DDRJ_CPU1_SDA'
 '@T6G_MB_LIB.T6G(SCH_1):I3C_SPD_DDRJ_CPU1_SDA':
 C_SIGNAL='@t6g_mb_lib.t6g(sch_1):i3c_spd_ddrj_cpu1_sda';
NODE_NAME     J29 5
 '@T6G_MB_LIB.T6G(SCH_1):PAGE106_I22@PURE_QUANTA.SCONN288_DDR506112002KQ(CHIPS)':
 'HSDA': CDS_PINID='HSDA';
NODE_NAME     R1709 2
 '@T6G_MB_LIB.T6G(SCH_1):PAGE106_I243@PURE_QUANTA.Q_RES(CHIPS)':
 'B': CDS_PINID='B';
NET_NAME
'I3C_SPD_DDRK_CPU0_SCL'
 '@T6G_MB_LIB.T6G(SCH_1):I3C_SPD_DDRK_CPU0_SCL':
 C_SIGNAL='@t6g_mb_lib.t6g(sch_1):i3c_spd_ddrk_cpu0_scl';
NODE_NAME     J20 4
 '@T6G_MB_LIB.T6G(SCH_1):PAGE95_I22@PURE_QUANTA.SCONN288_DDR506112002KQ(CHIPS)':
 'HSCL': CDS_PINID='HSCL';
NODE_NAME     R1578 2
 '@T6G_MB_LIB.T6G(SCH_1):PAGE95_I242@PURE_QUANTA.Q_RES(CHIPS)':
 'B': CDS_PINID='B';
NET_NAME
'I3C_SPD_DDRK_CPU0_SDA'
 '@T6G_MB_LIB.T6G(SCH_1):I3C_SPD_DDRK_CPU0_SDA':
 C_SIGNAL='@t6g_mb_lib.t6g(sch_1):i3c_spd_ddrk_cpu0_sda';
NODE_NAME     J20 5
 '@T6G_MB_LIB.T6G(SCH_1):PAGE95_I22@PURE_QUANTA.SCONN288_DDR506112002KQ(CHIPS)':
 'HSDA': CDS_PINID='HSDA';
NODE_NAME     R1685 2
 '@T6G_MB_LIB.T6G(SCH_1):PAGE95_I243@PURE_QUANTA.Q_RES(CHIPS)':
 'B': CDS_PINID='B';
NET_NAME
'I3C_SPD_DDRK_CPU1_SCL'
 '@T6G_MB_LIB.T6G(SCH_1):I3C_SPD_DDRK_CPU1_SCL':
 C_SIGNAL='@t6g_mb_lib.t6g(sch_1):i3c_spd_ddrk_cpu1_scl';
NODE_NAME     J99 4
 '@T6G_MB_LIB.T6G(SCH_1):PAGE107_I22@PURE_QUANTA.SCONN288_DDR506112002KQ(CHIPS)':
 'HSCL': CDS_PINID='HSCL';
NODE_NAME     R1590 2
 '@T6G_MB_LIB.T6G(SCH_1):PAGE107_I241@PURE_QUANTA.Q_RES(CHIPS)':
 'B': CDS_PINID='B';
NET_NAME
'I3C_SPD_DDRK_CPU1_SDA'
 '@T6G_MB_LIB.T6G(SCH_1):I3C_SPD_DDRK_CPU1_SDA':
 C_SIGNAL='@t6g_mb_lib.t6g(sch_1):i3c_spd_ddrk_cpu1_sda';
NODE_NAME     J99 5
 '@T6G_MB_LIB.T6G(SCH_1):PAGE107_I22@PURE_QUANTA.SCONN288_DDR506112002KQ(CHIPS)':
 'HSDA': CDS_PINID='HSDA';
NODE_NAME     R1710 2
 '@T6G_MB_LIB.T6G(SCH_1):PAGE107_I242@PURE_QUANTA.Q_RES(CHIPS)':
 'B': CDS_PINID='B';
NET_NAME
'I3C_SPD_DDRL_CPU0_SCL'
 '@T6G_MB_LIB.T6G(SCH_1):I3C_SPD_DDRL_CPU0_SCL':
 C_SIGNAL='@t6g_mb_lib.t6g(sch_1):i3c_spd_ddrl_cpu0_scl';
NODE_NAME     J67 4
 '@T6G_MB_LIB.T6G(SCH_1):PAGE96_I22@PURE_QUANTA.SCONN288_DDR506112002KQ(CHIPS)':
 'HSCL': CDS_PINID='HSCL';
NODE_NAME     R1579 2
 '@T6G_MB_LIB.T6G(SCH_1):PAGE96_I242@PURE_QUANTA.Q_RES(CHIPS)':
 'B': CDS_PINID='B';
NET_NAME
'I3C_SPD_DDRL_CPU0_SDA'
 '@T6G_MB_LIB.T6G(SCH_1):I3C_SPD_DDRL_CPU0_SDA':
 C_SIGNAL='@t6g_mb_lib.t6g(sch_1):i3c_spd_ddrl_cpu0_sda';
NODE_NAME     J67 5
 '@T6G_MB_LIB.T6G(SCH_1):PAGE96_I22@PURE_QUANTA.SCONN288_DDR506112002KQ(CHIPS)':
 'HSDA': CDS_PINID='HSDA';
NODE_NAME     R1686 2
 '@T6G_MB_LIB.T6G(SCH_1):PAGE96_I243@PURE_QUANTA.Q_RES(CHIPS)':
 'B': CDS_PINID='B';
NET_NAME
'I3C_SPD_DDRL_CPU1_SCL'
 '@T6G_MB_LIB.T6G(SCH_1):I3C_SPD_DDRL_CPU1_SCL':
 C_SIGNAL='@t6g_mb_lib.t6g(sch_1):i3c_spd_ddrl_cpu1_scl';
NODE_NAME     J37 4
 '@T6G_MB_LIB.T6G(SCH_1):PAGE108_I22@PURE_QUANTA.SCONN288_DDR506112002KQ(CHIPS)':
 'HSCL': CDS_PINID='HSCL';
NODE_NAME     R1591 2
 '@T6G_MB_LIB.T6G(SCH_1):PAGE108_I241@PURE_QUANTA.Q_RES(CHIPS)':
 'B': CDS_PINID='B';
NET_NAME
'I3C_SPD_DDRL_CPU1_SDA'
 '@T6G_MB_LIB.T6G(SCH_1):I3C_SPD_DDRL_CPU1_SDA':
 C_SIGNAL='@t6g_mb_lib.t6g(sch_1):i3c_spd_ddrl_cpu1_sda';
NODE_NAME     J37 5
 '@T6G_MB_LIB.T6G(SCH_1):PAGE108_I22@PURE_QUANTA.SCONN288_DDR506112002KQ(CHIPS)':
 'HSDA': CDS_PINID='HSDA';
NODE_NAME     R1711 2
 '@T6G_MB_LIB.T6G(SCH_1):PAGE108_I242@PURE_QUANTA.Q_RES(CHIPS)':
 'B': CDS_PINID='B';
NET_NAME
'INA230_1_A0'
 '@T6G_MB_LIB.T6G(SCH_1):INA230_1_A0':
 C_SIGNAL='@t6g_mb_lib.t6g(sch_1):ina230_1_a0';
NODE_NAME     U266 2
 '@T6G_MB_LIB.T6G(SCH_1):PAGE295_I30@PURE_QUANTA.ISL28022FRZT(CHIPS)':
 'A0': CDS_PINID='A0';
NODE_NAME     R3617 2
 '@T6G_MB_LIB.T6G(SCH_1):PAGE295_I40@PURE_QUANTA.Q_RES(CHIPS)':
 'B': CDS_PINID='B';
NODE_NAME     R3627 2
 '@T6G_MB_LIB.T6G(SCH_1):PAGE295_I89@PURE_QUANTA.Q_RES(CHIPS)':
 'B': CDS_PINID='B';
NET_NAME
'INA230_1_A1'
 '@T6G_MB_LIB.T6G(SCH_1):INA230_1_A1':
 C_SIGNAL='@t6g_mb_lib.t6g(sch_1):ina230_1_a1';
NODE_NAME     U266 1
 '@T6G_MB_LIB.T6G(SCH_1):PAGE295_I30@PURE_QUANTA.ISL28022FRZT(CHIPS)':
 'A1': CDS_PINID='A1';
NODE_NAME     R3616 2
 '@T6G_MB_LIB.T6G(SCH_1):PAGE295_I31@PURE_QUANTA.Q_RES(CHIPS)':
 'B': CDS_PINID='B';
NODE_NAME     R3628 2
 '@T6G_MB_LIB.T6G(SCH_1):PAGE295_I88@PURE_QUANTA.Q_RES(CHIPS)':
 'B': CDS_PINID='B';
NET_NAME
'INA230_2_A0'
 '@T6G_MB_LIB.T6G(SCH_1):INA230_2_A0':
 C_SIGNAL='@t6g_mb_lib.t6g(sch_1):ina230_2_a0';
NODE_NAME     U276 2
 '@T6G_MB_LIB.T6G(SCH_1):PAGE295_I129@PURE_QUANTA.ISL28022FRZT(CHIPS)':
 'A0': CDS_PINID='A0';
NODE_NAME     R3764 2
 '@T6G_MB_LIB.T6G(SCH_1):PAGE295_I135@PURE_QUANTA.Q_RES(CHIPS)':
 'B': CDS_PINID='B';
NODE_NAME     R3751 1
 '@T6G_MB_LIB.T6G(SCH_1):PAGE295_I146@PURE_QUANTA.Q_RES(CHIPS)':
 'A': CDS_PINID='A';
NET_NAME
'INA230_2_A1'
 '@T6G_MB_LIB.T6G(SCH_1):INA230_2_A1':
 C_SIGNAL='@t6g_mb_lib.t6g(sch_1):ina230_2_a1';
NODE_NAME     U276 1
 '@T6G_MB_LIB.T6G(SCH_1):PAGE295_I129@PURE_QUANTA.ISL28022FRZT(CHIPS)':
 'A1': CDS_PINID='A1';
NODE_NAME     R3763 2
 '@T6G_MB_LIB.T6G(SCH_1):PAGE295_I136@PURE_QUANTA.Q_RES(CHIPS)':
 'B': CDS_PINID='B';
NET_NAME
'INA230_3_A0'
 '@T6G_MB_LIB.T6G(SCH_1):INA230_3_A0':
 C_SIGNAL='@t6g_mb_lib.t6g(sch_1):ina230_3_a0';
NODE_NAME     U263 2
 '@T6G_MB_LIB.T6G(SCH_1):PAGE360_I94@PURE_QUANTA.ISL28022FRZT(CHIPS)':
 'A0': CDS_PINID='A0';
NODE_NAME     R3620 1
 '@T6G_MB_LIB.T6G(SCH_1):PAGE360_I100@PURE_QUANTA.Q_RES(CHIPS)':
 'A': CDS_PINID='A';
NODE_NAME     R3609 2
 '@T6G_MB_LIB.T6G(SCH_1):PAGE360_I104@PURE_QUANTA.Q_RES(CHIPS)':
 'B': CDS_PINID='B';
NET_NAME
'INA230_3_A1'
 '@T6G_MB_LIB.T6G(SCH_1):INA230_3_A1':
 C_SIGNAL='@t6g_mb_lib.t6g(sch_1):ina230_3_a1';
NODE_NAME     U263 1
 '@T6G_MB_LIB.T6G(SCH_1):PAGE360_I94@PURE_QUANTA.ISL28022FRZT(CHIPS)':
 'A1': CDS_PINID='A1';
NODE_NAME     R3608 2
 '@T6G_MB_LIB.T6G(SCH_1):PAGE360_I103@PURE_QUANTA.Q_RES(CHIPS)':
 'B': CDS_PINID='B';
NET_NAME
'INA230_4_A0'
 '@T6G_MB_LIB.T6G(SCH_1):INA230_4_A0':
 C_SIGNAL='@t6g_mb_lib.t6g(sch_1):ina230_4_a0';
NODE_NAME     R3611 2
 '@T6G_MB_LIB.T6G(SCH_1):PAGE360_I36@PURE_QUANTA.Q_RES(CHIPS)':
 'B': CDS_PINID='B';
NODE_NAME     U264 2
 '@T6G_MB_LIB.T6G(SCH_1):PAGE360_I46@PURE_QUANTA.ISL28022FRZT(CHIPS)':
 'A0': CDS_PINID='A0';
NODE_NAME     R3621 2
 '@T6G_MB_LIB.T6G(SCH_1):PAGE360_I87@PURE_QUANTA.Q_RES(CHIPS)':
 'B': CDS_PINID='B';
NET_NAME
'INA230_4_A1'
 '@T6G_MB_LIB.T6G(SCH_1):INA230_4_A1':
 C_SIGNAL='@t6g_mb_lib.t6g(sch_1):ina230_4_a1';
NODE_NAME     R3610 2
 '@T6G_MB_LIB.T6G(SCH_1):PAGE360_I45@PURE_QUANTA.Q_RES(CHIPS)':
 'B': CDS_PINID='B';
NODE_NAME     U264 1
 '@T6G_MB_LIB.T6G(SCH_1):PAGE360_I46@PURE_QUANTA.ISL28022FRZT(CHIPS)':
 'A1': CDS_PINID='A1';
NODE_NAME     R3623 2
 '@T6G_MB_LIB.T6G(SCH_1):PAGE360_I86@PURE_QUANTA.Q_RES(CHIPS)':
 'B': CDS_PINID='B';
NET_NAME
'INA230_5_A0'
 '@T6G_MB_LIB.T6G(SCH_1):INA230_5_A0':
 C_SIGNAL='@t6g_mb_lib.t6g(sch_1):ina230_5_a0';
NODE_NAME     R3613 2
 '@T6G_MB_LIB.T6G(SCH_1):PAGE360_I59@PURE_QUANTA.Q_RES(CHIPS)':
 'B': CDS_PINID='B';
NODE_NAME     U265 2
 '@T6G_MB_LIB.T6G(SCH_1):PAGE360_I69@PURE_QUANTA.ISL28022FRZT(CHIPS)':
 'A0': CDS_PINID='A0';
NODE_NAME     R3622 2
 '@T6G_MB_LIB.T6G(SCH_1):PAGE360_I90@PURE_QUANTA.Q_RES(CHIPS)':
 'B': CDS_PINID='B';
NET_NAME
'INA230_5_A1'
 '@T6G_MB_LIB.T6G(SCH_1):INA230_5_A1':
 C_SIGNAL='@t6g_mb_lib.t6g(sch_1):ina230_5_a1';
NODE_NAME     R3612 2
 '@T6G_MB_LIB.T6G(SCH_1):PAGE360_I68@PURE_QUANTA.Q_RES(CHIPS)':
 'B': CDS_PINID='B';
NODE_NAME     U265 1
 '@T6G_MB_LIB.T6G(SCH_1):PAGE360_I69@PURE_QUANTA.ISL28022FRZT(CHIPS)':
 'A1': CDS_PINID='A1';
NODE_NAME     R3624 2
 '@T6G_MB_LIB.T6G(SCH_1):PAGE360_I89@PURE_QUANTA.Q_RES(CHIPS)':
 'B': CDS_PINID='B';
NET_NAME
'INA230_6_A0'
 '@T6G_MB_LIB.T6G(SCH_1):INA230_6_A0':
 C_SIGNAL='@t6g_mb_lib.t6g(sch_1):ina230_6_a0';
NODE_NAME     R1309 2
 '@T6G_MB_LIB.T6G(SCH_1):PAGE466_I13@PURE_QUANTA.Q_RES(CHIPS)':
 'B': CDS_PINID='B';
NODE_NAME     U55 2
 '@T6G_MB_LIB.T6G(SCH_1):PAGE466_I28@PURE_QUANTA.ISL28022FRZT(CHIPS)':
 'A0': CDS_PINID='A0';
NODE_NAME     R1355 1
 '@T6G_MB_LIB.T6G(SCH_1):PAGE466_I92@PURE_QUANTA.Q_RES(CHIPS)':
 'A': CDS_PINID='A';
NET_NAME
'INA230_6_A1'
 '@T6G_MB_LIB.T6G(SCH_1):INA230_6_A1':
 C_SIGNAL='@t6g_mb_lib.t6g(sch_1):ina230_6_a1';
NODE_NAME     R1306 2
 '@T6G_MB_LIB.T6G(SCH_1):PAGE466_I12@PURE_QUANTA.Q_RES(CHIPS)':
 'B': CDS_PINID='B';
NODE_NAME     R1320 2
 '@T6G_MB_LIB.T6G(SCH_1):PAGE466_I17@PURE_QUANTA.Q_RES(CHIPS)':
 'B': CDS_PINID='B';
NODE_NAME     U55 1
 '@T6G_MB_LIB.T6G(SCH_1):PAGE466_I28@PURE_QUANTA.ISL28022FRZT(CHIPS)':
 'A1': CDS_PINID='A1';
NET_NAME
'INA230_7_A0'
 '@T6G_MB_LIB.T6G(SCH_1):INA230_7_A0':
 C_SIGNAL='@t6g_mb_lib.t6g(sch_1):ina230_7_a0';
NODE_NAME     U56 2
 '@T6G_MB_LIB.T6G(SCH_1):PAGE466_I29@PURE_QUANTA.ISL28022FRZT(CHIPS)':
 'A0': CDS_PINID='A0';
NODE_NAME     R1310 2
 '@T6G_MB_LIB.T6G(SCH_1):PAGE466_I45@PURE_QUANTA.Q_RES(CHIPS)':
 'B': CDS_PINID='B';
NODE_NAME     R1360 1
 '@T6G_MB_LIB.T6G(SCH_1):PAGE466_I93@PURE_QUANTA.Q_RES(CHIPS)':
 'A': CDS_PINID='A';
NET_NAME
'INA230_7_A1'
 '@T6G_MB_LIB.T6G(SCH_1):INA230_7_A1':
 C_SIGNAL='@t6g_mb_lib.t6g(sch_1):ina230_7_a1';
NODE_NAME     U56 1
 '@T6G_MB_LIB.T6G(SCH_1):PAGE466_I29@PURE_QUANTA.ISL28022FRZT(CHIPS)':
 'A1': CDS_PINID='A1';
NODE_NAME     R1322 2
 '@T6G_MB_LIB.T6G(SCH_1):PAGE466_I39@PURE_QUANTA.Q_RES(CHIPS)':
 'B': CDS_PINID='B';
NODE_NAME     R1307 2
 '@T6G_MB_LIB.T6G(SCH_1):PAGE466_I44@PURE_QUANTA.Q_RES(CHIPS)':
 'B': CDS_PINID='B';
NET_NAME
'INA230_8_A0'
 '@T6G_MB_LIB.T6G(SCH_1):INA230_8_A0':
 C_SIGNAL='@t6g_mb_lib.t6g(sch_1):ina230_8_a0';
NODE_NAME     U52 2
 '@T6G_MB_LIB.T6G(SCH_1):PAGE466_I57@PURE_QUANTA.ISL28022FRZT(CHIPS)':
 'A0': CDS_PINID='A0';
NODE_NAME     R1308 2
 '@T6G_MB_LIB.T6G(SCH_1):PAGE466_I96@PURE_QUANTA.Q_RES(CHIPS)':
 'B': CDS_PINID='B';
NET_NAME
'INA230_8_A1'
 '@T6G_MB_LIB.T6G(SCH_1):INA230_8_A1':
 C_SIGNAL='@t6g_mb_lib.t6g(sch_1):ina230_8_a1';
NODE_NAME     U52 1
 '@T6G_MB_LIB.T6G(SCH_1):PAGE466_I57@PURE_QUANTA.ISL28022FRZT(CHIPS)':
 'A1': CDS_PINID='A1';
NODE_NAME     R1305 2
 '@T6G_MB_LIB.T6G(SCH_1):PAGE466_I72@PURE_QUANTA.Q_RES(CHIPS)':
 'B': CDS_PINID='B';
NODE_NAME     R1350 1
 '@T6G_MB_LIB.T6G(SCH_1):PAGE466_I94@PURE_QUANTA.Q_RES(CHIPS)':
 'A': CDS_PINID='A';
NODE_NAME     R1317 2
 '@T6G_MB_LIB.T6G(SCH_1):PAGE466_I95@PURE_QUANTA.Q_RES(CHIPS)':
 'B': CDS_PINID='B';
NET_NAME
'IND_CPU0_P0_CPL0'
 '@T6G_MB_LIB.T6G(SCH_1):IND_CPU0_P0_CPL0':
 C_SIGNAL='@t6g_mb_lib.t6g(sch_1):ind_cpu0_p0_cpl0';
NODE_NAME     PL50 2
 '@T6G_MB_LIB.T6G(SCH_1):PAGE171_I51@PURE_QUANTA.Q_INDUCTOR(CHIPS)':
 '2': CDS_PINID='\2\';
NODE_NAME     PL70 2
 '@T6G_MB_LIB.T6G(SCH_1):PAGE171_I52@PURE_QUANTA.Q_INDUCTOR4P_14(CHIPS)':
 '2': CDS_PINID='\2\';
NET_NAME
'IND_CPU0_P0_CPL1'
 '@T6G_MB_LIB.T6G(SCH_1):IND_CPU0_P0_CPL1':
 C_SIGNAL='@t6g_mb_lib.t6g(sch_1):ind_cpu0_p0_cpl1';
NODE_NAME     PL52 2
 '@T6G_MB_LIB.T6G(SCH_1):PAGE169_I62@PURE_QUANTA.Q_INDUCTOR4P_14(CHIPS)':
 '2': CDS_PINID='\2\';
NODE_NAME     PL51 3
 '@T6G_MB_LIB.T6G(SCH_1):PAGE169_I77@PURE_QUANTA.Q_INDUCTOR4P_14(CHIPS)':
 '3': CDS_PINID='\3\';
NET_NAME
'IND_CPU0_P0_CPL2'
 '@T6G_MB_LIB.T6G(SCH_1):IND_CPU0_P0_CPL2':
 C_SIGNAL='@t6g_mb_lib.t6g(sch_1):ind_cpu0_p0_cpl2';
NODE_NAME     PL52 3
 '@T6G_MB_LIB.T6G(SCH_1):PAGE169_I62@PURE_QUANTA.Q_INDUCTOR4P_14(CHIPS)':
 '3': CDS_PINID='\3\';
NODE_NAME     PL59 2
 '@T6G_MB_LIB.T6G(SCH_1):PAGE170_I64@PURE_QUANTA.Q_INDUCTOR4P_14(CHIPS)':
 '2': CDS_PINID='\2\';
NET_NAME
'IND_CPU0_P0_CPL3'
 '@T6G_MB_LIB.T6G(SCH_1):IND_CPU0_P0_CPL3':
 C_SIGNAL='@t6g_mb_lib.t6g(sch_1):ind_cpu0_p0_cpl3';
NODE_NAME     PL60 2
 '@T6G_MB_LIB.T6G(SCH_1):PAGE170_I52@PURE_QUANTA.Q_INDUCTOR4P_14(CHIPS)':
 '2': CDS_PINID='\2\';
NODE_NAME     PL59 3
 '@T6G_MB_LIB.T6G(SCH_1):PAGE170_I64@PURE_QUANTA.Q_INDUCTOR4P_14(CHIPS)':
 '3': CDS_PINID='\3\';
NET_NAME
'IND_CPU0_P0_CPL5'
 '@T6G_MB_LIB.T6G(SCH_1):IND_CPU0_P0_CPL5':
 C_SIGNAL='@t6g_mb_lib.t6g(sch_1):ind_cpu0_p0_cpl5';
NODE_NAME     PL51 2
 '@T6G_MB_LIB.T6G(SCH_1):PAGE169_I77@PURE_QUANTA.Q_INDUCTOR4P_14(CHIPS)':
 '2': CDS_PINID='\2\';
NODE_NAME     PL61 3
 '@T6G_MB_LIB.T6G(SCH_1):PAGE171_I64@PURE_QUANTA.Q_INDUCTOR4P_14(CHIPS)':
 '3': CDS_PINID='\3\';
NET_NAME
'IND_CPU0_P0_CPL6'
 '@T6G_MB_LIB.T6G(SCH_1):IND_CPU0_P0_CPL6':
 C_SIGNAL='@t6g_mb_lib.t6g(sch_1):ind_cpu0_p0_cpl6';
NODE_NAME     PL70 3
 '@T6G_MB_LIB.T6G(SCH_1):PAGE171_I52@PURE_QUANTA.Q_INDUCTOR4P_14(CHIPS)':
 '3': CDS_PINID='\3\';
NODE_NAME     PL61 2
 '@T6G_MB_LIB.T6G(SCH_1):PAGE171_I64@PURE_QUANTA.Q_INDUCTOR4P_14(CHIPS)':
 '2': CDS_PINID='\2\';
NET_NAME
'IND_CPU0_P1_CPL0'
 '@T6G_MB_LIB.T6G(SCH_1):IND_CPU0_P1_CPL0':
 C_SIGNAL='@t6g_mb_lib.t6g(sch_1):ind_cpu0_p1_cpl0';
NODE_NAME     PL27 2
 '@T6G_MB_LIB.T6G(SCH_1):PAGE188_I51@PURE_QUANTA.Q_INDUCTOR(CHIPS)':
 '2': CDS_PINID='\2\';
NODE_NAME     PL8 2
 '@T6G_MB_LIB.T6G(SCH_1):PAGE188_I53@PURE_QUANTA.Q_INDUCTOR4P_14(CHIPS)':
 '2': CDS_PINID='\2\';
NET_NAME
'IND_CPU0_P1_CPL1'
 '@T6G_MB_LIB.T6G(SCH_1):IND_CPU0_P1_CPL1':
 C_SIGNAL='@t6g_mb_lib.t6g(sch_1):ind_cpu0_p1_cpl1';
NODE_NAME     PL29 2
 '@T6G_MB_LIB.T6G(SCH_1):PAGE186_I56@PURE_QUANTA.Q_INDUCTOR4P_14(CHIPS)':
 '2': CDS_PINID='\2\';
NODE_NAME     PL28 3
 '@T6G_MB_LIB.T6G(SCH_1):PAGE186_I90@PURE_QUANTA.Q_INDUCTOR4P_14(CHIPS)':
 '3': CDS_PINID='\3\';
NET_NAME
'IND_CPU0_P1_CPL2'
 '@T6G_MB_LIB.T6G(SCH_1):IND_CPU0_P1_CPL2':
 C_SIGNAL='@t6g_mb_lib.t6g(sch_1):ind_cpu0_p1_cpl2';
NODE_NAME     PL29 3
 '@T6G_MB_LIB.T6G(SCH_1):PAGE186_I56@PURE_QUANTA.Q_INDUCTOR4P_14(CHIPS)':
 '3': CDS_PINID='\3\';
NODE_NAME     PL31 2
 '@T6G_MB_LIB.T6G(SCH_1):PAGE187_I67@PURE_QUANTA.Q_INDUCTOR4P_14(CHIPS)':
 '2': CDS_PINID='\2\';
NET_NAME
'IND_CPU0_P1_CPL3'
 '@T6G_MB_LIB.T6G(SCH_1):IND_CPU0_P1_CPL3':
 C_SIGNAL='@t6g_mb_lib.t6g(sch_1):ind_cpu0_p1_cpl3';
NODE_NAME     PL32 2
 '@T6G_MB_LIB.T6G(SCH_1):PAGE187_I53@PURE_QUANTA.Q_INDUCTOR4P_14(CHIPS)':
 '2': CDS_PINID='\2\';
NODE_NAME     PL31 3
 '@T6G_MB_LIB.T6G(SCH_1):PAGE187_I67@PURE_QUANTA.Q_INDUCTOR4P_14(CHIPS)':
 '3': CDS_PINID='\3\';
NET_NAME
'IND_CPU0_P1_CPL5'
 '@T6G_MB_LIB.T6G(SCH_1):IND_CPU0_P1_CPL5':
 C_SIGNAL='@t6g_mb_lib.t6g(sch_1):ind_cpu0_p1_cpl5';
NODE_NAME     PL28 2
 '@T6G_MB_LIB.T6G(SCH_1):PAGE186_I90@PURE_QUANTA.Q_INDUCTOR4P_14(CHIPS)':
 '2': CDS_PINID='\2\';
NODE_NAME     PL33 3
 '@T6G_MB_LIB.T6G(SCH_1):PAGE188_I64@PURE_QUANTA.Q_INDUCTOR4P_14(CHIPS)':
 '3': CDS_PINID='\3\';
NET_NAME
'IND_CPU0_P1_CPL6'
 '@T6G_MB_LIB.T6G(SCH_1):IND_CPU0_P1_CPL6':
 C_SIGNAL='@t6g_mb_lib.t6g(sch_1):ind_cpu0_p1_cpl6';
NODE_NAME     PL8 3
 '@T6G_MB_LIB.T6G(SCH_1):PAGE188_I53@PURE_QUANTA.Q_INDUCTOR4P_14(CHIPS)':
 '3': CDS_PINID='\3\';
NODE_NAME     PL33 2
 '@T6G_MB_LIB.T6G(SCH_1):PAGE188_I64@PURE_QUANTA.Q_INDUCTOR4P_14(CHIPS)':
 '2': CDS_PINID='\2\';
NET_NAME
'IND_CPU1_P0_CPL0'
 '@T6G_MB_LIB.T6G(SCH_1):IND_CPU1_P0_CPL0':
 C_SIGNAL='@t6g_mb_lib.t6g(sch_1):ind_cpu1_p0_cpl0';
NODE_NAME     PL9 1
 '@T6G_MB_LIB.T6G(SCH_1):PAGE178_I36@PURE_QUANTA.Q_INDUCTOR(CHIPS)':
 '1': CDS_PINID='\1\';
NODE_NAME     PL7 2
 '@T6G_MB_LIB.T6G(SCH_1):PAGE178_I38@PURE_QUANTA.Q_INDUCTOR4P_14(CHIPS)':
 '2': CDS_PINID='\2\';
NET_NAME
'IND_CPU1_P0_CPL1'
 '@T6G_MB_LIB.T6G(SCH_1):IND_CPU1_P0_CPL1':
 C_SIGNAL='@t6g_mb_lib.t6g(sch_1):ind_cpu1_p0_cpl1';
NODE_NAME     PL11 2
 '@T6G_MB_LIB.T6G(SCH_1):PAGE176_I46@PURE_QUANTA.Q_INDUCTOR4P_14(CHIPS)':
 '2': CDS_PINID='\2\';
NODE_NAME     PL10 3
 '@T6G_MB_LIB.T6G(SCH_1):PAGE176_I62@PURE_QUANTA.Q_INDUCTOR4P_14(CHIPS)':
 '3': CDS_PINID='\3\';
NET_NAME
'IND_CPU1_P0_CPL2'
 '@T6G_MB_LIB.T6G(SCH_1):IND_CPU1_P0_CPL2':
 C_SIGNAL='@t6g_mb_lib.t6g(sch_1):ind_cpu1_p0_cpl2';
NODE_NAME     PL11 3
 '@T6G_MB_LIB.T6G(SCH_1):PAGE176_I46@PURE_QUANTA.Q_INDUCTOR4P_14(CHIPS)':
 '3': CDS_PINID='\3\';
NODE_NAME     PL14 2
 '@T6G_MB_LIB.T6G(SCH_1):PAGE177_I64@PURE_QUANTA.Q_INDUCTOR4P_14(CHIPS)':
 '2': CDS_PINID='\2\';
NET_NAME
'IND_CPU1_P0_CPL3'
 '@T6G_MB_LIB.T6G(SCH_1):IND_CPU1_P0_CPL3':
 C_SIGNAL='@t6g_mb_lib.t6g(sch_1):ind_cpu1_p0_cpl3';
NODE_NAME     PL13 2
 '@T6G_MB_LIB.T6G(SCH_1):PAGE177_I42@PURE_QUANTA.Q_INDUCTOR4P_14(CHIPS)':
 '2': CDS_PINID='\2\';
NODE_NAME     PL14 3
 '@T6G_MB_LIB.T6G(SCH_1):PAGE177_I64@PURE_QUANTA.Q_INDUCTOR4P_14(CHIPS)':
 '3': CDS_PINID='\3\';
NET_NAME
'IND_CPU1_P0_CPL5'
 '@T6G_MB_LIB.T6G(SCH_1):IND_CPU1_P0_CPL5':
 C_SIGNAL='@t6g_mb_lib.t6g(sch_1):ind_cpu1_p0_cpl5';
NODE_NAME     PL10 2
 '@T6G_MB_LIB.T6G(SCH_1):PAGE176_I62@PURE_QUANTA.Q_INDUCTOR4P_14(CHIPS)':
 '2': CDS_PINID='\2\';
NODE_NAME     PL15 3
 '@T6G_MB_LIB.T6G(SCH_1):PAGE178_I63@PURE_QUANTA.Q_INDUCTOR4P_14(CHIPS)':
 '3': CDS_PINID='\3\';
NET_NAME
'IND_CPU1_P0_CPL6'
 '@T6G_MB_LIB.T6G(SCH_1):IND_CPU1_P0_CPL6':
 C_SIGNAL='@t6g_mb_lib.t6g(sch_1):ind_cpu1_p0_cpl6';
NODE_NAME     PL7 3
 '@T6G_MB_LIB.T6G(SCH_1):PAGE178_I38@PURE_QUANTA.Q_INDUCTOR4P_14(CHIPS)':
 '3': CDS_PINID='\3\';
NODE_NAME     PL15 2
 '@T6G_MB_LIB.T6G(SCH_1):PAGE178_I63@PURE_QUANTA.Q_INDUCTOR4P_14(CHIPS)':
 '2': CDS_PINID='\2\';
NET_NAME
'IND_CPU1_P1_CPL0'
 '@T6G_MB_LIB.T6G(SCH_1):IND_CPU1_P1_CPL0':
 C_SIGNAL='@t6g_mb_lib.t6g(sch_1):ind_cpu1_p1_cpl0';
NODE_NAME     PL39 1
 '@T6G_MB_LIB.T6G(SCH_1):PAGE195_I37@PURE_QUANTA.Q_INDUCTOR(CHIPS)':
 '1': CDS_PINID='\1\';
NODE_NAME     PL69 2
 '@T6G_MB_LIB.T6G(SCH_1):PAGE195_I50@PURE_QUANTA.Q_INDUCTOR4P_14(CHIPS)':
 '2': CDS_PINID='\2\';
NET_NAME
'IND_CPU1_P1_CPL1'
 '@T6G_MB_LIB.T6G(SCH_1):IND_CPU1_P1_CPL1':
 C_SIGNAL='@t6g_mb_lib.t6g(sch_1):ind_cpu1_p1_cpl1';
NODE_NAME     PL41 2
 '@T6G_MB_LIB.T6G(SCH_1):PAGE193_I62@PURE_QUANTA.Q_INDUCTOR4P_14(CHIPS)':
 '2': CDS_PINID='\2\';
NODE_NAME     PL40 3
 '@T6G_MB_LIB.T6G(SCH_1):PAGE193_I77@PURE_QUANTA.Q_INDUCTOR4P_14(CHIPS)':
 '3': CDS_PINID='\3\';
NET_NAME
'IND_CPU1_P1_CPL2'
 '@T6G_MB_LIB.T6G(SCH_1):IND_CPU1_P1_CPL2':
 C_SIGNAL='@t6g_mb_lib.t6g(sch_1):ind_cpu1_p1_cpl2';
NODE_NAME     PL41 3
 '@T6G_MB_LIB.T6G(SCH_1):PAGE193_I62@PURE_QUANTA.Q_INDUCTOR4P_14(CHIPS)':
 '3': CDS_PINID='\3\';
NODE_NAME     PL44 2
 '@T6G_MB_LIB.T6G(SCH_1):PAGE194_I62@PURE_QUANTA.Q_INDUCTOR4P_14(CHIPS)':
 '2': CDS_PINID='\2\';
NET_NAME
'IND_CPU1_P1_CPL3'
 '@T6G_MB_LIB.T6G(SCH_1):IND_CPU1_P1_CPL3':
 C_SIGNAL='@t6g_mb_lib.t6g(sch_1):ind_cpu1_p1_cpl3';
NODE_NAME     PL43 2
 '@T6G_MB_LIB.T6G(SCH_1):PAGE194_I50@PURE_QUANTA.Q_INDUCTOR4P_14(CHIPS)':
 '2': CDS_PINID='\2\';
NODE_NAME     PL44 3
 '@T6G_MB_LIB.T6G(SCH_1):PAGE194_I62@PURE_QUANTA.Q_INDUCTOR4P_14(CHIPS)':
 '3': CDS_PINID='\3\';
NET_NAME
'IND_CPU1_P1_CPL5'
 '@T6G_MB_LIB.T6G(SCH_1):IND_CPU1_P1_CPL5':
 C_SIGNAL='@t6g_mb_lib.t6g(sch_1):ind_cpu1_p1_cpl5';
NODE_NAME     PL40 2
 '@T6G_MB_LIB.T6G(SCH_1):PAGE193_I77@PURE_QUANTA.Q_INDUCTOR4P_14(CHIPS)':
 '2': CDS_PINID='\2\';
NODE_NAME     PL45 3
 '@T6G_MB_LIB.T6G(SCH_1):PAGE195_I63@PURE_QUANTA.Q_INDUCTOR4P_14(CHIPS)':
 '3': CDS_PINID='\3\';
NET_NAME
'IND_CPU1_P1_CPL6'
 '@T6G_MB_LIB.T6G(SCH_1):IND_CPU1_P1_CPL6':
 C_SIGNAL='@t6g_mb_lib.t6g(sch_1):ind_cpu1_p1_cpl6';
NODE_NAME     PL69 3
 '@T6G_MB_LIB.T6G(SCH_1):PAGE195_I50@PURE_QUANTA.Q_INDUCTOR4P_14(CHIPS)':
 '3': CDS_PINID='\3\';
NODE_NAME     PL45 2
 '@T6G_MB_LIB.T6G(SCH_1):PAGE195_I63@PURE_QUANTA.Q_INDUCTOR4P_14(CHIPS)':
 '2': CDS_PINID='\2\';
NET_NAME
'IND_PVDDIO_P0_CPL0'
 '@T6G_MB_LIB.T6G(SCH_1):IND_PVDDIO_P0_CPL0':
 C_SIGNAL='@t6g_mb_lib.t6g(sch_1):ind_pvddio_p0_cpl0';
NODE_NAME     PL20 2
 '@T6G_MB_LIB.T6G(SCH_1):PAGE181_I42@PURE_QUANTA.Q_INDUCTOR4P_14(CHIPS)':
 '2': CDS_PINID='\2\';
NODE_NAME     PL16 1
 '@T6G_MB_LIB.T6G(SCH_1):PAGE181_I43@PURE_QUANTA.Q_INDUCTOR(CHIPS)':
 '1': CDS_PINID='\1\';
NET_NAME
'IND_PVDDIO_P0_CPL2'
 '@T6G_MB_LIB.T6G(SCH_1):IND_PVDDIO_P0_CPL2':
 C_SIGNAL='@t6g_mb_lib.t6g(sch_1):ind_pvddio_p0_cpl2';
NODE_NAME     PL18 3
 '@T6G_MB_LIB.T6G(SCH_1):PAGE180_I40@PURE_QUANTA.Q_INDUCTOR4P_14(CHIPS)':
 '3': CDS_PINID='\3\';
NODE_NAME     PL17 2
 '@T6G_MB_LIB.T6G(SCH_1):PAGE180_I64@PURE_QUANTA.Q_INDUCTOR4P_14(CHIPS)':
 '2': CDS_PINID='\2\';
NET_NAME
'IND_PVDDIO_P0_CPL3'
 '@T6G_MB_LIB.T6G(SCH_1):IND_PVDDIO_P0_CPL3':
 C_SIGNAL='@t6g_mb_lib.t6g(sch_1):ind_pvddio_p0_cpl3';
NODE_NAME     PL18 2
 '@T6G_MB_LIB.T6G(SCH_1):PAGE180_I40@PURE_QUANTA.Q_INDUCTOR4P_14(CHIPS)':
 '2': CDS_PINID='\2\';
NODE_NAME     PL21 3
 '@T6G_MB_LIB.T6G(SCH_1):PAGE181_I61@PURE_QUANTA.Q_INDUCTOR4P_14(CHIPS)':
 '3': CDS_PINID='\3\';
NET_NAME
'IND_PVDDIO_P0_CPL4'
 '@T6G_MB_LIB.T6G(SCH_1):IND_PVDDIO_P0_CPL4':
 C_SIGNAL='@t6g_mb_lib.t6g(sch_1):ind_pvddio_p0_cpl4';
NODE_NAME     PL20 3
 '@T6G_MB_LIB.T6G(SCH_1):PAGE181_I42@PURE_QUANTA.Q_INDUCTOR4P_14(CHIPS)':
 '3': CDS_PINID='\3\';
NODE_NAME     PL21 2
 '@T6G_MB_LIB.T6G(SCH_1):PAGE181_I61@PURE_QUANTA.Q_INDUCTOR4P_14(CHIPS)':
 '2': CDS_PINID='\2\';
NET_NAME
'IND_PVDDIO_P1_CPL0'
 '@T6G_MB_LIB.T6G(SCH_1):IND_PVDDIO_P1_CPL0':
 C_SIGNAL='@t6g_mb_lib.t6g(sch_1):ind_pvddio_p1_cpl0';
NODE_NAME     PL67 2
 '@T6G_MB_LIB.T6G(SCH_1):PAGE198_I42@PURE_QUANTA.Q_INDUCTOR4P_14(CHIPS)':
 '2': CDS_PINID='\2\';
NODE_NAME     PL46 1
 '@T6G_MB_LIB.T6G(SCH_1):PAGE198_I43@PURE_QUANTA.Q_INDUCTOR(CHIPS)':
 '1': CDS_PINID='\1\';
NET_NAME
'IND_PVDDIO_P1_CPL2'
 '@T6G_MB_LIB.T6G(SCH_1):IND_PVDDIO_P1_CPL2':
 C_SIGNAL='@t6g_mb_lib.t6g(sch_1):ind_pvddio_p1_cpl2';
NODE_NAME     PL47 2
 '@T6G_MB_LIB.T6G(SCH_1):PAGE197_I71@PURE_QUANTA.Q_INDUCTOR4P_14(CHIPS)':
 '2': CDS_PINID='\2\';
NODE_NAME     PL48 3
 '@T6G_MB_LIB.T6G(SCH_1):PAGE197_I83@PURE_QUANTA.Q_INDUCTOR4P_14(CHIPS)':
 '3': CDS_PINID='\3\';
NET_NAME
'IND_PVDDIO_P1_CPL3'
 '@T6G_MB_LIB.T6G(SCH_1):IND_PVDDIO_P1_CPL3':
 C_SIGNAL='@t6g_mb_lib.t6g(sch_1):ind_pvddio_p1_cpl3';
NODE_NAME     PL48 2
 '@T6G_MB_LIB.T6G(SCH_1):PAGE197_I83@PURE_QUANTA.Q_INDUCTOR4P_14(CHIPS)':
 '2': CDS_PINID='\2\';
NODE_NAME     PL68 3
 '@T6G_MB_LIB.T6G(SCH_1):PAGE198_I62@PURE_QUANTA.Q_INDUCTOR4P_14(CHIPS)':
 '3': CDS_PINID='\3\';
NET_NAME
'IND_PVDDIO_P1_CPL4'
 '@T6G_MB_LIB.T6G(SCH_1):IND_PVDDIO_P1_CPL4':
 C_SIGNAL='@t6g_mb_lib.t6g(sch_1):ind_pvddio_p1_cpl4';
NODE_NAME     PL67 3
 '@T6G_MB_LIB.T6G(SCH_1):PAGE198_I42@PURE_QUANTA.Q_INDUCTOR4P_14(CHIPS)':
 '3': CDS_PINID='\3\';
NODE_NAME     PL68 2
 '@T6G_MB_LIB.T6G(SCH_1):PAGE198_I62@PURE_QUANTA.Q_INDUCTOR4P_14(CHIPS)':
 '2': CDS_PINID='\2\';
NET_NAME
'IND_SOC_P0_CPL0'
 '@T6G_MB_LIB.T6G(SCH_1):IND_SOC_P0_CPL0':
 C_SIGNAL='@t6g_mb_lib.t6g(sch_1):ind_soc_p0_cpl0';
NODE_NAME     PL66 2
 '@T6G_MB_LIB.T6G(SCH_1):PAGE174_I25@PURE_QUANTA.Q_INDUCTOR4P_14(CHIPS)':
 '2': CDS_PINID='\2\';
NODE_NAME     PL62 2
 '@T6G_MB_LIB.T6G(SCH_1):PAGE174_I24@PURE_QUANTA.Q_INDUCTOR(CHIPS)':
 '2': CDS_PINID='\2\';
NET_NAME
'IND_SOC_P0_CPL2'
 '@T6G_MB_LIB.T6G(SCH_1):IND_SOC_P0_CPL2':
 C_SIGNAL='@t6g_mb_lib.t6g(sch_1):ind_soc_p0_cpl2';
NODE_NAME     PL63 2
 '@T6G_MB_LIB.T6G(SCH_1):PAGE173_I69@PURE_QUANTA.Q_INDUCTOR4P_14(CHIPS)':
 '2': CDS_PINID='\2\';
NODE_NAME     PL64 3
 '@T6G_MB_LIB.T6G(SCH_1):PAGE173_I53@PURE_QUANTA.Q_INDUCTOR4P_14(CHIPS)':
 '3': CDS_PINID='\3\';
NET_NAME
'IND_SOC_P0_CPL3'
 '@T6G_MB_LIB.T6G(SCH_1):IND_SOC_P0_CPL3':
 C_SIGNAL='@t6g_mb_lib.t6g(sch_1):ind_soc_p0_cpl3';
NODE_NAME     PL66 3
 '@T6G_MB_LIB.T6G(SCH_1):PAGE174_I25@PURE_QUANTA.Q_INDUCTOR4P_14(CHIPS)':
 '3': CDS_PINID='\3\';
NODE_NAME     PL64 2
 '@T6G_MB_LIB.T6G(SCH_1):PAGE173_I53@PURE_QUANTA.Q_INDUCTOR4P_14(CHIPS)':
 '2': CDS_PINID='\2\';
NET_NAME
'IND_SOC_P1_CPL0'
 '@T6G_MB_LIB.T6G(SCH_1):IND_SOC_P1_CPL0':
 C_SIGNAL='@t6g_mb_lib.t6g(sch_1):ind_soc_p1_cpl0';
NODE_NAME     PL34 2
 '@T6G_MB_LIB.T6G(SCH_1):PAGE191_I25@PURE_QUANTA.Q_INDUCTOR(CHIPS)':
 '2': CDS_PINID='\2\';
NODE_NAME     PL38 2
 '@T6G_MB_LIB.T6G(SCH_1):PAGE191_I26@PURE_QUANTA.Q_INDUCTOR4P_14(CHIPS)':
 '2': CDS_PINID='\2\';
NET_NAME
'IND_SOC_P1_CPL2'
 '@T6G_MB_LIB.T6G(SCH_1):IND_SOC_P1_CPL2':
 C_SIGNAL='@t6g_mb_lib.t6g(sch_1):ind_soc_p1_cpl2';
NODE_NAME     PL36 3
 '@T6G_MB_LIB.T6G(SCH_1):PAGE190_I52@PURE_QUANTA.Q_INDUCTOR4P_14(CHIPS)':
 '3': CDS_PINID='\3\';
NODE_NAME     PL35 2
 '@T6G_MB_LIB.T6G(SCH_1):PAGE190_I69@PURE_QUANTA.Q_INDUCTOR4P_14(CHIPS)':
 '2': CDS_PINID='\2\';
NET_NAME
'IND_SOC_P1_CPL3'
 '@T6G_MB_LIB.T6G(SCH_1):IND_SOC_P1_CPL3':
 C_SIGNAL='@t6g_mb_lib.t6g(sch_1):ind_soc_p1_cpl3';
NODE_NAME     PL36 2
 '@T6G_MB_LIB.T6G(SCH_1):PAGE190_I52@PURE_QUANTA.Q_INDUCTOR4P_14(CHIPS)':
 '2': CDS_PINID='\2\';
NODE_NAME     PL38 3
 '@T6G_MB_LIB.T6G(SCH_1):PAGE191_I26@PURE_QUANTA.Q_INDUCTOR4P_14(CHIPS)':
 '3': CDS_PINID='\3\';
NET_NAME
'INT_CPU1_HP_UBM_N'
 '@T6G_MB_LIB.T6G(SCH_1):INT_CPU1_HP_UBM_N':
 C_SIGNAL='@t6g_mb_lib.t6g(sch_1):int_cpu1_hp_ubm_n';
NODE_NAME     U26 DJ35
 '@T6G_MB_LIB.T6G(SCH_1):PAGE55_I182@PURE_QUANTA.GENOA_SP5(CHIPS)':
 'GENINT_L||PM_INTR_L||UBM_CPRSNT_CHANGE_DET_L||AGPIO89': CDS_PINID='\genint_l||pm_intr_l||ubm_cprsnt_change_det_l||agpio89\';
NODE_NAME     R1424 2
 '@T6G_MB_LIB.T6G(SCH_1):PAGE55_I292@PURE_QUANTA.Q_RES(CHIPS)':
 'B': CDS_PINID='B';
NET_NAME
'IRQ0_A56'
 '@T6G_MB_LIB.T6G(SCH_1):IRQ0_A56':
 C_SIGNAL='@t6g_mb_lib.t6g(sch_1):irq0_a56';
NODE_NAME     R321 2
 '@T6G_MB_LIB.T6G(SCH_1):PAGE348_I24@PURE_QUANTA.Q_RES(CHIPS)':
 'B': CDS_PINID='B';
NODE_NAME     J41 A56
 '@T6G_MB_LIB.T6G(SCH_1):PAGE348_I176@PURE_QUANTA.SCONN168_ME1016810202011(CHIPS)':
 'PERN12': CDS_PINID='PERN12';
NET_NAME
'IRQ_BMC_SMI_N'
 '@T6G_MB_LIB.T6G(SCH_1):IRQ_BMC_SMI_N':
 C_SIGNAL='@t6g_mb_lib.t6g(sch_1):irq_bmc_smi_n';
NODE_NAME     R244 1
 '@T6G_MB_LIB.T6G(SCH_1):PAGE81_I72@PURE_QUANTA.Q_RES(CHIPS)':
 'A': CDS_PINID='A';
NODE_NAME     R5028 2
 '@T6G_MB_LIB.T6G(SCH_1):PAGE28_I60@PURE_QUANTA.Q_RES(CHIPS)':
 'B': CDS_PINID='B';
NODE_NAME     R445 1
 '@T6G_MB_LIB.T6G(SCH_1):PAGE28_I66@PURE_QUANTA.Q_RES(CHIPS)':
 'A': CDS_PINID='A';
NODE_NAME     U25 DE40
 '@T6G_MB_LIB.T6G(SCH_1):PAGE28_I188@PURE_QUANTA.GENOA_SP5(CHIPS)':
 'AGPIO6||DEVSLP1||SATA_ZP1_L': CDS_PINID='\agpio6||devslp1||sata_zp1_l\';
NET_NAME
'IRQ_BMC_SMI_R_N'
 '@T6G_MB_LIB.T6G(SCH_1):IRQ_BMC_SMI_R_N':
 C_SIGNAL='@t6g_mb_lib.t6g(sch_1):irq_bmc_smi_r_n';
NODE_NAME     R244 2
 '@T6G_MB_LIB.T6G(SCH_1):PAGE81_I72@PURE_QUANTA.Q_RES(CHIPS)':
 'B': CDS_PINID='B';
NODE_NAME     U18 F5
 '@T6G_MB_LIB.T6G(SCH_1):PAGE81_I143@PURE_QUANTA.LCMXO3LF9400C5BG484C(CHIPS)':
 'PL3B||L_GPLLC_FB': CDS_PINID='\pl3b||l_gpllc_fb\';
NET_NAME
'IRQ_CPU_BMC_NMI_N'
 '@T6G_MB_LIB.T6G(SCH_1):IRQ_CPU_BMC_NMI_N':
 C_SIGNAL='@t6g_mb_lib.t6g(sch_1):irq_cpu_bmc_nmi_n';
NODE_NAME     U26 DF40
 '@T6G_MB_LIB.T6G(SCH_1):PAGE55_I182@PURE_QUANTA.GENOA_SP5(CHIPS)':
 'AGPIO5||DEVSLP0||SATA_ZP0_L': CDS_PINID='\agpio5||devslp0||sata_zp0_l\';
NODE_NAME     R187 1
 '@T6G_MB_LIB.T6G(SCH_1):PAGE81_I68@PURE_QUANTA.Q_RES(CHIPS)':
 'A': CDS_PINID='A';
NODE_NAME     R5032 2
 '@T6G_MB_LIB.T6G(SCH_1):PAGE55_I330@PURE_QUANTA.Q_RES(CHIPS)':
 'B': CDS_PINID='B';
NODE_NAME     R544 1
 '@T6G_MB_LIB.T6G(SCH_1):PAGE55_I336@PURE_QUANTA.Q_RES(CHIPS)':
 'A': CDS_PINID='A';
NET_NAME
'IRQ_CPU_BMC_NMI_R_N'
 '@T6G_MB_LIB.T6G(SCH_1):IRQ_CPU_BMC_NMI_R_N':
 C_SIGNAL='@t6g_mb_lib.t6g(sch_1):irq_cpu_bmc_nmi_r_n';
NODE_NAME     R187 2
 '@T6G_MB_LIB.T6G(SCH_1):PAGE81_I68@PURE_QUANTA.Q_RES(CHIPS)':
 'B': CDS_PINID='B';
NODE_NAME     U18 H7
 '@T6G_MB_LIB.T6G(SCH_1):PAGE81_I143@PURE_QUANTA.LCMXO3LF9400C5BG484C(CHIPS)':
 'PL3D': CDS_PINID='PL3D';
NET_NAME
'IRQ_HSC_FAULT'
 '@T6G_MB_LIB.T6G(SCH_1):IRQ_HSC_FAULT':
 C_SIGNAL='@t6g_mb_lib.t6g(sch_1):irq_hsc_fault';
NODE_NAME     Q9003 6
 '@T6G_MB_LIB.T6G(SCH_1):PAGE84_I111@PURE_QUANTA.MOSFET_NCH_DUAL(CHIPS)':
 'D1': CDS_PINID='D1';
NODE_NAME     R9026 2
 '@T6G_MB_LIB.T6G(SCH_1):PAGE84_I112@PURE_QUANTA.Q_RES(CHIPS)':
 'B': CDS_PINID='B';
NODE_NAME     Q9003 5
 '@T6G_MB_LIB.T6G(SCH_1):PAGE84_I121@PURE_QUANTA.MOSFET_NCH_DUAL(CHIPS)':
 'G2': CDS_PINID='G2';
NET_NAME
'IRQ_HSC_FAULT_BUF_N'
 '@T6G_MB_LIB.T6G(SCH_1):IRQ_HSC_FAULT_BUF_N':
 C_SIGNAL='@t6g_mb_lib.t6g(sch_1):irq_hsc_fault_buf_n';
NODE_NAME     R6095 2
 '@T6G_MB_LIB.T6G(SCH_1):PAGE79_I112@PURE_QUANTA.Q_RES(CHIPS)':
 'B': CDS_PINID='B';
NODE_NAME     R9027 2
 '@T6G_MB_LIB.T6G(SCH_1):PAGE84_I114@PURE_QUANTA.Q_RES(CHIPS)':
 'B': CDS_PINID='B';
NODE_NAME     C9005 1
 '@T6G_MB_LIB.T6G(SCH_1):PAGE84_I116@PURE_QUANTA.Q_CAP(CHIPS)':
 'A': CDS_PINID='A';
NODE_NAME     R9028 2
 '@T6G_MB_LIB.T6G(SCH_1):PAGE84_I118@PURE_QUANTA.Q_RES(CHIPS)':
 'B': CDS_PINID='B';
NODE_NAME     Q9003 3
 '@T6G_MB_LIB.T6G(SCH_1):PAGE84_I121@PURE_QUANTA.MOSFET_NCH_DUAL(CHIPS)':
 'D2': CDS_PINID='D2';
NET_NAME
'IRQ_HSC_FAULT_BUF_R_N'
 '@T6G_MB_LIB.T6G(SCH_1):IRQ_HSC_FAULT_BUF_R_N':
 C_SIGNAL='@t6g_mb_lib.t6g(sch_1):irq_hsc_fault_buf_r_n';
NODE_NAME     U18 B6
 '@T6G_MB_LIB.T6G(SCH_1):PAGE79_I94@PURE_QUANTA.LCMXO3LF9400C5BG484C(CHIPS)':
 'PT14A': CDS_PINID='PT14A';
NODE_NAME     R6095 1
 '@T6G_MB_LIB.T6G(SCH_1):PAGE79_I112@PURE_QUANTA.Q_RES(CHIPS)':
 'A': CDS_PINID='A';
NET_NAME
'IRQ_HSC_FAULT_N'
 '@T6G_MB_LIB.T6G(SCH_1):IRQ_HSC_FAULT_N':
 C_SIGNAL='@t6g_mb_lib.t6g(sch_1):irq_hsc_fault_n';
NODE_NAME     R2588 2
 '@T6G_MB_LIB.T6G(SCH_1):PAGE267_I79@PURE_QUANTA.Q_RES(CHIPS)':
 'B': CDS_PINID='B';
NODE_NAME     PJ38 13
 '@T6G_MB_LIB.T6G(SCH_1):PAGE371_I42@PURE_QUANTA.SCONN21_9193031121LF(CHIPS)':
 '13': CDS_PINID='\13\';
NODE_NAME     R9025 1
 '@T6G_MB_LIB.T6G(SCH_1):PAGE84_I106@PURE_QUANTA.Q_RES(CHIPS)':
 'A': CDS_PINID='A';
NODE_NAME     Q9003 2
 '@T6G_MB_LIB.T6G(SCH_1):PAGE84_I111@PURE_QUANTA.MOSFET_NCH_DUAL(CHIPS)':
 'G1': CDS_PINID='G1';
NODE_NAME     R9028 1
 '@T6G_MB_LIB.T6G(SCH_1):PAGE84_I118@PURE_QUANTA.Q_RES(CHIPS)':
 'A': CDS_PINID='A';
NODE_NAME     R2587 1
 '@T6G_MB_LIB.T6G(SCH_1):PAGE267_I99@PURE_QUANTA.Q_RES(CHIPS)':
 'A': CDS_PINID='A';
NODE_NAME     R9024 2
 '@T6G_MB_LIB.T6G(SCH_1):PAGE371_I113@PURE_QUANTA.Q_RES(CHIPS)':
 'B': CDS_PINID='B';
NET_NAME
'IRQ_LVC3_OCP_SFF_WAKE_N'
 '@T6G_MB_LIB.T6G(SCH_1):IRQ_LVC3_OCP_SFF_WAKE_N':
 C_SIGNAL='@t6g_mb_lib.t6g(sch_1):irq_lvc3_ocp_sff_wake_n';
NODE_NAME     J38 OA3
 '@T6G_MB_LIB.T6G(SCH_1):PAGE335_I168@PURE_QUANTA.SCONN168_ME1016810202011(CHIPS)':
 'WAKE#': CDS_PINID='\wake#\';
NODE_NAME     U8082 2
 '@T6G_MB_LIB.T6G(SCH_1):PAGE337_I8@PURE_QUANTA.74LVC1G126SE7(CHIPS)':
 'A': CDS_PINID='A';
NODE_NAME     R1824 2
 '@T6G_MB_LIB.T6G(SCH_1):PAGE337_I11@PURE_QUANTA.Q_RES(CHIPS)':
 'B': CDS_PINID='B';
NET_NAME
'IRQ_LVC3_OCP_V3_2_WAKE_N'
 '@T6G_MB_LIB.T6G(SCH_1):IRQ_LVC3_OCP_V3_2_WAKE_N':
 C_SIGNAL='@t6g_mb_lib.t6g(sch_1):irq_lvc3_ocp_v3_2_wake_n';
NODE_NAME     J35 OA3
 '@T6G_MB_LIB.T6G(SCH_1):PAGE341_I168@PURE_QUANTA.SCONN168_ME1016810202011(CHIPS)':
 'WAKE#': CDS_PINID='\wake#\';
NODE_NAME     R3182 2
 '@T6G_MB_LIB.T6G(SCH_1):PAGE342_I3@PURE_QUANTA.Q_RES(CHIPS)':
 'B': CDS_PINID='B';
NODE_NAME     U217 2
 '@T6G_MB_LIB.T6G(SCH_1):PAGE342_I14@PURE_QUANTA.74LVC1G126SE7(CHIPS)':
 'A': CDS_PINID='A';
NET_NAME
'IRQ_LVC3_V3_2_WAKE_BUF_N'
 '@T6G_MB_LIB.T6G(SCH_1):IRQ_LVC3_V3_2_WAKE_BUF_N':
 C_SIGNAL='@t6g_mb_lib.t6g(sch_1):irq_lvc3_v3_2_wake_buf_n';
NODE_NAME     R3192 2
 '@T6G_MB_LIB.T6G(SCH_1):PAGE342_I44@PURE_QUANTA.Q_RES(CHIPS)':
 'B': CDS_PINID='B';
NODE_NAME     U219 4
 '@T6G_MB_LIB.T6G(SCH_1):PAGE342_I32@PURE_QUANTA.74LVC1G07GV(CHIPS)':
 'Y': CDS_PINID='Y';
NODE_NAME     R3193 1
 '@T6G_MB_LIB.T6G(SCH_1):PAGE342_I43@PURE_QUANTA.Q_RES(CHIPS)':
 'A': CDS_PINID='A';
NET_NAME
'IRQ_LVC3_WAKE'
 '@T6G_MB_LIB.T6G(SCH_1):IRQ_LVC3_WAKE':
 C_SIGNAL='@t6g_mb_lib.t6g(sch_1):irq_lvc3_wake';
NODE_NAME     Q4 6
 '@T6G_MB_LIB.T6G(SCH_1):PAGE132_I12@PURE_QUANTA.MOSFET_DUAL_6P(CHIPS)':
 'D1': CDS_PINID='D1';
NODE_NAME     Q4 5
 '@T6G_MB_LIB.T6G(SCH_1):PAGE132_I12@PURE_QUANTA.MOSFET_DUAL_6P(CHIPS)':
 'G2': CDS_PINID='G2';
NODE_NAME     R1009 2
 '@T6G_MB_LIB.T6G(SCH_1):PAGE132_I10@PURE_QUANTA.Q_RES(CHIPS)':
 'B': CDS_PINID='B';
NET_NAME
'IRQ_LVC3_WAKE_BUF_N'
 '@T6G_MB_LIB.T6G(SCH_1):IRQ_LVC3_WAKE_BUF_N':
 C_SIGNAL='@t6g_mb_lib.t6g(sch_1):irq_lvc3_wake_buf_n';
NODE_NAME     R2487 2
 '@T6G_MB_LIB.T6G(SCH_1):PAGE337_I56@PURE_QUANTA.Q_RES(CHIPS)':
 'B': CDS_PINID='B';
NODE_NAME     U157 4
 '@T6G_MB_LIB.T6G(SCH_1):PAGE337_I25@PURE_QUANTA.74LVC1G07GV(CHIPS)':
 'Y': CDS_PINID='Y';
NODE_NAME     R2489 1
 '@T6G_MB_LIB.T6G(SCH_1):PAGE337_I50@PURE_QUANTA.Q_RES(CHIPS)':
 'A': CDS_PINID='A';
NET_NAME
'IRQ_LVC3_WAKE_N'
 '@T6G_MB_LIB.T6G(SCH_1):IRQ_LVC3_WAKE_N':
 C_SIGNAL='@t6g_mb_lib.t6g(sch_1):irq_lvc3_wake_n';
NODE_NAME     Q4 2
 '@T6G_MB_LIB.T6G(SCH_1):PAGE132_I12@PURE_QUANTA.MOSFET_DUAL_6P(CHIPS)':
 'G1': CDS_PINID='G1';
NODE_NAME     R1005 2
 '@T6G_MB_LIB.T6G(SCH_1):PAGE132_I4@PURE_QUANTA.Q_RES(CHIPS)':
 'B': CDS_PINID='B';
NODE_NAME     R116 2
 '@T6G_MB_LIB.T6G(SCH_1):PAGE132_I5@PURE_QUANTA.Q_RES(CHIPS)':
 'B': CDS_PINID='B';
NODE_NAME     R6063 2
 '@T6G_MB_LIB.T6G(SCH_1):PAGE132_I6@PURE_QUANTA.Q_RES(CHIPS)':
 'B': CDS_PINID='B';
NODE_NAME     R994 2
 '@T6G_MB_LIB.T6G(SCH_1):PAGE132_I7@PURE_QUANTA.Q_RES(CHIPS)':
 'B': CDS_PINID='B';
NET_NAME
'IRQ_OCP_SFF_WAKE_BUF_N'
 '@T6G_MB_LIB.T6G(SCH_1):IRQ_OCP_SFF_WAKE_BUF_N':
 C_SIGNAL='@t6g_mb_lib.t6g(sch_1):irq_ocp_sff_wake_buf_n';
NODE_NAME     R2489 2
 '@T6G_MB_LIB.T6G(SCH_1):PAGE337_I50@PURE_QUANTA.Q_RES(CHIPS)':
 'B': CDS_PINID='B';
NODE_NAME     R116 1
 '@T6G_MB_LIB.T6G(SCH_1):PAGE132_I5@PURE_QUANTA.Q_RES(CHIPS)':
 'A': CDS_PINID='A';
NET_NAME
'IRQ_OCP_V3_2_WAKE_BUF_N'
 '@T6G_MB_LIB.T6G(SCH_1):IRQ_OCP_V3_2_WAKE_BUF_N':
 C_SIGNAL='@t6g_mb_lib.t6g(sch_1):irq_ocp_v3_2_wake_buf_n';
NODE_NAME     R3193 2
 '@T6G_MB_LIB.T6G(SCH_1):PAGE342_I43@PURE_QUANTA.Q_RES(CHIPS)':
 'B': CDS_PINID='B';
NODE_NAME     R6063 1
 '@T6G_MB_LIB.T6G(SCH_1):PAGE132_I6@PURE_QUANTA.Q_RES(CHIPS)':
 'A': CDS_PINID='A';
NET_NAME
'IRQ_SMI_ACTIVE_N'
 '@T6G_MB_LIB.T6G(SCH_1):IRQ_SMI_ACTIVE_N':
 C_SIGNAL='@t6g_mb_lib.t6g(sch_1):irq_smi_active_n';
NODE_NAME     R245 1
 '@T6G_MB_LIB.T6G(SCH_1):PAGE81_I67@PURE_QUANTA.Q_RES(CHIPS)':
 'A': CDS_PINID='A';
NODE_NAME     R5027 2
 '@T6G_MB_LIB.T6G(SCH_1):PAGE28_I59@PURE_QUANTA.Q_RES(CHIPS)':
 'B': CDS_PINID='B';
NODE_NAME     R446 1
 '@T6G_MB_LIB.T6G(SCH_1):PAGE28_I64@PURE_QUANTA.Q_RES(CHIPS)':
 'A': CDS_PINID='A';
NODE_NAME     U25 DH16
 '@T6G_MB_LIB.T6G(SCH_1):PAGE28_I188@PURE_QUANTA.GENOA_SP5(CHIPS)':
 'AGPIO115||CLK_REQ11_L': CDS_PINID='\agpio115||clk_req11_l\';
NET_NAME
'IRQ_SMI_ACTIVE_N_R'
 '@T6G_MB_LIB.T6G(SCH_1):IRQ_SMI_ACTIVE_N_R':
 C_SIGNAL='@t6g_mb_lib.t6g(sch_1):irq_smi_active_n_r';
NODE_NAME     R245 2
 '@T6G_MB_LIB.T6G(SCH_1):PAGE81_I67@PURE_QUANTA.Q_RES(CHIPS)':
 'B': CDS_PINID='B';
NODE_NAME     U18 G5
 '@T6G_MB_LIB.T6G(SCH_1):PAGE81_I143@PURE_QUANTA.LCMXO3LF9400C5BG484C(CHIPS)':
 'PL4C': CDS_PINID='PL4C';
NET_NAME
'IRQ_SML1_PMBUS_ALERT'
 '@T6G_MB_LIB.T6G(SCH_1):IRQ_SML1_PMBUS_ALERT':
 C_SIGNAL='@t6g_mb_lib.t6g(sch_1):irq_sml1_pmbus_alert';
NODE_NAME     R3924 2
 '@T6G_MB_LIB.T6G(SCH_1):PAGE267_I24@PURE_QUANTA.Q_RES(CHIPS)':
 'B': CDS_PINID='B';
NODE_NAME     R3925 1
 '@T6G_MB_LIB.T6G(SCH_1):PAGE267_I34@PURE_QUANTA.Q_RES(CHIPS)':
 'A': CDS_PINID='A';
NODE_NAME     PU289 10
 '@T6G_MB_LIB.T6G(SCH_1):PAGE267_I58@PURE_QUANTA.MP5990GMA1111Z(CHIPS)':
 'ALT#': CDS_PINID='\alt#\';
NET_NAME
'IRQ_SML1_PMBUS_ALERT_N'
 '@T6G_MB_LIB.T6G(SCH_1):IRQ_SML1_PMBUS_ALERT_N':
 C_SIGNAL='@t6g_mb_lib.t6g(sch_1):irq_sml1_pmbus_alert_n';
NODE_NAME     U18 B21
 '@T6G_MB_LIB.T6G(SCH_1):PAGE79_I94@PURE_QUANTA.LCMXO3LF9400C5BG484C(CHIPS)':
 'PT43B||R_GPLLC': CDS_PINID='\pt43b||r_gpllc\';
NODE_NAME     R3924 1
 '@T6G_MB_LIB.T6G(SCH_1):PAGE267_I24@PURE_QUANTA.Q_RES(CHIPS)':
 'A': CDS_PINID='A';
NODE_NAME     PJ38 20
 '@T6G_MB_LIB.T6G(SCH_1):PAGE371_I42@PURE_QUANTA.SCONN21_9193031121LF(CHIPS)':
 '20': CDS_PINID='\20\';
NET_NAME
'IRQ_TPM_SPI_R1_N'
 '@T6G_MB_LIB.T6G(SCH_1):IRQ_TPM_SPI_R1_N':
 C_SIGNAL='@t6g_mb_lib.t6g(sch_1):irq_tpm_spi_r1_n';
NODE_NAME     R246 2
 '@T6G_MB_LIB.T6G(SCH_1):PAGE81_I65@PURE_QUANTA.Q_RES(CHIPS)':
 'B': CDS_PINID='B';
NODE_NAME     U18 H6
 '@T6G_MB_LIB.T6G(SCH_1):PAGE81_I143@PURE_QUANTA.LCMXO3LF9400C5BG484C(CHIPS)':
 'PL4D': CDS_PINID='PL4D';
NET_NAME
'IRQ_TPM_SPI_R_N'
 '@T6G_MB_LIB.T6G(SCH_1):IRQ_TPM_SPI_R_N':
 C_SIGNAL='@t6g_mb_lib.t6g(sch_1):irq_tpm_spi_r_n';
NODE_NAME     R246 1
 '@T6G_MB_LIB.T6G(SCH_1):PAGE81_I65@PURE_QUANTA.Q_RES(CHIPS)':
 'A': CDS_PINID='A';
NODE_NAME     R5029 2
 '@T6G_MB_LIB.T6G(SCH_1):PAGE28_I62@PURE_QUANTA.Q_RES(CHIPS)':
 'B': CDS_PINID='B';
NODE_NAME     R447 1
 '@T6G_MB_LIB.T6G(SCH_1):PAGE28_I65@PURE_QUANTA.Q_RES(CHIPS)':
 'A': CDS_PINID='A';
NODE_NAME     U25 DH15
 '@T6G_MB_LIB.T6G(SCH_1):PAGE28_I188@PURE_QUANTA.GENOA_SP5(CHIPS)':
 'AGPIO116||CLK_REQ12_L': CDS_PINID='\agpio116||clk_req12_l\';
NET_NAME
'IRQ_UV_DETECT_N'
 '@T6G_MB_LIB.T6G(SCH_1):IRQ_UV_DETECT_N':
 C_SIGNAL='@t6g_mb_lib.t6g(sch_1):irq_uv_detect_n';
NODE_NAME     R6038 2
 '@T6G_MB_LIB.T6G(SCH_1):PAGE79_I21@PURE_QUANTA.Q_RES(CHIPS)':
 'B': CDS_PINID='B';
NODE_NAME     U325 D
 '@T6G_MB_LIB.T6G(SCH_1):PAGE372_I42@PURE_QUANTA.MOSFET_N(CHIPS)':
 'DRAIN': CDS_PINID='DRAIN';
NODE_NAME     R4620 2
 '@T6G_MB_LIB.T6G(SCH_1):PAGE372_I46@PURE_QUANTA.Q_RES(CHIPS)':
 'B': CDS_PINID='B';
NODE_NAME     R8124 2
 '@T6G_MB_LIB.T6G(SCH_1):PAGE372_I85@PURE_QUANTA.Q_RES(CHIPS)':
 'B': CDS_PINID='B';
NODE_NAME     R8125 2
 '@T6G_MB_LIB.T6G(SCH_1):PAGE372_I104@PURE_QUANTA.Q_RES(CHIPS)':
 'B': CDS_PINID='B';
NET_NAME
'IRQ_UV_DETECT_R2_N'
 '@T6G_MB_LIB.T6G(SCH_1):IRQ_UV_DETECT_R2_N':
 C_SIGNAL='@t6g_mb_lib.t6g(sch_1):irq_uv_detect_r2_n';
NODE_NAME     U8010 4
 '@T6G_MB_LIB.T6G(SCH_1):PAGE372_I80@PURE_QUANTA.AP331AWG7(CHIPS)':
 'OUTPUT': CDS_PINID='OUTPUT';
NODE_NAME     R8123 2
 '@T6G_MB_LIB.T6G(SCH_1):PAGE372_I81@PURE_QUANTA.Q_RES(CHIPS)':
 'B': CDS_PINID='B';
NODE_NAME     R8124 1
 '@T6G_MB_LIB.T6G(SCH_1):PAGE372_I85@PURE_QUANTA.Q_RES(CHIPS)':
 'A': CDS_PINID='A';
NET_NAME
'IRQ_WAKE_N'
 '@T6G_MB_LIB.T6G(SCH_1):IRQ_WAKE_N':
 C_SIGNAL='@t6g_mb_lib.t6g(sch_1):irq_wake_n';
NODE_NAME     U26 DJ10
 '@T6G_MB_LIB.T6G(SCH_1):PAGE55_I182@PURE_QUANTA.GENOA_SP5(CHIPS)':
 'WAKE_L||AGPIO2': CDS_PINID='\wake_l||agpio2\';
NODE_NAME     U25 DJ10
 '@T6G_MB_LIB.T6G(SCH_1):PAGE28_I188@PURE_QUANTA.GENOA_SP5(CHIPS)':
 'WAKE_L||AGPIO2': CDS_PINID='\wake_l||agpio2\';
NODE_NAME     R1311 2
 '@T6G_MB_LIB.T6G(SCH_1):PAGE132_I16@PURE_QUANTA.Q_RES(CHIPS)':
 'B': CDS_PINID='B';
NODE_NAME     R437 2
 '@T6G_MB_LIB.T6G(SCH_1):PAGE132_I18@PURE_QUANTA.Q_RES(CHIPS)':
 'B': CDS_PINID='B';
NET_NAME
'IRQ_WAKE_R_N'
 '@T6G_MB_LIB.T6G(SCH_1):IRQ_WAKE_R_N':
 C_SIGNAL='@t6g_mb_lib.t6g(sch_1):irq_wake_r_n';
NODE_NAME     Q4 3
 '@T6G_MB_LIB.T6G(SCH_1):PAGE132_I12@PURE_QUANTA.MOSFET_DUAL_6P(CHIPS)':
 'D2': CDS_PINID='D2';
NODE_NAME     R1311 1
 '@T6G_MB_LIB.T6G(SCH_1):PAGE132_I16@PURE_QUANTA.Q_RES(CHIPS)':
 'A': CDS_PINID='A';
NET_NAME
'JTAG_BMC_OE'
 '@T6G_MB_LIB.T6G(SCH_1):JTAG_BMC_OE':
 C_SIGNAL='@t6g_mb_lib.t6g(sch_1):jtag_bmc_oe';
NODE_NAME     U124 4
 '@T6G_MB_LIB.T6G(SCH_1):PAGE144_I38@PURE_QUANTA.SN74LVC1G07DBVR(CHIPS)':
 'Y': CDS_PINID='Y';
NODE_NAME     R1619 1
 '@T6G_MB_LIB.T6G(SCH_1):PAGE149_I92@PURE_QUANTA.Q_RES(CHIPS)':
 'A': CDS_PINID='A';
NODE_NAME     Q62 G
 '@T6G_MB_LIB.T6G(SCH_1):PAGE149_I102@PURE_QUANTA.MOSFET_N(CHIPS)':
 'GATE': CDS_PINID='GATE';
NODE_NAME     R8 2
 '@T6G_MB_LIB.T6G(SCH_1):PAGE144_I47@PURE_QUANTA.Q_RES(CHIPS)':
 'B': CDS_PINID='B';
NET_NAME
'JTAG_BMC_OE_N'
 '@T6G_MB_LIB.T6G(SCH_1):JTAG_BMC_OE_N':
 C_SIGNAL='@t6g_mb_lib.t6g(sch_1):jtag_bmc_oe_n';
NODE_NAME     U147 2
 '@T6G_MB_LIB.T6G(SCH_1):PAGE149_I1@PURE_QUANTA.SN74AVC2T245RSWR(CHIPS)':
 'OE_#': CDS_PINID='\oe_#\';
NODE_NAME     U148 9
 '@T6G_MB_LIB.T6G(SCH_1):PAGE149_I34@PURE_QUANTA.SN74AVC4T774PWR(CHIPS)':
 'OE': CDS_PINID='OE';
NODE_NAME     R1622 2
 '@T6G_MB_LIB.T6G(SCH_1):PAGE149_I83@PURE_QUANTA.Q_RES(CHIPS)':
 'B': CDS_PINID='B';
NODE_NAME     Q62 D
 '@T6G_MB_LIB.T6G(SCH_1):PAGE149_I102@PURE_QUANTA.MOSFET_N(CHIPS)':
 'DRAIN': CDS_PINID='DRAIN';
NET_NAME
'JTAG_BMC_R_D_OE'
 '@T6G_MB_LIB.T6G(SCH_1):JTAG_BMC_R_D_OE':
 C_SIGNAL='@t6g_mb_lib.t6g(sch_1):jtag_bmc_r_d_oe';
NODE_NAME     U149 9
 '@T6G_MB_LIB.T6G(SCH_1):PAGE149_I31@PURE_QUANTA.SN74AVC4T774PWR(CHIPS)':
 'OE': CDS_PINID='OE';
NODE_NAME     U146 2
 '@T6G_MB_LIB.T6G(SCH_1):PAGE149_I76@PURE_QUANTA.SN74AVC2T245RSWR(CHIPS)':
 'OE_#': CDS_PINID='\oe_#\';
NODE_NAME     R1619 2
 '@T6G_MB_LIB.T6G(SCH_1):PAGE149_I92@PURE_QUANTA.Q_RES(CHIPS)':
 'B': CDS_PINID='B';
NODE_NAME     R617 2
 '@T6G_MB_LIB.T6G(SCH_1):PAGE149_I101@PURE_QUANTA.Q_RES(CHIPS)':
 'B': CDS_PINID='B';
NODE_NAME     C8006 1
 '@T6G_MB_LIB.T6G(SCH_1):PAGE149_I163@PURE_QUANTA.Q_CAP(CHIPS)':
 'A': CDS_PINID='A';
NET_NAME
'JTAG_CPU0_BYPASS'
 '@T6G_MB_LIB.T6G(SCH_1):JTAG_CPU0_BYPASS':
 C_SIGNAL='@t6g_mb_lib.t6g(sch_1):jtag_cpu0_bypass';
NODE_NAME     U153 6
 '@T6G_MB_LIB.T6G(SCH_1):PAGE151_I1@PURE_QUANTA.SN74AUC2G66DCTR(CHIPS)':
 '2B': CDS_PINID='\2b\';
NODE_NAME     R6104 1
 '@T6G_MB_LIB.T6G(SCH_1):PAGE151_I48@PURE_QUANTA.Q_RES(CHIPS)':
 'A': CDS_PINID='A';
NET_NAME
'JTAG_CPU0_BYPASS_R1'
 '@T6G_MB_LIB.T6G(SCH_1):JTAG_CPU0_BYPASS_R1':
 C_SIGNAL='@t6g_mb_lib.t6g(sch_1):jtag_cpu0_bypass_r1';
NODE_NAME     U13 5
 '@T6G_MB_LIB.T6G(SCH_1):PAGE151_I17@PURE_QUANTA.SN74AUC2G66DCTR(CHIPS)':
 '2A': CDS_PINID='\2a\';
NODE_NAME     R6104 2
 '@T6G_MB_LIB.T6G(SCH_1):PAGE151_I48@PURE_QUANTA.Q_RES(CHIPS)':
 'B': CDS_PINID='B';
NET_NAME
'JTAG_CPU0_DBREQ_N'
 '@T6G_MB_LIB.T6G(SCH_1):JTAG_CPU0_DBREQ_N':
 C_SIGNAL='@t6g_mb_lib.t6g(sch_1):jtag_cpu0_dbreq_n';
NODE_NAME     U25 C16
 '@T6G_MB_LIB.T6G(SCH_1):PAGE27_I227@PURE_QUANTA.GENOA_SP5(CHIPS)':
 'DBREQ_L': CDS_PINID='DBREQ_L';
NODE_NAME     R403 2
 '@T6G_MB_LIB.T6G(SCH_1):PAGE27_I294@PURE_QUANTA.Q_RES(CHIPS)':
 'B': CDS_PINID='B';
NODE_NAME     C212 1
 '@T6G_MB_LIB.T6G(SCH_1):PAGE27_I295@PURE_QUANTA.Q_CAP(CHIPS)':
 'A': CDS_PINID='A';
NODE_NAME     R1641 2
 '@T6G_MB_LIB.T6G(SCH_1):PAGE150_I24@PURE_QUANTA.Q_RES(CHIPS)':
 'B': CDS_PINID='B';
NET_NAME
'JTAG_CPU0_R_TDI'
 '@T6G_MB_LIB.T6G(SCH_1):JTAG_CPU0_R_TDI':
 C_SIGNAL='@t6g_mb_lib.t6g(sch_1):jtag_cpu0_r_tdi';
NODE_NAME     U153 2
 '@T6G_MB_LIB.T6G(SCH_1):PAGE151_I1@PURE_QUANTA.SN74AUC2G66DCTR(CHIPS)':
 '1B': CDS_PINID='\1b\';
NODE_NAME     R1648 1
 '@T6G_MB_LIB.T6G(SCH_1):PAGE151_I2@PURE_QUANTA.Q_RES(CHIPS)':
 'A': CDS_PINID='A';
NET_NAME
'JTAG_CPU0_R_TDO'
 '@T6G_MB_LIB.T6G(SCH_1):JTAG_CPU0_R_TDO':
 C_SIGNAL='@t6g_mb_lib.t6g(sch_1):jtag_cpu0_r_tdo';
NODE_NAME     R404 1
 '@T6G_MB_LIB.T6G(SCH_1):PAGE27_I170@PURE_QUANTA.Q_RES(CHIPS)':
 'A': CDS_PINID='A';
NODE_NAME     U25 C18
 '@T6G_MB_LIB.T6G(SCH_1):PAGE27_I227@PURE_QUANTA.GENOA_SP5(CHIPS)':
 'TDO': CDS_PINID='TDO';
NET_NAME
'JTAG_CPU0_TCK'
 '@T6G_MB_LIB.T6G(SCH_1):JTAG_CPU0_TCK':
 C_SIGNAL='@t6g_mb_lib.t6g(sch_1):jtag_cpu0_tck';
NODE_NAME     U25 B17
 '@T6G_MB_LIB.T6G(SCH_1):PAGE27_I227@PURE_QUANTA.GENOA_SP5(CHIPS)':
 'TCK': CDS_PINID='TCK';
NODE_NAME     R401 2
 '@T6G_MB_LIB.T6G(SCH_1):PAGE27_I300@PURE_QUANTA.Q_RES(CHIPS)':
 'B': CDS_PINID='B';
NODE_NAME     C210 1
 '@T6G_MB_LIB.T6G(SCH_1):PAGE27_I302@PURE_QUANTA.Q_CAP(CHIPS)':
 'A': CDS_PINID='A';
NODE_NAME     R1638 2
 '@T6G_MB_LIB.T6G(SCH_1):PAGE150_I27@PURE_QUANTA.Q_RES(CHIPS)':
 'B': CDS_PINID='B';
NET_NAME
'JTAG_CPU0_TDI'
 '@T6G_MB_LIB.T6G(SCH_1):JTAG_CPU0_TDI':
 C_SIGNAL='@t6g_mb_lib.t6g(sch_1):jtag_cpu0_tdi';
NODE_NAME     U25 C17
 '@T6G_MB_LIB.T6G(SCH_1):PAGE27_I227@PURE_QUANTA.GENOA_SP5(CHIPS)':
 'TDI': CDS_PINID='TDI';
NODE_NAME     R399 2
 '@T6G_MB_LIB.T6G(SCH_1):PAGE27_I304@PURE_QUANTA.Q_RES(CHIPS)':
 'B': CDS_PINID='B';
NODE_NAME     C208 1
 '@T6G_MB_LIB.T6G(SCH_1):PAGE27_I306@PURE_QUANTA.Q_CAP(CHIPS)':
 'A': CDS_PINID='A';
NODE_NAME     R1648 2
 '@T6G_MB_LIB.T6G(SCH_1):PAGE151_I2@PURE_QUANTA.Q_RES(CHIPS)':
 'B': CDS_PINID='B';
NODE_NAME     C1520 1
 '@T6G_MB_LIB.T6G(SCH_1):PAGE151_I4@PURE_QUANTA.Q_CAP(CHIPS)':
 'A': CDS_PINID='A';
NET_NAME
'JTAG_CPU0_TDO'
 '@T6G_MB_LIB.T6G(SCH_1):JTAG_CPU0_TDO':
 C_SIGNAL='@t6g_mb_lib.t6g(sch_1):jtag_cpu0_tdo';
NODE_NAME     R404 2
 '@T6G_MB_LIB.T6G(SCH_1):PAGE27_I170@PURE_QUANTA.Q_RES(CHIPS)':
 'B': CDS_PINID='B';
NODE_NAME     R398 2
 '@T6G_MB_LIB.T6G(SCH_1):PAGE27_I305@PURE_QUANTA.Q_RES(CHIPS)':
 'B': CDS_PINID='B';
NODE_NAME     C207 1
 '@T6G_MB_LIB.T6G(SCH_1):PAGE27_I307@PURE_QUANTA.Q_CAP(CHIPS)':
 'A': CDS_PINID='A';
NODE_NAME     U13 1
 '@T6G_MB_LIB.T6G(SCH_1):PAGE151_I17@PURE_QUANTA.SN74AUC2G66DCTR(CHIPS)':
 '1A': CDS_PINID='\1a\';
NET_NAME
'JTAG_CPU0_TDO_CPU1_TDI'
 '@T6G_MB_LIB.T6G(SCH_1):JTAG_CPU0_TDO_CPU1_TDI':
 C_SIGNAL='@t6g_mb_lib.t6g(sch_1):jtag_cpu0_tdo_cpu1_tdi';
NODE_NAME     U13 2
 '@T6G_MB_LIB.T6G(SCH_1):PAGE151_I17@PURE_QUANTA.SN74AUC2G66DCTR(CHIPS)':
 '1B': CDS_PINID='\1b\';
NODE_NAME     U14 1
 '@T6G_MB_LIB.T6G(SCH_1):PAGE151_I23@PURE_QUANTA.SN74AUC2G66DCTR(CHIPS)':
 '1A': CDS_PINID='\1a\';
NODE_NAME     U14 5
 '@T6G_MB_LIB.T6G(SCH_1):PAGE151_I23@PURE_QUANTA.SN74AUC2G66DCTR(CHIPS)':
 '2A': CDS_PINID='\2a\';
NODE_NAME     R6105 2
 '@T6G_MB_LIB.T6G(SCH_1):PAGE151_I49@PURE_QUANTA.Q_RES(CHIPS)':
 'B': CDS_PINID='B';
NET_NAME
'JTAG_CPU0_TDO_CPU1_TDI_R1'
 '@T6G_MB_LIB.T6G(SCH_1):JTAG_CPU0_TDO_CPU1_TDI_R1':
 C_SIGNAL='@t6g_mb_lib.t6g(sch_1):jtag_cpu0_tdo_cpu1_tdi_r1';
NODE_NAME     U13 6
 '@T6G_MB_LIB.T6G(SCH_1):PAGE151_I17@PURE_QUANTA.SN74AUC2G66DCTR(CHIPS)':
 '2B': CDS_PINID='\2b\';
NODE_NAME     R6105 1
 '@T6G_MB_LIB.T6G(SCH_1):PAGE151_I49@PURE_QUANTA.Q_RES(CHIPS)':
 'A': CDS_PINID='A';
NET_NAME
'JTAG_CPU0_TMS'
 '@T6G_MB_LIB.T6G(SCH_1):JTAG_CPU0_TMS':
 C_SIGNAL='@t6g_mb_lib.t6g(sch_1):jtag_cpu0_tms';
NODE_NAME     U25 A16
 '@T6G_MB_LIB.T6G(SCH_1):PAGE27_I227@PURE_QUANTA.GENOA_SP5(CHIPS)':
 'TMS': CDS_PINID='TMS';
NODE_NAME     R402 2
 '@T6G_MB_LIB.T6G(SCH_1):PAGE27_I296@PURE_QUANTA.Q_RES(CHIPS)':
 'B': CDS_PINID='B';
NODE_NAME     C211 1
 '@T6G_MB_LIB.T6G(SCH_1):PAGE27_I297@PURE_QUANTA.Q_CAP(CHIPS)':
 'A': CDS_PINID='A';
NODE_NAME     R1639 2
 '@T6G_MB_LIB.T6G(SCH_1):PAGE150_I25@PURE_QUANTA.Q_RES(CHIPS)':
 'B': CDS_PINID='B';
NET_NAME
'JTAG_CPU0_TRST_N'
 '@T6G_MB_LIB.T6G(SCH_1):JTAG_CPU0_TRST_N':
 C_SIGNAL='@t6g_mb_lib.t6g(sch_1):jtag_cpu0_trst_n';
NODE_NAME     U25 A17
 '@T6G_MB_LIB.T6G(SCH_1):PAGE27_I227@PURE_QUANTA.GENOA_SP5(CHIPS)':
 'TRST_L': CDS_PINID='TRST_L';
NODE_NAME     R400 2
 '@T6G_MB_LIB.T6G(SCH_1):PAGE27_I301@PURE_QUANTA.Q_RES(CHIPS)':
 'B': CDS_PINID='B';
NODE_NAME     C209 1
 '@T6G_MB_LIB.T6G(SCH_1):PAGE27_I303@PURE_QUANTA.Q_CAP(CHIPS)':
 'A': CDS_PINID='A';
NODE_NAME     R1640 2
 '@T6G_MB_LIB.T6G(SCH_1):PAGE150_I26@PURE_QUANTA.Q_RES(CHIPS)':
 'B': CDS_PINID='B';
NET_NAME
'JTAG_CPU1_BYPASS'
 '@T6G_MB_LIB.T6G(SCH_1):JTAG_CPU1_BYPASS':
 C_SIGNAL='@t6g_mb_lib.t6g(sch_1):jtag_cpu1_bypass';
NODE_NAME     U14 6
 '@T6G_MB_LIB.T6G(SCH_1):PAGE151_I23@PURE_QUANTA.SN74AUC2G66DCTR(CHIPS)':
 '2B': CDS_PINID='\2b\';
NODE_NAME     U154 5
 '@T6G_MB_LIB.T6G(SCH_1):PAGE151_I31@PURE_QUANTA.SN74AUC2G66DCTR(CHIPS)':
 '2A': CDS_PINID='\2a\';
NET_NAME
'JTAG_CPU1_DBREQ_N'
 '@T6G_MB_LIB.T6G(SCH_1):JTAG_CPU1_DBREQ_N':
 C_SIGNAL='@t6g_mb_lib.t6g(sch_1):jtag_cpu1_dbreq_n';
NODE_NAME     U26 C16
 '@T6G_MB_LIB.T6G(SCH_1):PAGE54_I190@PURE_QUANTA.GENOA_SP5(CHIPS)':
 'DBREQ_L': CDS_PINID='DBREQ_L';
NODE_NAME     R528 2
 '@T6G_MB_LIB.T6G(SCH_1):PAGE54_I308@PURE_QUANTA.Q_RES(CHIPS)':
 'B': CDS_PINID='B';
NODE_NAME     C235 1
 '@T6G_MB_LIB.T6G(SCH_1):PAGE54_I310@PURE_QUANTA.Q_CAP(CHIPS)':
 'A': CDS_PINID='A';
NODE_NAME     R1645 2
 '@T6G_MB_LIB.T6G(SCH_1):PAGE150_I36@PURE_QUANTA.Q_RES(CHIPS)':
 'B': CDS_PINID='B';
NET_NAME
'JTAG_CPU1_R_TDI'
 '@T6G_MB_LIB.T6G(SCH_1):JTAG_CPU1_R_TDI':
 C_SIGNAL='@t6g_mb_lib.t6g(sch_1):jtag_cpu1_r_tdi';
NODE_NAME     U14 2
 '@T6G_MB_LIB.T6G(SCH_1):PAGE151_I23@PURE_QUANTA.SN74AUC2G66DCTR(CHIPS)':
 '1B': CDS_PINID='\1b\';
NODE_NAME     R1651 1
 '@T6G_MB_LIB.T6G(SCH_1):PAGE151_I34@PURE_QUANTA.Q_RES(CHIPS)':
 'A': CDS_PINID='A';
NET_NAME
'JTAG_CPU1_R_TDO'
 '@T6G_MB_LIB.T6G(SCH_1):JTAG_CPU1_R_TDO':
 C_SIGNAL='@t6g_mb_lib.t6g(sch_1):jtag_cpu1_r_tdo';
NODE_NAME     U26 C18
 '@T6G_MB_LIB.T6G(SCH_1):PAGE54_I190@PURE_QUANTA.GENOA_SP5(CHIPS)':
 'TDO': CDS_PINID='TDO';
NODE_NAME     R529 1
 '@T6G_MB_LIB.T6G(SCH_1):PAGE54_I203@PURE_QUANTA.Q_RES(CHIPS)':
 'A': CDS_PINID='A';
NET_NAME
'JTAG_CPU1_TCK'
 '@T6G_MB_LIB.T6G(SCH_1):JTAG_CPU1_TCK':
 C_SIGNAL='@t6g_mb_lib.t6g(sch_1):jtag_cpu1_tck';
NODE_NAME     U26 B17
 '@T6G_MB_LIB.T6G(SCH_1):PAGE54_I190@PURE_QUANTA.GENOA_SP5(CHIPS)':
 'TCK': CDS_PINID='TCK';
NODE_NAME     R526 2
 '@T6G_MB_LIB.T6G(SCH_1):PAGE54_I314@PURE_QUANTA.Q_RES(CHIPS)':
 'B': CDS_PINID='B';
NODE_NAME     C233 1
 '@T6G_MB_LIB.T6G(SCH_1):PAGE54_I315@PURE_QUANTA.Q_CAP(CHIPS)':
 'A': CDS_PINID='A';
NODE_NAME     R1642 2
 '@T6G_MB_LIB.T6G(SCH_1):PAGE150_I33@PURE_QUANTA.Q_RES(CHIPS)':
 'B': CDS_PINID='B';
NET_NAME
'JTAG_CPU1_TDI'
 '@T6G_MB_LIB.T6G(SCH_1):JTAG_CPU1_TDI':
 C_SIGNAL='@t6g_mb_lib.t6g(sch_1):jtag_cpu1_tdi';
NODE_NAME     U26 C17
 '@T6G_MB_LIB.T6G(SCH_1):PAGE54_I190@PURE_QUANTA.GENOA_SP5(CHIPS)':
 'TDI': CDS_PINID='TDI';
NODE_NAME     R524 2
 '@T6G_MB_LIB.T6G(SCH_1):PAGE54_I317@PURE_QUANTA.Q_RES(CHIPS)':
 'B': CDS_PINID='B';
NODE_NAME     C231 1
 '@T6G_MB_LIB.T6G(SCH_1):PAGE54_I319@PURE_QUANTA.Q_CAP(CHIPS)':
 'A': CDS_PINID='A';
NODE_NAME     R1651 2
 '@T6G_MB_LIB.T6G(SCH_1):PAGE151_I34@PURE_QUANTA.Q_RES(CHIPS)':
 'B': CDS_PINID='B';
NET_NAME
'JTAG_CPU1_TDO'
 '@T6G_MB_LIB.T6G(SCH_1):JTAG_CPU1_TDO':
 C_SIGNAL='@t6g_mb_lib.t6g(sch_1):jtag_cpu1_tdo';
NODE_NAME     R529 2
 '@T6G_MB_LIB.T6G(SCH_1):PAGE54_I203@PURE_QUANTA.Q_RES(CHIPS)':
 'B': CDS_PINID='B';
NODE_NAME     R523 2
 '@T6G_MB_LIB.T6G(SCH_1):PAGE54_I324@PURE_QUANTA.Q_RES(CHIPS)':
 'B': CDS_PINID='B';
NODE_NAME     C230 1
 '@T6G_MB_LIB.T6G(SCH_1):PAGE54_I325@PURE_QUANTA.Q_CAP(CHIPS)':
 'A': CDS_PINID='A';
NODE_NAME     U154 1
 '@T6G_MB_LIB.T6G(SCH_1):PAGE151_I31@PURE_QUANTA.SN74AUC2G66DCTR(CHIPS)':
 '1A': CDS_PINID='\1a\';
NET_NAME
'JTAG_CPU1_TMS'
 '@T6G_MB_LIB.T6G(SCH_1):JTAG_CPU1_TMS':
 C_SIGNAL='@t6g_mb_lib.t6g(sch_1):jtag_cpu1_tms';
NODE_NAME     U26 A16
 '@T6G_MB_LIB.T6G(SCH_1):PAGE54_I190@PURE_QUANTA.GENOA_SP5(CHIPS)':
 'TMS': CDS_PINID='TMS';
NODE_NAME     R527 2
 '@T6G_MB_LIB.T6G(SCH_1):PAGE54_I309@PURE_QUANTA.Q_RES(CHIPS)':
 'B': CDS_PINID='B';
NODE_NAME     C234 1
 '@T6G_MB_LIB.T6G(SCH_1):PAGE54_I311@PURE_QUANTA.Q_CAP(CHIPS)':
 'A': CDS_PINID='A';
NODE_NAME     R1643 2
 '@T6G_MB_LIB.T6G(SCH_1):PAGE150_I34@PURE_QUANTA.Q_RES(CHIPS)':
 'B': CDS_PINID='B';
NET_NAME
'JTAG_CPU1_TRST_N'
 '@T6G_MB_LIB.T6G(SCH_1):JTAG_CPU1_TRST_N':
 C_SIGNAL='@t6g_mb_lib.t6g(sch_1):jtag_cpu1_trst_n';
NODE_NAME     U26 A17
 '@T6G_MB_LIB.T6G(SCH_1):PAGE54_I190@PURE_QUANTA.GENOA_SP5(CHIPS)':
 'TRST_L': CDS_PINID='TRST_L';
NODE_NAME     R525 2
 '@T6G_MB_LIB.T6G(SCH_1):PAGE54_I316@PURE_QUANTA.Q_RES(CHIPS)':
 'B': CDS_PINID='B';
NODE_NAME     C232 1
 '@T6G_MB_LIB.T6G(SCH_1):PAGE54_I318@PURE_QUANTA.Q_CAP(CHIPS)':
 'A': CDS_PINID='A';
NODE_NAME     R1644 2
 '@T6G_MB_LIB.T6G(SCH_1):PAGE150_I35@PURE_QUANTA.Q_RES(CHIPS)':
 'B': CDS_PINID='B';
NET_NAME
'JTAG_CPUX_TDI'
 '@T6G_MB_LIB.T6G(SCH_1):JTAG_CPUX_TDI':
 C_SIGNAL='@t6g_mb_lib.t6g(sch_1):jtag_cpux_tdi';
NODE_NAME     U153 1
 '@T6G_MB_LIB.T6G(SCH_1):PAGE151_I1@PURE_QUANTA.SN74AUC2G66DCTR(CHIPS)':
 '1A': CDS_PINID='\1a\';
NODE_NAME     U153 5
 '@T6G_MB_LIB.T6G(SCH_1):PAGE151_I1@PURE_QUANTA.SN74AUC2G66DCTR(CHIPS)':
 '2A': CDS_PINID='\2a\';
NODE_NAME     R6103 2
 '@T6G_MB_LIB.T6G(SCH_1):PAGE150_I76@PURE_QUANTA.Q_RES(CHIPS)':
 'B': CDS_PINID='B';
NET_NAME
'JTAG_CPUX_TDI_R1'
 '@T6G_MB_LIB.T6G(SCH_1):JTAG_CPUX_TDI_R1':
 C_SIGNAL='@t6g_mb_lib.t6g(sch_1):jtag_cpux_tdi_r1';
NODE_NAME     U152 5
 '@T6G_MB_LIB.T6G(SCH_1):PAGE150_I60@PURE_QUANTA.SN74AVC2T245RSWR(CHIPS)':
 'B1': CDS_PINID='B1';
NODE_NAME     R6103 1
 '@T6G_MB_LIB.T6G(SCH_1):PAGE150_I76@PURE_QUANTA.Q_RES(CHIPS)':
 'A': CDS_PINID='A';
NET_NAME
'JTAG_CPUX_TDO'
 '@T6G_MB_LIB.T6G(SCH_1):JTAG_CPUX_TDO':
 C_SIGNAL='@t6g_mb_lib.t6g(sch_1):jtag_cpux_tdo';
NODE_NAME     U152 4
 '@T6G_MB_LIB.T6G(SCH_1):PAGE150_I60@PURE_QUANTA.SN74AVC2T245RSWR(CHIPS)':
 'B2': CDS_PINID='B2';
NODE_NAME     R6110 2
 '@T6G_MB_LIB.T6G(SCH_1):PAGE151_I50@PURE_QUANTA.Q_RES(CHIPS)':
 'B': CDS_PINID='B';
NET_NAME
'JTAG_CPUX_TDO_R'
 '@T6G_MB_LIB.T6G(SCH_1):JTAG_CPUX_TDO_R':
 C_SIGNAL='@t6g_mb_lib.t6g(sch_1):jtag_cpux_tdo_r';
NODE_NAME     U154 2
 '@T6G_MB_LIB.T6G(SCH_1):PAGE151_I31@PURE_QUANTA.SN74AUC2G66DCTR(CHIPS)':
 '1B': CDS_PINID='\1b\';
NODE_NAME     U154 6
 '@T6G_MB_LIB.T6G(SCH_1):PAGE151_I31@PURE_QUANTA.SN74AUC2G66DCTR(CHIPS)':
 '2B': CDS_PINID='\2b\';
NODE_NAME     R6110 1
 '@T6G_MB_LIB.T6G(SCH_1):PAGE151_I50@PURE_QUANTA.Q_RES(CHIPS)':
 'A': CDS_PINID='A';
NET_NAME
'JTAG_DBREQ_N'
 '@T6G_MB_LIB.T6G(SCH_1):JTAG_DBREQ_N':
 C_SIGNAL='@t6g_mb_lib.t6g(sch_1):jtag_dbreq_n';
NODE_NAME     R1636 2
 '@T6G_MB_LIB.T6G(SCH_1):PAGE149_I9@PURE_QUANTA.Q_RES(CHIPS)':
 'B': CDS_PINID='B';
NODE_NAME     C1512 1
 '@T6G_MB_LIB.T6G(SCH_1):PAGE149_I21@PURE_QUANTA.Q_CAP(CHIPS)':
 'A': CDS_PINID='A';
NODE_NAME     U150 6
 '@T6G_MB_LIB.T6G(SCH_1):PAGE150_I8@PURE_QUANTA.SN74AVC4T774PWR(CHIPS)':
 'A4': CDS_PINID='A4';
NODE_NAME     U151 6
 '@T6G_MB_LIB.T6G(SCH_1):PAGE150_I28@PURE_QUANTA.SN74AVC4T774PWR(CHIPS)':
 'A4': CDS_PINID='A4';
NET_NAME
'JTAG_DBREQ_R_N'
 '@T6G_MB_LIB.T6G(SCH_1):JTAG_DBREQ_R_N':
 C_SIGNAL='@t6g_mb_lib.t6g(sch_1):jtag_dbreq_r_n';
NODE_NAME     R1636 1
 '@T6G_MB_LIB.T6G(SCH_1):PAGE149_I9@PURE_QUANTA.Q_RES(CHIPS)':
 'A': CDS_PINID='A';
NODE_NAME     U149 11
 '@T6G_MB_LIB.T6G(SCH_1):PAGE149_I31@PURE_QUANTA.SN74AVC4T774PWR(CHIPS)':
 'B4': CDS_PINID='B4';
NODE_NAME     U148 11
 '@T6G_MB_LIB.T6G(SCH_1):PAGE149_I34@PURE_QUANTA.SN74AVC4T774PWR(CHIPS)':
 'B4': CDS_PINID='B4';
NET_NAME
'JTAG_P0_R_DBREQ_N'
 '@T6G_MB_LIB.T6G(SCH_1):JTAG_P0_R_DBREQ_N':
 C_SIGNAL='@t6g_mb_lib.t6g(sch_1):jtag_p0_r_dbreq_n';
NODE_NAME     U150 11
 '@T6G_MB_LIB.T6G(SCH_1):PAGE150_I8@PURE_QUANTA.SN74AVC4T774PWR(CHIPS)':
 'B4': CDS_PINID='B4';
NODE_NAME     R1641 1
 '@T6G_MB_LIB.T6G(SCH_1):PAGE150_I24@PURE_QUANTA.Q_RES(CHIPS)':
 'A': CDS_PINID='A';
NET_NAME
'JTAG_P0_R_TCK'
 '@T6G_MB_LIB.T6G(SCH_1):JTAG_P0_R_TCK':
 C_SIGNAL='@t6g_mb_lib.t6g(sch_1):jtag_p0_r_tck';
NODE_NAME     U150 14
 '@T6G_MB_LIB.T6G(SCH_1):PAGE150_I8@PURE_QUANTA.SN74AVC4T774PWR(CHIPS)':
 'B1': CDS_PINID='B1';
NODE_NAME     R1638 1
 '@T6G_MB_LIB.T6G(SCH_1):PAGE150_I27@PURE_QUANTA.Q_RES(CHIPS)':
 'A': CDS_PINID='A';
NET_NAME
'JTAG_P0_R_TMS'
 '@T6G_MB_LIB.T6G(SCH_1):JTAG_P0_R_TMS':
 C_SIGNAL='@t6g_mb_lib.t6g(sch_1):jtag_p0_r_tms';
NODE_NAME     U150 13
 '@T6G_MB_LIB.T6G(SCH_1):PAGE150_I8@PURE_QUANTA.SN74AVC4T774PWR(CHIPS)':
 'B2': CDS_PINID='B2';
NODE_NAME     R1639 1
 '@T6G_MB_LIB.T6G(SCH_1):PAGE150_I25@PURE_QUANTA.Q_RES(CHIPS)':
 'A': CDS_PINID='A';
NET_NAME
'JTAG_P0_R_TRST_N'
 '@T6G_MB_LIB.T6G(SCH_1):JTAG_P0_R_TRST_N':
 C_SIGNAL='@t6g_mb_lib.t6g(sch_1):jtag_p0_r_trst_n';
NODE_NAME     U150 12
 '@T6G_MB_LIB.T6G(SCH_1):PAGE150_I8@PURE_QUANTA.SN74AVC4T774PWR(CHIPS)':
 'B3': CDS_PINID='B3';
NODE_NAME     R1640 1
 '@T6G_MB_LIB.T6G(SCH_1):PAGE150_I26@PURE_QUANTA.Q_RES(CHIPS)':
 'A': CDS_PINID='A';
NET_NAME
'JTAG_P1_R_DBREQ_N'
 '@T6G_MB_LIB.T6G(SCH_1):JTAG_P1_R_DBREQ_N':
 C_SIGNAL='@t6g_mb_lib.t6g(sch_1):jtag_p1_r_dbreq_n';
NODE_NAME     U151 11
 '@T6G_MB_LIB.T6G(SCH_1):PAGE150_I28@PURE_QUANTA.SN74AVC4T774PWR(CHIPS)':
 'B4': CDS_PINID='B4';
NODE_NAME     R1645 1
 '@T6G_MB_LIB.T6G(SCH_1):PAGE150_I36@PURE_QUANTA.Q_RES(CHIPS)':
 'A': CDS_PINID='A';
NET_NAME
'JTAG_P1_R_TCK'
 '@T6G_MB_LIB.T6G(SCH_1):JTAG_P1_R_TCK':
 C_SIGNAL='@t6g_mb_lib.t6g(sch_1):jtag_p1_r_tck';
NODE_NAME     U151 14
 '@T6G_MB_LIB.T6G(SCH_1):PAGE150_I28@PURE_QUANTA.SN74AVC4T774PWR(CHIPS)':
 'B1': CDS_PINID='B1';
NODE_NAME     R1642 1
 '@T6G_MB_LIB.T6G(SCH_1):PAGE150_I33@PURE_QUANTA.Q_RES(CHIPS)':
 'A': CDS_PINID='A';
NET_NAME
'JTAG_P1_R_TMS'
 '@T6G_MB_LIB.T6G(SCH_1):JTAG_P1_R_TMS':
 C_SIGNAL='@t6g_mb_lib.t6g(sch_1):jtag_p1_r_tms';
NODE_NAME     U151 13
 '@T6G_MB_LIB.T6G(SCH_1):PAGE150_I28@PURE_QUANTA.SN74AVC4T774PWR(CHIPS)':
 'B2': CDS_PINID='B2';
NODE_NAME     R1643 1
 '@T6G_MB_LIB.T6G(SCH_1):PAGE150_I34@PURE_QUANTA.Q_RES(CHIPS)':
 'A': CDS_PINID='A';
NET_NAME
'JTAG_P1_R_TRST_N'
 '@T6G_MB_LIB.T6G(SCH_1):JTAG_P1_R_TRST_N':
 C_SIGNAL='@t6g_mb_lib.t6g(sch_1):jtag_p1_r_trst_n';
NODE_NAME     U151 12
 '@T6G_MB_LIB.T6G(SCH_1):PAGE150_I28@PURE_QUANTA.SN74AVC4T774PWR(CHIPS)':
 'B3': CDS_PINID='B3';
NODE_NAME     R1644 1
 '@T6G_MB_LIB.T6G(SCH_1):PAGE150_I35@PURE_QUANTA.Q_RES(CHIPS)':
 'A': CDS_PINID='A';
NET_NAME
'JTAG_PLD_TCK'
 '@T6G_MB_LIB.T6G(SCH_1):JTAG_PLD_TCK':
 C_SIGNAL='@t6g_mb_lib.t6g(sch_1):jtag_pld_tck';
NODE_NAME     J57 8
 '@T6G_MB_LIB.T6G(SCH_1):PAGE84_I41@PURE_QUANTA.CONN8_HBB1081L200D8H(CHIPS)':
 '8': CDS_PINID='\8\';
NODE_NAME     R15 1
 '@T6G_MB_LIB.T6G(SCH_1):PAGE84_I35@PURE_QUANTA.Q_RES(CHIPS)':
 'A': CDS_PINID='A';
NET_NAME
'JTAG_PLD_TDI'
 '@T6G_MB_LIB.T6G(SCH_1):JTAG_PLD_TDI':
 C_SIGNAL='@t6g_mb_lib.t6g(sch_1):jtag_pld_tdi';
NODE_NAME     R9 1
 '@T6G_MB_LIB.T6G(SCH_1):PAGE84_I37@PURE_QUANTA.Q_RES(CHIPS)':
 'A': CDS_PINID='A';
NODE_NAME     J57 2
 '@T6G_MB_LIB.T6G(SCH_1):PAGE84_I41@PURE_QUANTA.CONN8_HBB1081L200D8H(CHIPS)':
 '2': CDS_PINID='\2\';
NET_NAME
'JTAG_PLD_TDO'
 '@T6G_MB_LIB.T6G(SCH_1):JTAG_PLD_TDO':
 C_SIGNAL='@t6g_mb_lib.t6g(sch_1):jtag_pld_tdo';
NODE_NAME     R13 1
 '@T6G_MB_LIB.T6G(SCH_1):PAGE84_I38@PURE_QUANTA.Q_RES(CHIPS)':
 'A': CDS_PINID='A';
NODE_NAME     J57 3
 '@T6G_MB_LIB.T6G(SCH_1):PAGE84_I41@PURE_QUANTA.CONN8_HBB1081L200D8H(CHIPS)':
 '3': CDS_PINID='\3\';
NET_NAME
'JTAG_PLD_TMS'
 '@T6G_MB_LIB.T6G(SCH_1):JTAG_PLD_TMS':
 C_SIGNAL='@t6g_mb_lib.t6g(sch_1):jtag_pld_tms';
NODE_NAME     R14 1
 '@T6G_MB_LIB.T6G(SCH_1):PAGE84_I36@PURE_QUANTA.Q_RES(CHIPS)':
 'A': CDS_PINID='A';
NODE_NAME     J57 6
 '@T6G_MB_LIB.T6G(SCH_1):PAGE84_I41@PURE_QUANTA.CONN8_HBB1081L200D8H(CHIPS)':
 '6': CDS_PINID='\6\';
NET_NAME
'JTAG_SCM_DBREQ_N'
 '@T6G_MB_LIB.T6G(SCH_1):JTAG_SCM_DBREQ_N':
 C_SIGNAL='@t6g_mb_lib.t6g(sch_1):jtag_scm_dbreq_n';
NODE_NAME     U148 6
 '@T6G_MB_LIB.T6G(SCH_1):PAGE149_I34@PURE_QUANTA.SN74AVC4T774PWR(CHIPS)':
 'A4': CDS_PINID='A4';
NODE_NAME     R6032 1
 '@T6G_MB_LIB.T6G(SCH_1):PAGE348_I28@PURE_QUANTA.Q_RES(CHIPS)':
 'A': CDS_PINID='A';
NODE_NAME     R6070 2
 '@T6G_MB_LIB.T6G(SCH_1):PAGE349_I161@PURE_QUANTA.Q_RES(CHIPS)':
 'B': CDS_PINID='B';
NET_NAME
'JTAG_SCM_MUX_R_TCK'
 '@T6G_MB_LIB.T6G(SCH_1):JTAG_SCM_MUX_R_TCK':
 C_SIGNAL='@t6g_mb_lib.t6g(sch_1):jtag_scm_mux_r_tck';
NODE_NAME     U160 14
 '@T6G_MB_LIB.T6G(SCH_1):PAGE148_I266@PURE_QUANTA.74LV4052PW(CHIPS)':
 '1Y1': CDS_PINID='\1y1\';
NODE_NAME     R1736 1
 '@T6G_MB_LIB.T6G(SCH_1):PAGE148_I363@PURE_QUANTA.Q_RES(CHIPS)':
 'A': CDS_PINID='A';
NET_NAME
'JTAG_SCM_MUX_R_TDI'
 '@T6G_MB_LIB.T6G(SCH_1):JTAG_SCM_MUX_R_TDI':
 C_SIGNAL='@t6g_mb_lib.t6g(sch_1):jtag_scm_mux_r_tdi';
NODE_NAME     U212 14
 '@T6G_MB_LIB.T6G(SCH_1):PAGE148_I302@PURE_QUANTA.74LV4052PW(CHIPS)':
 '1Y1': CDS_PINID='\1y1\';
NODE_NAME     R1738 1
 '@T6G_MB_LIB.T6G(SCH_1):PAGE148_I349@PURE_QUANTA.Q_RES(CHIPS)':
 'A': CDS_PINID='A';
NET_NAME
'JTAG_SCM_MUX_R_TDO'
 '@T6G_MB_LIB.T6G(SCH_1):JTAG_SCM_MUX_R_TDO':
 C_SIGNAL='@t6g_mb_lib.t6g(sch_1):jtag_scm_mux_r_tdo';
NODE_NAME     U212 5
 '@T6G_MB_LIB.T6G(SCH_1):PAGE148_I302@PURE_QUANTA.74LV4052PW(CHIPS)':
 '2Y1': CDS_PINID='\2y1\';
NODE_NAME     R1739 1
 '@T6G_MB_LIB.T6G(SCH_1):PAGE148_I388@PURE_QUANTA.Q_RES(CHIPS)':
 'A': CDS_PINID='A';
NET_NAME
'JTAG_SCM_MUX_R_TMS'
 '@T6G_MB_LIB.T6G(SCH_1):JTAG_SCM_MUX_R_TMS':
 C_SIGNAL='@t6g_mb_lib.t6g(sch_1):jtag_scm_mux_r_tms';
NODE_NAME     U160 5
 '@T6G_MB_LIB.T6G(SCH_1):PAGE148_I266@PURE_QUANTA.74LV4052PW(CHIPS)':
 '2Y1': CDS_PINID='\2y1\';
NODE_NAME     R1737 1
 '@T6G_MB_LIB.T6G(SCH_1):PAGE148_I357@PURE_QUANTA.Q_RES(CHIPS)':
 'A': CDS_PINID='A';
NET_NAME
'JTAG_SCM_MUX_TCK'
 '@T6G_MB_LIB.T6G(SCH_1):JTAG_SCM_MUX_TCK':
 C_SIGNAL='@t6g_mb_lib.t6g(sch_1):jtag_scm_mux_tck';
NODE_NAME     R1747 2
 '@T6G_MB_LIB.T6G(SCH_1):PAGE148_I255@PURE_QUANTA.Q_RES(CHIPS)':
 'B': CDS_PINID='B';
NODE_NAME     R1748 1
 '@T6G_MB_LIB.T6G(SCH_1):PAGE148_I258@PURE_QUANTA.Q_RES(CHIPS)':
 'A': CDS_PINID='A';
NODE_NAME     R1736 2
 '@T6G_MB_LIB.T6G(SCH_1):PAGE148_I363@PURE_QUANTA.Q_RES(CHIPS)':
 'B': CDS_PINID='B';
NODE_NAME     U148 3
 '@T6G_MB_LIB.T6G(SCH_1):PAGE149_I34@PURE_QUANTA.SN74AVC4T774PWR(CHIPS)':
 'A1': CDS_PINID='A1';
NET_NAME
'JTAG_SCM_MUX_TDI'
 '@T6G_MB_LIB.T6G(SCH_1):JTAG_SCM_MUX_TDI':
 C_SIGNAL='@t6g_mb_lib.t6g(sch_1):jtag_scm_mux_tdi';
NODE_NAME     R1744 2
 '@T6G_MB_LIB.T6G(SCH_1):PAGE148_I261@PURE_QUANTA.Q_RES(CHIPS)':
 'B': CDS_PINID='B';
NODE_NAME     R1738 2
 '@T6G_MB_LIB.T6G(SCH_1):PAGE148_I349@PURE_QUANTA.Q_RES(CHIPS)':
 'B': CDS_PINID='B';
NODE_NAME     U147 9
 '@T6G_MB_LIB.T6G(SCH_1):PAGE149_I1@PURE_QUANTA.SN74AVC2T245RSWR(CHIPS)':
 'A2': CDS_PINID='A2';
NET_NAME
'JTAG_SCM_MUX_TDO'
 '@T6G_MB_LIB.T6G(SCH_1):JTAG_SCM_MUX_TDO':
 C_SIGNAL='@t6g_mb_lib.t6g(sch_1):jtag_scm_mux_tdo';
NODE_NAME     R1745 2
 '@T6G_MB_LIB.T6G(SCH_1):PAGE148_I257@PURE_QUANTA.Q_RES(CHIPS)':
 'B': CDS_PINID='B';
NODE_NAME     U147 8
 '@T6G_MB_LIB.T6G(SCH_1):PAGE149_I1@PURE_QUANTA.SN74AVC2T245RSWR(CHIPS)':
 'A1': CDS_PINID='A1';
NODE_NAME     R1739 2
 '@T6G_MB_LIB.T6G(SCH_1):PAGE148_I388@PURE_QUANTA.Q_RES(CHIPS)':
 'B': CDS_PINID='B';
NET_NAME
'JTAG_SCM_MUX_TMS'
 '@T6G_MB_LIB.T6G(SCH_1):JTAG_SCM_MUX_TMS':
 C_SIGNAL='@t6g_mb_lib.t6g(sch_1):jtag_scm_mux_tms';
NODE_NAME     R1746 2
 '@T6G_MB_LIB.T6G(SCH_1):PAGE148_I256@PURE_QUANTA.Q_RES(CHIPS)':
 'B': CDS_PINID='B';
NODE_NAME     R1737 2
 '@T6G_MB_LIB.T6G(SCH_1):PAGE148_I357@PURE_QUANTA.Q_RES(CHIPS)':
 'B': CDS_PINID='B';
NODE_NAME     U148 4
 '@T6G_MB_LIB.T6G(SCH_1):PAGE149_I34@PURE_QUANTA.SN74AVC4T774PWR(CHIPS)':
 'A2': CDS_PINID='A2';
NET_NAME
'JTAG_SCM_PLD_R_TCK'
 '@T6G_MB_LIB.T6G(SCH_1):JTAG_SCM_PLD_R_TCK':
 C_SIGNAL='@t6g_mb_lib.t6g(sch_1):jtag_scm_pld_r_tck';
NODE_NAME     U160 15
 '@T6G_MB_LIB.T6G(SCH_1):PAGE148_I266@PURE_QUANTA.74LV4052PW(CHIPS)':
 '1Y2': CDS_PINID='\1y2\';
NODE_NAME     U160 11
 '@T6G_MB_LIB.T6G(SCH_1):PAGE148_I266@PURE_QUANTA.74LV4052PW(CHIPS)':
 '1Y3': CDS_PINID='\1y3\';
NODE_NAME     R1740 1
 '@T6G_MB_LIB.T6G(SCH_1):PAGE148_I368@PURE_QUANTA.Q_RES(CHIPS)':
 'A': CDS_PINID='A';
NET_NAME
'JTAG_SCM_PLD_R_TDI'
 '@T6G_MB_LIB.T6G(SCH_1):JTAG_SCM_PLD_R_TDI':
 C_SIGNAL='@t6g_mb_lib.t6g(sch_1):jtag_scm_pld_r_tdi';
NODE_NAME     U212 15
 '@T6G_MB_LIB.T6G(SCH_1):PAGE148_I302@PURE_QUANTA.74LV4052PW(CHIPS)':
 '1Y2': CDS_PINID='\1y2\';
NODE_NAME     U212 11
 '@T6G_MB_LIB.T6G(SCH_1):PAGE148_I302@PURE_QUANTA.74LV4052PW(CHIPS)':
 '1Y3': CDS_PINID='\1y3\';
NODE_NAME     R1742 1
 '@T6G_MB_LIB.T6G(SCH_1):PAGE148_I352@PURE_QUANTA.Q_RES(CHIPS)':
 'A': CDS_PINID='A';
NET_NAME
'JTAG_SCM_PLD_R_TDO'
 '@T6G_MB_LIB.T6G(SCH_1):JTAG_SCM_PLD_R_TDO':
 C_SIGNAL='@t6g_mb_lib.t6g(sch_1):jtag_scm_pld_r_tdo';
NODE_NAME     U212 2
 '@T6G_MB_LIB.T6G(SCH_1):PAGE148_I302@PURE_QUANTA.74LV4052PW(CHIPS)':
 '2Y2': CDS_PINID='\2y2\';
NODE_NAME     U212 4
 '@T6G_MB_LIB.T6G(SCH_1):PAGE148_I302@PURE_QUANTA.74LV4052PW(CHIPS)':
 '2Y3': CDS_PINID='\2y3\';
NODE_NAME     R1743 1
 '@T6G_MB_LIB.T6G(SCH_1):PAGE148_I332@PURE_QUANTA.Q_RES(CHIPS)':
 'A': CDS_PINID='A';
NET_NAME
'JTAG_SCM_PLD_R_TMS'
 '@T6G_MB_LIB.T6G(SCH_1):JTAG_SCM_PLD_R_TMS':
 C_SIGNAL='@t6g_mb_lib.t6g(sch_1):jtag_scm_pld_r_tms';
NODE_NAME     U160 2
 '@T6G_MB_LIB.T6G(SCH_1):PAGE148_I266@PURE_QUANTA.74LV4052PW(CHIPS)':
 '2Y2': CDS_PINID='\2y2\';
NODE_NAME     U160 4
 '@T6G_MB_LIB.T6G(SCH_1):PAGE148_I266@PURE_QUANTA.74LV4052PW(CHIPS)':
 '2Y3': CDS_PINID='\2y3\';
NODE_NAME     R1741 1
 '@T6G_MB_LIB.T6G(SCH_1):PAGE148_I366@PURE_QUANTA.Q_RES(CHIPS)':
 'A': CDS_PINID='A';
NET_NAME
'JTAG_SCM_PLD_TCK'
 '@T6G_MB_LIB.T6G(SCH_1):JTAG_SCM_PLD_TCK':
 C_SIGNAL='@t6g_mb_lib.t6g(sch_1):jtag_scm_pld_tck';
NODE_NAME     R1740 2
 '@T6G_MB_LIB.T6G(SCH_1):PAGE148_I368@PURE_QUANTA.Q_RES(CHIPS)':
 'B': CDS_PINID='B';
NODE_NAME     U18 D10
 '@T6G_MB_LIB.T6G(SCH_1):PAGE79_I25@PURE_QUANTA.LCMXO3LF9400C5BG484C(CHIPS)':
 'PT22C||TCK': CDS_PINID='\pt22c||tck\';
NODE_NAME     R15 2
 '@T6G_MB_LIB.T6G(SCH_1):PAGE84_I35@PURE_QUANTA.Q_RES(CHIPS)':
 'B': CDS_PINID='B';
NODE_NAME     R6090 1
 '@T6G_MB_LIB.T6G(SCH_1):PAGE84_I77@PURE_QUANTA.Q_RES(CHIPS)':
 'A': CDS_PINID='A';
NET_NAME
'JTAG_SCM_PLD_TDI'
 '@T6G_MB_LIB.T6G(SCH_1):JTAG_SCM_PLD_TDI':
 C_SIGNAL='@t6g_mb_lib.t6g(sch_1):jtag_scm_pld_tdi';
NODE_NAME     R1742 2
 '@T6G_MB_LIB.T6G(SCH_1):PAGE148_I352@PURE_QUANTA.Q_RES(CHIPS)':
 'B': CDS_PINID='B';
NODE_NAME     R9 2
 '@T6G_MB_LIB.T6G(SCH_1):PAGE84_I37@PURE_QUANTA.Q_RES(CHIPS)':
 'B': CDS_PINID='B';
NODE_NAME     U18 E8
 '@T6G_MB_LIB.T6G(SCH_1):PAGE79_I25@PURE_QUANTA.LCMXO3LF9400C5BG484C(CHIPS)':
 'PT15C||TDO': CDS_PINID='\pt15c||tdo\';
NET_NAME
'JTAG_SCM_PLD_TDO'
 '@T6G_MB_LIB.T6G(SCH_1):JTAG_SCM_PLD_TDO':
 C_SIGNAL='@t6g_mb_lib.t6g(sch_1):jtag_scm_pld_tdo';
NODE_NAME     R1743 2
 '@T6G_MB_LIB.T6G(SCH_1):PAGE148_I332@PURE_QUANTA.Q_RES(CHIPS)':
 'B': CDS_PINID='B';
NODE_NAME     R13 2
 '@T6G_MB_LIB.T6G(SCH_1):PAGE84_I38@PURE_QUANTA.Q_RES(CHIPS)':
 'B': CDS_PINID='B';
NODE_NAME     U18 E9
 '@T6G_MB_LIB.T6G(SCH_1):PAGE79_I25@PURE_QUANTA.LCMXO3LF9400C5BG484C(CHIPS)':
 'PT15D||TDI': CDS_PINID='\pt15d||tdi\';
NET_NAME
'JTAG_SCM_PLD_TMS'
 '@T6G_MB_LIB.T6G(SCH_1):JTAG_SCM_PLD_TMS':
 C_SIGNAL='@t6g_mb_lib.t6g(sch_1):jtag_scm_pld_tms';
NODE_NAME     R1741 2
 '@T6G_MB_LIB.T6G(SCH_1):PAGE148_I366@PURE_QUANTA.Q_RES(CHIPS)':
 'B': CDS_PINID='B';
NODE_NAME     R14 2
 '@T6G_MB_LIB.T6G(SCH_1):PAGE84_I36@PURE_QUANTA.Q_RES(CHIPS)':
 'B': CDS_PINID='B';
NODE_NAME     U18 C10
 '@T6G_MB_LIB.T6G(SCH_1):PAGE79_I25@PURE_QUANTA.LCMXO3LF9400C5BG484C(CHIPS)':
 'PT22D||TMS': CDS_PINID='\pt22d||tms\';
NET_NAME
'JTAG_SCM_TCK'
 '@T6G_MB_LIB.T6G(SCH_1):JTAG_SCM_TCK':
 C_SIGNAL='@t6g_mb_lib.t6g(sch_1):jtag_scm_tck';
NODE_NAME     R1734 2
 '@T6G_MB_LIB.T6G(SCH_1):PAGE148_I244@PURE_QUANTA.Q_RES(CHIPS)':
 'B': CDS_PINID='B';
NODE_NAME     R1735 1
 '@T6G_MB_LIB.T6G(SCH_1):PAGE148_I246@PURE_QUANTA.Q_RES(CHIPS)':
 'A': CDS_PINID='A';
NODE_NAME     U160 13
 '@T6G_MB_LIB.T6G(SCH_1):PAGE148_I266@PURE_QUANTA.74LV4052PW(CHIPS)':
 '1Z': CDS_PINID='\1z\';
NODE_NAME     J41 A34
 '@T6G_MB_LIB.T6G(SCH_1):PAGE348_I176@PURE_QUANTA.SCONN168_ME1016810202011(CHIPS)':
 'PERP5': CDS_PINID='PERP5';
NET_NAME
'JTAG_SCM_TDI'
 '@T6G_MB_LIB.T6G(SCH_1):JTAG_SCM_TDI':
 C_SIGNAL='@t6g_mb_lib.t6g(sch_1):jtag_scm_tdi';
NODE_NAME     R1728 2
 '@T6G_MB_LIB.T6G(SCH_1):PAGE148_I249@PURE_QUANTA.Q_RES(CHIPS)':
 'B': CDS_PINID='B';
NODE_NAME     U212 13
 '@T6G_MB_LIB.T6G(SCH_1):PAGE148_I302@PURE_QUANTA.74LV4052PW(CHIPS)':
 '1Z': CDS_PINID='\1z\';
NODE_NAME     R6066 2
 '@T6G_MB_LIB.T6G(SCH_1):PAGE349_I150@PURE_QUANTA.Q_RES(CHIPS)':
 'B': CDS_PINID='B';
NODE_NAME     R6067 2
 '@T6G_MB_LIB.T6G(SCH_1):PAGE349_I159@PURE_QUANTA.Q_RES(CHIPS)':
 'B': CDS_PINID='B';
NET_NAME
'JTAG_SCM_TDI_R'
 '@T6G_MB_LIB.T6G(SCH_1):JTAG_SCM_TDI_R':
 C_SIGNAL='@t6g_mb_lib.t6g(sch_1):jtag_scm_tdi_r';
NODE_NAME     J41 A36
 '@T6G_MB_LIB.T6G(SCH_1):PAGE348_I176@PURE_QUANTA.SCONN168_ME1016810202011(CHIPS)':
 'PERN6': CDS_PINID='PERN6';
NODE_NAME     R6066 1
 '@T6G_MB_LIB.T6G(SCH_1):PAGE349_I150@PURE_QUANTA.Q_RES(CHIPS)':
 'A': CDS_PINID='A';
NODE_NAME     R6069 1
 '@T6G_MB_LIB.T6G(SCH_1):PAGE349_I158@PURE_QUANTA.Q_RES(CHIPS)':
 'A': CDS_PINID='A';
NET_NAME
'JTAG_SCM_TDO'
 '@T6G_MB_LIB.T6G(SCH_1):JTAG_SCM_TDO':
 C_SIGNAL='@t6g_mb_lib.t6g(sch_1):jtag_scm_tdo';
NODE_NAME     R1727 2
 '@T6G_MB_LIB.T6G(SCH_1):PAGE148_I250@PURE_QUANTA.Q_RES(CHIPS)':
 'B': CDS_PINID='B';
NODE_NAME     U212 3
 '@T6G_MB_LIB.T6G(SCH_1):PAGE148_I302@PURE_QUANTA.74LV4052PW(CHIPS)':
 '2Z': CDS_PINID='\2z\';
NODE_NAME     R6068 2
 '@T6G_MB_LIB.T6G(SCH_1):PAGE349_I151@PURE_QUANTA.Q_RES(CHIPS)':
 'B': CDS_PINID='B';
NODE_NAME     R6069 2
 '@T6G_MB_LIB.T6G(SCH_1):PAGE349_I158@PURE_QUANTA.Q_RES(CHIPS)':
 'B': CDS_PINID='B';
NET_NAME
'JTAG_SCM_TDO_R'
 '@T6G_MB_LIB.T6G(SCH_1):JTAG_SCM_TDO_R':
 C_SIGNAL='@t6g_mb_lib.t6g(sch_1):jtag_scm_tdo_r';
NODE_NAME     J41 A37
 '@T6G_MB_LIB.T6G(SCH_1):PAGE348_I176@PURE_QUANTA.SCONN168_ME1016810202011(CHIPS)':
 'PERP6': CDS_PINID='PERP6';
NODE_NAME     R6068 1
 '@T6G_MB_LIB.T6G(SCH_1):PAGE349_I151@PURE_QUANTA.Q_RES(CHIPS)':
 'A': CDS_PINID='A';
NODE_NAME     R6067 1
 '@T6G_MB_LIB.T6G(SCH_1):PAGE349_I159@PURE_QUANTA.Q_RES(CHIPS)':
 'A': CDS_PINID='A';
NET_NAME
'JTAG_SCM_TMS'
 '@T6G_MB_LIB.T6G(SCH_1):JTAG_SCM_TMS':
 C_SIGNAL='@t6g_mb_lib.t6g(sch_1):jtag_scm_tms';
NODE_NAME     R1731 2
 '@T6G_MB_LIB.T6G(SCH_1):PAGE148_I245@PURE_QUANTA.Q_RES(CHIPS)':
 'B': CDS_PINID='B';
NODE_NAME     U160 3
 '@T6G_MB_LIB.T6G(SCH_1):PAGE148_I266@PURE_QUANTA.74LV4052PW(CHIPS)':
 '2Z': CDS_PINID='\2z\';
NODE_NAME     J41 A35
 '@T6G_MB_LIB.T6G(SCH_1):PAGE348_I176@PURE_QUANTA.SCONN168_ME1016810202011(CHIPS)':
 'GND_A35': CDS_PINID='GND_A35';
NET_NAME
'JTAG_SCM_TRST_N'
 '@T6G_MB_LIB.T6G(SCH_1):JTAG_SCM_TRST_N':
 C_SIGNAL='@t6g_mb_lib.t6g(sch_1):jtag_scm_trst_n';
NODE_NAME     U148 5
 '@T6G_MB_LIB.T6G(SCH_1):PAGE149_I34@PURE_QUANTA.SN74AVC4T774PWR(CHIPS)':
 'A3': CDS_PINID='A3';
NODE_NAME     R160 2
 '@T6G_MB_LIB.T6G(SCH_1):PAGE79_I16@PURE_QUANTA.Q_RES(CHIPS)':
 'B': CDS_PINID='B';
NET_NAME
'JTAG_SCM_TRST_R_N'
 '@T6G_MB_LIB.T6G(SCH_1):JTAG_SCM_TRST_R_N':
 C_SIGNAL='@t6g_mb_lib.t6g(sch_1):jtag_scm_trst_r_n';
NODE_NAME     R160 1
 '@T6G_MB_LIB.T6G(SCH_1):PAGE79_I16@PURE_QUANTA.Q_RES(CHIPS)':
 'A': CDS_PINID='A';
NODE_NAME     U18 D11
 '@T6G_MB_LIB.T6G(SCH_1):PAGE79_I94@PURE_QUANTA.LCMXO3LF9400C5BG484C(CHIPS)':
 'PT24D': CDS_PINID='PT24D';
NET_NAME
'JTAG_TCK'
 '@T6G_MB_LIB.T6G(SCH_1):JTAG_TCK':
 C_SIGNAL='@t6g_mb_lib.t6g(sch_1):jtag_tck';
NODE_NAME     R1633 2
 '@T6G_MB_LIB.T6G(SCH_1):PAGE149_I7@PURE_QUANTA.Q_RES(CHIPS)':
 'B': CDS_PINID='B';
NODE_NAME     C1510 1
 '@T6G_MB_LIB.T6G(SCH_1):PAGE149_I25@PURE_QUANTA.Q_CAP(CHIPS)':
 'A': CDS_PINID='A';
NODE_NAME     U150 3
 '@T6G_MB_LIB.T6G(SCH_1):PAGE150_I8@PURE_QUANTA.SN74AVC4T774PWR(CHIPS)':
 'A1': CDS_PINID='A1';
NODE_NAME     U151 3
 '@T6G_MB_LIB.T6G(SCH_1):PAGE150_I28@PURE_QUANTA.SN74AVC4T774PWR(CHIPS)':
 'A1': CDS_PINID='A1';
NET_NAME
'JTAG_TCK_R'
 '@T6G_MB_LIB.T6G(SCH_1):JTAG_TCK_R':
 C_SIGNAL='@t6g_mb_lib.t6g(sch_1):jtag_tck_r';
NODE_NAME     R1633 1
 '@T6G_MB_LIB.T6G(SCH_1):PAGE149_I7@PURE_QUANTA.Q_RES(CHIPS)':
 'A': CDS_PINID='A';
NODE_NAME     U149 14
 '@T6G_MB_LIB.T6G(SCH_1):PAGE149_I31@PURE_QUANTA.SN74AVC4T774PWR(CHIPS)':
 'B1': CDS_PINID='B1';
NODE_NAME     U148 14
 '@T6G_MB_LIB.T6G(SCH_1):PAGE149_I34@PURE_QUANTA.SN74AVC4T774PWR(CHIPS)':
 'B1': CDS_PINID='B1';
NET_NAME
'JTAG_TCK_RT_CPU0_P0'
 '@T6G_MB_LIB.T6G(SCH_1):JTAG_TCK_RT_CPU0_P0':
 C_SIGNAL='@t6g_mb_lib.t6g(sch_1):jtag_tck_rt_cpu0_p0';
NODE_NAME     U6010 B3
 '@T6G_MB_LIB.T6G(SCH_1):PAGE385_I53@PURE_QUANTA.PT5161LRS(CHIPS)':
 'JTAG_TCK': CDS_PINID='JTAG_TCK';
NODE_NAME     R1365 1
 '@T6G_MB_LIB.T6G(SCH_1):PAGE385_I123@PURE_QUANTA.Q_RES(CHIPS)':
 'A': CDS_PINID='A';
NODE_NAME     R1446 2
 '@T6G_MB_LIB.T6G(SCH_1):PAGE385_I143@PURE_QUANTA.Q_RES(CHIPS)':
 'B': CDS_PINID='B';
NET_NAME
'JTAG_TCK_RT_CPU0_P1'
 '@T6G_MB_LIB.T6G(SCH_1):JTAG_TCK_RT_CPU0_P1':
 C_SIGNAL='@t6g_mb_lib.t6g(sch_1):jtag_tck_rt_cpu0_p1';
NODE_NAME     U6011 B3
 '@T6G_MB_LIB.T6G(SCH_1):PAGE408_I83@PURE_QUANTA.PT5161LRS(CHIPS)':
 'JTAG_TCK': CDS_PINID='JTAG_TCK';
NODE_NAME     R1392 1
 '@T6G_MB_LIB.T6G(SCH_1):PAGE408_I119@PURE_QUANTA.Q_RES(CHIPS)':
 'A': CDS_PINID='A';
NODE_NAME     R1473 2
 '@T6G_MB_LIB.T6G(SCH_1):PAGE408_I122@PURE_QUANTA.Q_RES(CHIPS)':
 'B': CDS_PINID='B';
NET_NAME
'JTAG_TCK_RT_CPU0_P2'
 '@T6G_MB_LIB.T6G(SCH_1):JTAG_TCK_RT_CPU0_P2':
 C_SIGNAL='@t6g_mb_lib.t6g(sch_1):jtag_tck_rt_cpu0_p2';
NODE_NAME     U6012 B3
 '@T6G_MB_LIB.T6G(SCH_1):PAGE419_I83@PURE_QUANTA.PT5161LRS(CHIPS)':
 'JTAG_TCK': CDS_PINID='JTAG_TCK';
NODE_NAME     R1401 1
 '@T6G_MB_LIB.T6G(SCH_1):PAGE419_I120@PURE_QUANTA.Q_RES(CHIPS)':
 'A': CDS_PINID='A';
NODE_NAME     R1479 2
 '@T6G_MB_LIB.T6G(SCH_1):PAGE419_I121@PURE_QUANTA.Q_RES(CHIPS)':
 'B': CDS_PINID='B';
NET_NAME
'JTAG_TCK_RT_CPU0_P3'
 '@T6G_MB_LIB.T6G(SCH_1):JTAG_TCK_RT_CPU0_P3':
 C_SIGNAL='@t6g_mb_lib.t6g(sch_1):jtag_tck_rt_cpu0_p3';
NODE_NAME     U6013 B3
 '@T6G_MB_LIB.T6G(SCH_1):PAGE430_I83@PURE_QUANTA.PT5161LRS(CHIPS)':
 'JTAG_TCK': CDS_PINID='JTAG_TCK';
NODE_NAME     R1409 1
 '@T6G_MB_LIB.T6G(SCH_1):PAGE430_I117@PURE_QUANTA.Q_RES(CHIPS)':
 'A': CDS_PINID='A';
NODE_NAME     R1485 2
 '@T6G_MB_LIB.T6G(SCH_1):PAGE430_I119@PURE_QUANTA.Q_RES(CHIPS)':
 'B': CDS_PINID='B';
NET_NAME
'JTAG_TCK_RT_CPU1_P0'
 '@T6G_MB_LIB.T6G(SCH_1):JTAG_TCK_RT_CPU1_P0':
 C_SIGNAL='@t6g_mb_lib.t6g(sch_1):jtag_tck_rt_cpu1_p0';
NODE_NAME     U6014 B3
 '@T6G_MB_LIB.T6G(SCH_1):PAGE401_I1@PURE_QUANTA.PT5161LRS(CHIPS)':
 'JTAG_TCK': CDS_PINID='JTAG_TCK';
NODE_NAME     R1381 1
 '@T6G_MB_LIB.T6G(SCH_1):PAGE401_I144@PURE_QUANTA.Q_RES(CHIPS)':
 'A': CDS_PINID='A';
NODE_NAME     R1467 2
 '@T6G_MB_LIB.T6G(SCH_1):PAGE401_I147@PURE_QUANTA.Q_RES(CHIPS)':
 'B': CDS_PINID='B';
NET_NAME
'JTAG_TCK_RT_CPU1_P1'
 '@T6G_MB_LIB.T6G(SCH_1):JTAG_TCK_RT_CPU1_P1':
 C_SIGNAL='@t6g_mb_lib.t6g(sch_1):jtag_tck_rt_cpu1_p1';
NODE_NAME     U6015 B3
 '@T6G_MB_LIB.T6G(SCH_1):PAGE392_I47@PURE_QUANTA.PT5161LRS(CHIPS)':
 'JTAG_TCK': CDS_PINID='JTAG_TCK';
NODE_NAME     R1373 1
 '@T6G_MB_LIB.T6G(SCH_1):PAGE392_I150@PURE_QUANTA.Q_RES(CHIPS)':
 'A': CDS_PINID='A';
NODE_NAME     R1461 2
 '@T6G_MB_LIB.T6G(SCH_1):PAGE392_I151@PURE_QUANTA.Q_RES(CHIPS)':
 'B': CDS_PINID='B';
NET_NAME
'JTAG_TCK_RT_CPU1_P2'
 '@T6G_MB_LIB.T6G(SCH_1):JTAG_TCK_RT_CPU1_P2':
 C_SIGNAL='@t6g_mb_lib.t6g(sch_1):jtag_tck_rt_cpu1_p2';
NODE_NAME     U6016 B3
 '@T6G_MB_LIB.T6G(SCH_1):PAGE451_I97@PURE_QUANTA.PT5161LRS(CHIPS)':
 'JTAG_TCK': CDS_PINID='JTAG_TCK';
NODE_NAME     R1417 1
 '@T6G_MB_LIB.T6G(SCH_1):PAGE451_I136@PURE_QUANTA.Q_RES(CHIPS)':
 'A': CDS_PINID='A';
NODE_NAME     R1499 2
 '@T6G_MB_LIB.T6G(SCH_1):PAGE451_I137@PURE_QUANTA.Q_RES(CHIPS)':
 'B': CDS_PINID='B';
NET_NAME
'JTAG_TCK_RT_CPU1_P3'
 '@T6G_MB_LIB.T6G(SCH_1):JTAG_TCK_RT_CPU1_P3':
 C_SIGNAL='@t6g_mb_lib.t6g(sch_1):jtag_tck_rt_cpu1_p3';
NODE_NAME     U6017 B3
 '@T6G_MB_LIB.T6G(SCH_1):PAGE462_I97@PURE_QUANTA.PT5161LRS(CHIPS)':
 'JTAG_TCK': CDS_PINID='JTAG_TCK';
NODE_NAME     R1430 1
 '@T6G_MB_LIB.T6G(SCH_1):PAGE462_I136@PURE_QUANTA.Q_RES(CHIPS)':
 'A': CDS_PINID='A';
NODE_NAME     R1513 2
 '@T6G_MB_LIB.T6G(SCH_1):PAGE462_I137@PURE_QUANTA.Q_RES(CHIPS)':
 'B': CDS_PINID='B';
NET_NAME
'JTAG_TDI'
 '@T6G_MB_LIB.T6G(SCH_1):JTAG_TDI':
 C_SIGNAL='@t6g_mb_lib.t6g(sch_1):jtag_tdi';
NODE_NAME     R1625 2
 '@T6G_MB_LIB.T6G(SCH_1):PAGE149_I53@PURE_QUANTA.Q_RES(CHIPS)':
 'B': CDS_PINID='B';
NODE_NAME     U152 8
 '@T6G_MB_LIB.T6G(SCH_1):PAGE150_I60@PURE_QUANTA.SN74AVC2T245RSWR(CHIPS)':
 'A1': CDS_PINID='A1';
NODE_NAME     C86 1
 '@T6G_MB_LIB.T6G(SCH_1):PAGE149_I161@PURE_QUANTA.Q_CAP(CHIPS)':
 'A': CDS_PINID='A';
NET_NAME
'JTAG_TDI_R'
 '@T6G_MB_LIB.T6G(SCH_1):JTAG_TDI_R':
 C_SIGNAL='@t6g_mb_lib.t6g(sch_1):jtag_tdi_r';
NODE_NAME     U147 5
 '@T6G_MB_LIB.T6G(SCH_1):PAGE149_I1@PURE_QUANTA.SN74AVC2T245RSWR(CHIPS)':
 'B1': CDS_PINID='B1';
NODE_NAME     R1625 1
 '@T6G_MB_LIB.T6G(SCH_1):PAGE149_I53@PURE_QUANTA.Q_RES(CHIPS)':
 'A': CDS_PINID='A';
NODE_NAME     U146 5
 '@T6G_MB_LIB.T6G(SCH_1):PAGE149_I76@PURE_QUANTA.SN74AVC2T245RSWR(CHIPS)':
 'B1': CDS_PINID='B1';
NET_NAME
'JTAG_TDI_RT_CPU0_P0'
 '@T6G_MB_LIB.T6G(SCH_1):JTAG_TDI_RT_CPU0_P0':
 C_SIGNAL='@t6g_mb_lib.t6g(sch_1):jtag_tdi_rt_cpu0_p0';
NODE_NAME     U6010 B6
 '@T6G_MB_LIB.T6G(SCH_1):PAGE385_I53@PURE_QUANTA.PT5161LRS(CHIPS)':
 'JTAG_TDI': CDS_PINID='JTAG_TDI';
NODE_NAME     R1438 2
 '@T6G_MB_LIB.T6G(SCH_1):PAGE385_I147@PURE_QUANTA.Q_RES(CHIPS)':
 'B': CDS_PINID='B';
NET_NAME
'JTAG_TDI_RT_CPU0_P1'
 '@T6G_MB_LIB.T6G(SCH_1):JTAG_TDI_RT_CPU0_P1':
 C_SIGNAL='@t6g_mb_lib.t6g(sch_1):jtag_tdi_rt_cpu0_p1';
NODE_NAME     U6011 B6
 '@T6G_MB_LIB.T6G(SCH_1):PAGE408_I83@PURE_QUANTA.PT5161LRS(CHIPS)':
 'JTAG_TDI': CDS_PINID='JTAG_TDI';
NODE_NAME     R1470 2
 '@T6G_MB_LIB.T6G(SCH_1):PAGE408_I115@PURE_QUANTA.Q_RES(CHIPS)':
 'B': CDS_PINID='B';
NET_NAME
'JTAG_TDI_RT_CPU0_P2'
 '@T6G_MB_LIB.T6G(SCH_1):JTAG_TDI_RT_CPU0_P2':
 C_SIGNAL='@t6g_mb_lib.t6g(sch_1):jtag_tdi_rt_cpu0_p2';
NODE_NAME     U6012 B6
 '@T6G_MB_LIB.T6G(SCH_1):PAGE419_I83@PURE_QUANTA.PT5161LRS(CHIPS)':
 'JTAG_TDI': CDS_PINID='JTAG_TDI';
NODE_NAME     R1476 2
 '@T6G_MB_LIB.T6G(SCH_1):PAGE419_I116@PURE_QUANTA.Q_RES(CHIPS)':
 'B': CDS_PINID='B';
NET_NAME
'JTAG_TDI_RT_CPU0_P3'
 '@T6G_MB_LIB.T6G(SCH_1):JTAG_TDI_RT_CPU0_P3':
 C_SIGNAL='@t6g_mb_lib.t6g(sch_1):jtag_tdi_rt_cpu0_p3';
NODE_NAME     U6013 B6
 '@T6G_MB_LIB.T6G(SCH_1):PAGE430_I83@PURE_QUANTA.PT5161LRS(CHIPS)':
 'JTAG_TDI': CDS_PINID='JTAG_TDI';
NODE_NAME     R1482 2
 '@T6G_MB_LIB.T6G(SCH_1):PAGE430_I112@PURE_QUANTA.Q_RES(CHIPS)':
 'B': CDS_PINID='B';
NET_NAME
'JTAG_TDI_RT_CPU1_P0'
 '@T6G_MB_LIB.T6G(SCH_1):JTAG_TDI_RT_CPU1_P0':
 C_SIGNAL='@t6g_mb_lib.t6g(sch_1):jtag_tdi_rt_cpu1_p0';
NODE_NAME     U6014 B6
 '@T6G_MB_LIB.T6G(SCH_1):PAGE401_I1@PURE_QUANTA.PT5161LRS(CHIPS)':
 'JTAG_TDI': CDS_PINID='JTAG_TDI';
NODE_NAME     R1464 2
 '@T6G_MB_LIB.T6G(SCH_1):PAGE401_I149@PURE_QUANTA.Q_RES(CHIPS)':
 'B': CDS_PINID='B';
NET_NAME
'JTAG_TDI_RT_CPU1_P1'
 '@T6G_MB_LIB.T6G(SCH_1):JTAG_TDI_RT_CPU1_P1':
 C_SIGNAL='@t6g_mb_lib.t6g(sch_1):jtag_tdi_rt_cpu1_p1';
NODE_NAME     U6015 B6
 '@T6G_MB_LIB.T6G(SCH_1):PAGE392_I47@PURE_QUANTA.PT5161LRS(CHIPS)':
 'JTAG_TDI': CDS_PINID='JTAG_TDI';
NODE_NAME     R1454 2
 '@T6G_MB_LIB.T6G(SCH_1):PAGE392_I145@PURE_QUANTA.Q_RES(CHIPS)':
 'B': CDS_PINID='B';
NET_NAME
'JTAG_TDI_RT_CPU1_P2'
 '@T6G_MB_LIB.T6G(SCH_1):JTAG_TDI_RT_CPU1_P2':
 C_SIGNAL='@t6g_mb_lib.t6g(sch_1):jtag_tdi_rt_cpu1_p2';
NODE_NAME     U6016 B6
 '@T6G_MB_LIB.T6G(SCH_1):PAGE451_I97@PURE_QUANTA.PT5161LRS(CHIPS)':
 'JTAG_TDI': CDS_PINID='JTAG_TDI';
NODE_NAME     R1488 2
 '@T6G_MB_LIB.T6G(SCH_1):PAGE451_I132@PURE_QUANTA.Q_RES(CHIPS)':
 'B': CDS_PINID='B';
NET_NAME
'JTAG_TDI_RT_CPU1_P3'
 '@T6G_MB_LIB.T6G(SCH_1):JTAG_TDI_RT_CPU1_P3':
 C_SIGNAL='@t6g_mb_lib.t6g(sch_1):jtag_tdi_rt_cpu1_p3';
NODE_NAME     U6017 B6
 '@T6G_MB_LIB.T6G(SCH_1):PAGE462_I97@PURE_QUANTA.PT5161LRS(CHIPS)':
 'JTAG_TDI': CDS_PINID='JTAG_TDI';
NODE_NAME     R1510 2
 '@T6G_MB_LIB.T6G(SCH_1):PAGE462_I139@PURE_QUANTA.Q_RES(CHIPS)':
 'B': CDS_PINID='B';
NET_NAME
'JTAG_TDO'
 '@T6G_MB_LIB.T6G(SCH_1):JTAG_TDO':
 C_SIGNAL='@t6g_mb_lib.t6g(sch_1):jtag_tdo';
NODE_NAME     R6109 1
 '@T6G_MB_LIB.T6G(SCH_1):PAGE150_I78@PURE_QUANTA.Q_RES(CHIPS)':
 'A': CDS_PINID='A';
NODE_NAME     R6111 2
 '@T6G_MB_LIB.T6G(SCH_1):PAGE149_I160@PURE_QUANTA.Q_RES(CHIPS)':
 'B': CDS_PINID='B';
NET_NAME
'JTAG_TDO_R'
 '@T6G_MB_LIB.T6G(SCH_1):JTAG_TDO_R':
 C_SIGNAL='@t6g_mb_lib.t6g(sch_1):jtag_tdo_r';
NODE_NAME     U152 9
 '@T6G_MB_LIB.T6G(SCH_1):PAGE150_I60@PURE_QUANTA.SN74AVC2T245RSWR(CHIPS)':
 'A2': CDS_PINID='A2';
NODE_NAME     R6109 2
 '@T6G_MB_LIB.T6G(SCH_1):PAGE150_I78@PURE_QUANTA.Q_RES(CHIPS)':
 'B': CDS_PINID='B';
NET_NAME
'JTAG_TDO_R1'
 '@T6G_MB_LIB.T6G(SCH_1):JTAG_TDO_R1':
 C_SIGNAL='@t6g_mb_lib.t6g(sch_1):jtag_tdo_r1';
NODE_NAME     U147 4
 '@T6G_MB_LIB.T6G(SCH_1):PAGE149_I1@PURE_QUANTA.SN74AVC2T245RSWR(CHIPS)':
 'B2': CDS_PINID='B2';
NODE_NAME     U146 4
 '@T6G_MB_LIB.T6G(SCH_1):PAGE149_I76@PURE_QUANTA.SN74AVC2T245RSWR(CHIPS)':
 'B2': CDS_PINID='B2';
NODE_NAME     R6111 1
 '@T6G_MB_LIB.T6G(SCH_1):PAGE149_I160@PURE_QUANTA.Q_RES(CHIPS)':
 'A': CDS_PINID='A';
NET_NAME
'JTAG_TDO_RT_CPU0_P0'
 '@T6G_MB_LIB.T6G(SCH_1):JTAG_TDO_RT_CPU0_P0':
 C_SIGNAL='@t6g_mb_lib.t6g(sch_1):jtag_tdo_rt_cpu0_p0';
NODE_NAME     U6010 B9
 '@T6G_MB_LIB.T6G(SCH_1):PAGE385_I53@PURE_QUANTA.PT5161LRS(CHIPS)':
 'JTAG_TDO': CDS_PINID='JTAG_TDO';
NODE_NAME     R1445 2
 '@T6G_MB_LIB.T6G(SCH_1):PAGE385_I145@PURE_QUANTA.Q_RES(CHIPS)':
 'B': CDS_PINID='B';
NET_NAME
'JTAG_TDO_RT_CPU0_P1'
 '@T6G_MB_LIB.T6G(SCH_1):JTAG_TDO_RT_CPU0_P1':
 C_SIGNAL='@t6g_mb_lib.t6g(sch_1):jtag_tdo_rt_cpu0_p1';
NODE_NAME     U6011 B9
 '@T6G_MB_LIB.T6G(SCH_1):PAGE408_I83@PURE_QUANTA.PT5161LRS(CHIPS)':
 'JTAG_TDO': CDS_PINID='JTAG_TDO';
NODE_NAME     R1472 2
 '@T6G_MB_LIB.T6G(SCH_1):PAGE408_I121@PURE_QUANTA.Q_RES(CHIPS)':
 'B': CDS_PINID='B';
NET_NAME
'JTAG_TDO_RT_CPU0_P2'
 '@T6G_MB_LIB.T6G(SCH_1):JTAG_TDO_RT_CPU0_P2':
 C_SIGNAL='@t6g_mb_lib.t6g(sch_1):jtag_tdo_rt_cpu0_p2';
NODE_NAME     U6012 B9
 '@T6G_MB_LIB.T6G(SCH_1):PAGE419_I83@PURE_QUANTA.PT5161LRS(CHIPS)':
 'JTAG_TDO': CDS_PINID='JTAG_TDO';
NODE_NAME     R1478 2
 '@T6G_MB_LIB.T6G(SCH_1):PAGE419_I118@PURE_QUANTA.Q_RES(CHIPS)':
 'B': CDS_PINID='B';
NET_NAME
'JTAG_TDO_RT_CPU0_P3'
 '@T6G_MB_LIB.T6G(SCH_1):JTAG_TDO_RT_CPU0_P3':
 C_SIGNAL='@t6g_mb_lib.t6g(sch_1):jtag_tdo_rt_cpu0_p3';
NODE_NAME     U6013 B9
 '@T6G_MB_LIB.T6G(SCH_1):PAGE430_I83@PURE_QUANTA.PT5161LRS(CHIPS)':
 'JTAG_TDO': CDS_PINID='JTAG_TDO';
NODE_NAME     R1484 2
 '@T6G_MB_LIB.T6G(SCH_1):PAGE430_I118@PURE_QUANTA.Q_RES(CHIPS)':
 'B': CDS_PINID='B';
NET_NAME
'JTAG_TDO_RT_CPU1_P0'
 '@T6G_MB_LIB.T6G(SCH_1):JTAG_TDO_RT_CPU1_P0':
 C_SIGNAL='@t6g_mb_lib.t6g(sch_1):jtag_tdo_rt_cpu1_p0';
NODE_NAME     U6014 B9
 '@T6G_MB_LIB.T6G(SCH_1):PAGE401_I1@PURE_QUANTA.PT5161LRS(CHIPS)':
 'JTAG_TDO': CDS_PINID='JTAG_TDO';
NODE_NAME     R1466 2
 '@T6G_MB_LIB.T6G(SCH_1):PAGE401_I146@PURE_QUANTA.Q_RES(CHIPS)':
 'B': CDS_PINID='B';
NET_NAME
'JTAG_TDO_RT_CPU1_P1'
 '@T6G_MB_LIB.T6G(SCH_1):JTAG_TDO_RT_CPU1_P1':
 C_SIGNAL='@t6g_mb_lib.t6g(sch_1):jtag_tdo_rt_cpu1_p1';
NODE_NAME     U6015 B9
 '@T6G_MB_LIB.T6G(SCH_1):PAGE392_I47@PURE_QUANTA.PT5161LRS(CHIPS)':
 'JTAG_TDO': CDS_PINID='JTAG_TDO';
NODE_NAME     R1456 2
 '@T6G_MB_LIB.T6G(SCH_1):PAGE392_I153@PURE_QUANTA.Q_RES(CHIPS)':
 'B': CDS_PINID='B';
NET_NAME
'JTAG_TDO_RT_CPU1_P2'
 '@T6G_MB_LIB.T6G(SCH_1):JTAG_TDO_RT_CPU1_P2':
 C_SIGNAL='@t6g_mb_lib.t6g(sch_1):jtag_tdo_rt_cpu1_p2';
NODE_NAME     U6016 B9
 '@T6G_MB_LIB.T6G(SCH_1):PAGE451_I97@PURE_QUANTA.PT5161LRS(CHIPS)':
 'JTAG_TDO': CDS_PINID='JTAG_TDO';
NODE_NAME     R1490 2
 '@T6G_MB_LIB.T6G(SCH_1):PAGE451_I139@PURE_QUANTA.Q_RES(CHIPS)':
 'B': CDS_PINID='B';
NET_NAME
'JTAG_TDO_RT_CPU1_P3'
 '@T6G_MB_LIB.T6G(SCH_1):JTAG_TDO_RT_CPU1_P3':
 C_SIGNAL='@t6g_mb_lib.t6g(sch_1):jtag_tdo_rt_cpu1_p3';
NODE_NAME     U6017 B9
 '@T6G_MB_LIB.T6G(SCH_1):PAGE462_I97@PURE_QUANTA.PT5161LRS(CHIPS)':
 'JTAG_TDO': CDS_PINID='JTAG_TDO';
NODE_NAME     R1512 2
 '@T6G_MB_LIB.T6G(SCH_1):PAGE462_I140@PURE_QUANTA.Q_RES(CHIPS)':
 'B': CDS_PINID='B';
NET_NAME
'JTAG_TEST_MODE_RT_CPU0_P0'
 '@T6G_MB_LIB.T6G(SCH_1):JTAG_TEST_MODE_RT_CPU0_P0':
 C_SIGNAL='@t6g_mb_lib.t6g(sch_1):jtag_test_mode_rt_cpu0_p0';
NODE_NAME     U6010 FF8
 '@T6G_MB_LIB.T6G(SCH_1):PAGE385_I53@PURE_QUANTA.PT5161LRS(CHIPS)':
 'JTAG_TEST_MODE': CDS_PINID='JTAG_TEST_MODE';
NODE_NAME     R997 1
 '@T6G_MB_LIB.T6G(SCH_1):PAGE385_I60@PURE_QUANTA.Q_RES(CHIPS)':
 'A': CDS_PINID='A';
NODE_NAME     R975 2
 '@T6G_MB_LIB.T6G(SCH_1):PAGE385_I63@PURE_QUANTA.Q_RES(CHIPS)':
 'B': CDS_PINID='B';
NET_NAME
'JTAG_TEST_MODE_RT_CPU0_P1'
 '@T6G_MB_LIB.T6G(SCH_1):JTAG_TEST_MODE_RT_CPU0_P1':
 C_SIGNAL='@t6g_mb_lib.t6g(sch_1):jtag_test_mode_rt_cpu0_p1';
NODE_NAME     R1037 1
 '@T6G_MB_LIB.T6G(SCH_1):PAGE408_I39@PURE_QUANTA.Q_RES(CHIPS)':
 'A': CDS_PINID='A';
NODE_NAME     R1024 2
 '@T6G_MB_LIB.T6G(SCH_1):PAGE408_I42@PURE_QUANTA.Q_RES(CHIPS)':
 'B': CDS_PINID='B';
NODE_NAME     U6011 FF8
 '@T6G_MB_LIB.T6G(SCH_1):PAGE408_I83@PURE_QUANTA.PT5161LRS(CHIPS)':
 'JTAG_TEST_MODE': CDS_PINID='JTAG_TEST_MODE';
NET_NAME
'JTAG_TEST_MODE_RT_CPU0_P2'
 '@T6G_MB_LIB.T6G(SCH_1):JTAG_TEST_MODE_RT_CPU0_P2':
 C_SIGNAL='@t6g_mb_lib.t6g(sch_1):jtag_test_mode_rt_cpu0_p2';
NODE_NAME     R1079 1
 '@T6G_MB_LIB.T6G(SCH_1):PAGE419_I39@PURE_QUANTA.Q_RES(CHIPS)':
 'A': CDS_PINID='A';
NODE_NAME     R1066 2
 '@T6G_MB_LIB.T6G(SCH_1):PAGE419_I42@PURE_QUANTA.Q_RES(CHIPS)':
 'B': CDS_PINID='B';
NODE_NAME     U6012 FF8
 '@T6G_MB_LIB.T6G(SCH_1):PAGE419_I83@PURE_QUANTA.PT5161LRS(CHIPS)':
 'JTAG_TEST_MODE': CDS_PINID='JTAG_TEST_MODE';
NET_NAME
'JTAG_TEST_MODE_RT_CPU0_P3'
 '@T6G_MB_LIB.T6G(SCH_1):JTAG_TEST_MODE_RT_CPU0_P3':
 C_SIGNAL='@t6g_mb_lib.t6g(sch_1):jtag_test_mode_rt_cpu0_p3';
NODE_NAME     R1121 1
 '@T6G_MB_LIB.T6G(SCH_1):PAGE430_I39@PURE_QUANTA.Q_RES(CHIPS)':
 'A': CDS_PINID='A';
NODE_NAME     R1108 2
 '@T6G_MB_LIB.T6G(SCH_1):PAGE430_I42@PURE_QUANTA.Q_RES(CHIPS)':
 'B': CDS_PINID='B';
NODE_NAME     U6013 FF8
 '@T6G_MB_LIB.T6G(SCH_1):PAGE430_I83@PURE_QUANTA.PT5161LRS(CHIPS)':
 'JTAG_TEST_MODE': CDS_PINID='JTAG_TEST_MODE';
NET_NAME
'JTAG_TEST_MODE_RT_CPU1_P0'
 '@T6G_MB_LIB.T6G(SCH_1):JTAG_TEST_MODE_RT_CPU1_P0':
 C_SIGNAL='@t6g_mb_lib.t6g(sch_1):jtag_test_mode_rt_cpu1_p0';
NODE_NAME     U6014 FF8
 '@T6G_MB_LIB.T6G(SCH_1):PAGE401_I1@PURE_QUANTA.PT5161LRS(CHIPS)':
 'JTAG_TEST_MODE': CDS_PINID='JTAG_TEST_MODE';
NODE_NAME     R726 1
 '@T6G_MB_LIB.T6G(SCH_1):PAGE401_I90@PURE_QUANTA.Q_RES(CHIPS)':
 'A': CDS_PINID='A';
NODE_NAME     R6725 2
 '@T6G_MB_LIB.T6G(SCH_1):PAGE401_I91@PURE_QUANTA.Q_RES(CHIPS)':
 'B': CDS_PINID='B';
NET_NAME
'JTAG_TEST_MODE_RT_CPU1_P1'
 '@T6G_MB_LIB.T6G(SCH_1):JTAG_TEST_MODE_RT_CPU1_P1':
 C_SIGNAL='@t6g_mb_lib.t6g(sch_1):jtag_test_mode_rt_cpu1_p1';
NODE_NAME     U6015 FF8
 '@T6G_MB_LIB.T6G(SCH_1):PAGE392_I47@PURE_QUANTA.PT5161LRS(CHIPS)':
 'JTAG_TEST_MODE': CDS_PINID='JTAG_TEST_MODE';
NODE_NAME     R792 1
 '@T6G_MB_LIB.T6G(SCH_1):PAGE392_I54@PURE_QUANTA.Q_RES(CHIPS)':
 'A': CDS_PINID='A';
NODE_NAME     R759 2
 '@T6G_MB_LIB.T6G(SCH_1):PAGE392_I57@PURE_QUANTA.Q_RES(CHIPS)':
 'B': CDS_PINID='B';
NET_NAME
'JTAG_TEST_MODE_RT_CPU1_P2'
 '@T6G_MB_LIB.T6G(SCH_1):JTAG_TEST_MODE_RT_CPU1_P2':
 C_SIGNAL='@t6g_mb_lib.t6g(sch_1):jtag_test_mode_rt_cpu1_p2';
NODE_NAME     R884 1
 '@T6G_MB_LIB.T6G(SCH_1):PAGE451_I46@PURE_QUANTA.Q_RES(CHIPS)':
 'A': CDS_PINID='A';
NODE_NAME     R871 2
 '@T6G_MB_LIB.T6G(SCH_1):PAGE451_I50@PURE_QUANTA.Q_RES(CHIPS)':
 'B': CDS_PINID='B';
NODE_NAME     U6016 FF8
 '@T6G_MB_LIB.T6G(SCH_1):PAGE451_I97@PURE_QUANTA.PT5161LRS(CHIPS)':
 'JTAG_TEST_MODE': CDS_PINID='JTAG_TEST_MODE';
NET_NAME
'JTAG_TEST_MODE_RT_CPU1_P3'
 '@T6G_MB_LIB.T6G(SCH_1):JTAG_TEST_MODE_RT_CPU1_P3':
 C_SIGNAL='@t6g_mb_lib.t6g(sch_1):jtag_test_mode_rt_cpu1_p3';
NODE_NAME     R924 1
 '@T6G_MB_LIB.T6G(SCH_1):PAGE462_I53@PURE_QUANTA.Q_RES(CHIPS)':
 'A': CDS_PINID='A';
NODE_NAME     R912 2
 '@T6G_MB_LIB.T6G(SCH_1):PAGE462_I56@PURE_QUANTA.Q_RES(CHIPS)':
 'B': CDS_PINID='B';
NODE_NAME     U6017 FF8
 '@T6G_MB_LIB.T6G(SCH_1):PAGE462_I97@PURE_QUANTA.PT5161LRS(CHIPS)':
 'JTAG_TEST_MODE': CDS_PINID='JTAG_TEST_MODE';
NET_NAME
'JTAG_TMS'
 '@T6G_MB_LIB.T6G(SCH_1):JTAG_TMS':
 C_SIGNAL='@t6g_mb_lib.t6g(sch_1):jtag_tms';
NODE_NAME     R1634 2
 '@T6G_MB_LIB.T6G(SCH_1):PAGE149_I96@PURE_QUANTA.Q_RES(CHIPS)':
 'B': CDS_PINID='B';
NODE_NAME     U150 4
 '@T6G_MB_LIB.T6G(SCH_1):PAGE150_I8@PURE_QUANTA.SN74AVC4T774PWR(CHIPS)':
 'A2': CDS_PINID='A2';
NODE_NAME     U151 4
 '@T6G_MB_LIB.T6G(SCH_1):PAGE150_I28@PURE_QUANTA.SN74AVC4T774PWR(CHIPS)':
 'A2': CDS_PINID='A2';
NET_NAME
'JTAG_TMS_R'
 '@T6G_MB_LIB.T6G(SCH_1):JTAG_TMS_R':
 C_SIGNAL='@t6g_mb_lib.t6g(sch_1):jtag_tms_r';
NODE_NAME     U149 13
 '@T6G_MB_LIB.T6G(SCH_1):PAGE149_I31@PURE_QUANTA.SN74AVC4T774PWR(CHIPS)':
 'B2': CDS_PINID='B2';
NODE_NAME     U148 13
 '@T6G_MB_LIB.T6G(SCH_1):PAGE149_I34@PURE_QUANTA.SN74AVC4T774PWR(CHIPS)':
 'B2': CDS_PINID='B2';
NODE_NAME     R1634 1
 '@T6G_MB_LIB.T6G(SCH_1):PAGE149_I96@PURE_QUANTA.Q_RES(CHIPS)':
 'A': CDS_PINID='A';
NET_NAME
'JTAG_TMS_RT_CPU0_P0'
 '@T6G_MB_LIB.T6G(SCH_1):JTAG_TMS_RT_CPU0_P0':
 C_SIGNAL='@t6g_mb_lib.t6g(sch_1):jtag_tms_rt_cpu0_p0';
NODE_NAME     U6010 B12
 '@T6G_MB_LIB.T6G(SCH_1):PAGE385_I53@PURE_QUANTA.PT5161LRS(CHIPS)':
 'JTAG_TMS': CDS_PINID='JTAG_TMS';
NODE_NAME     R1439 2
 '@T6G_MB_LIB.T6G(SCH_1):PAGE385_I146@PURE_QUANTA.Q_RES(CHIPS)':
 'B': CDS_PINID='B';
NET_NAME
'JTAG_TMS_RT_CPU0_P1'
 '@T6G_MB_LIB.T6G(SCH_1):JTAG_TMS_RT_CPU0_P1':
 C_SIGNAL='@t6g_mb_lib.t6g(sch_1):jtag_tms_rt_cpu0_p1';
NODE_NAME     U6011 B12
 '@T6G_MB_LIB.T6G(SCH_1):PAGE408_I83@PURE_QUANTA.PT5161LRS(CHIPS)':
 'JTAG_TMS': CDS_PINID='JTAG_TMS';
NODE_NAME     R1471 2
 '@T6G_MB_LIB.T6G(SCH_1):PAGE408_I116@PURE_QUANTA.Q_RES(CHIPS)':
 'B': CDS_PINID='B';
NET_NAME
'JTAG_TMS_RT_CPU0_P2'
 '@T6G_MB_LIB.T6G(SCH_1):JTAG_TMS_RT_CPU0_P2':
 C_SIGNAL='@t6g_mb_lib.t6g(sch_1):jtag_tms_rt_cpu0_p2';
NODE_NAME     U6012 B12
 '@T6G_MB_LIB.T6G(SCH_1):PAGE419_I83@PURE_QUANTA.PT5161LRS(CHIPS)':
 'JTAG_TMS': CDS_PINID='JTAG_TMS';
NODE_NAME     R1477 2
 '@T6G_MB_LIB.T6G(SCH_1):PAGE419_I117@PURE_QUANTA.Q_RES(CHIPS)':
 'B': CDS_PINID='B';
NET_NAME
'JTAG_TMS_RT_CPU0_P3'
 '@T6G_MB_LIB.T6G(SCH_1):JTAG_TMS_RT_CPU0_P3':
 C_SIGNAL='@t6g_mb_lib.t6g(sch_1):jtag_tms_rt_cpu0_p3';
NODE_NAME     U6013 B12
 '@T6G_MB_LIB.T6G(SCH_1):PAGE430_I83@PURE_QUANTA.PT5161LRS(CHIPS)':
 'JTAG_TMS': CDS_PINID='JTAG_TMS';
NODE_NAME     R1483 2
 '@T6G_MB_LIB.T6G(SCH_1):PAGE430_I113@PURE_QUANTA.Q_RES(CHIPS)':
 'B': CDS_PINID='B';
NET_NAME
'JTAG_TMS_RT_CPU1_P0'
 '@T6G_MB_LIB.T6G(SCH_1):JTAG_TMS_RT_CPU1_P0':
 C_SIGNAL='@t6g_mb_lib.t6g(sch_1):jtag_tms_rt_cpu1_p0';
NODE_NAME     U6014 B12
 '@T6G_MB_LIB.T6G(SCH_1):PAGE401_I1@PURE_QUANTA.PT5161LRS(CHIPS)':
 'JTAG_TMS': CDS_PINID='JTAG_TMS';
NODE_NAME     R1465 2
 '@T6G_MB_LIB.T6G(SCH_1):PAGE401_I145@PURE_QUANTA.Q_RES(CHIPS)':
 'B': CDS_PINID='B';
NET_NAME
'JTAG_TMS_RT_CPU1_P1'
 '@T6G_MB_LIB.T6G(SCH_1):JTAG_TMS_RT_CPU1_P1':
 C_SIGNAL='@t6g_mb_lib.t6g(sch_1):jtag_tms_rt_cpu1_p1';
NODE_NAME     U6015 B12
 '@T6G_MB_LIB.T6G(SCH_1):PAGE392_I47@PURE_QUANTA.PT5161LRS(CHIPS)':
 'JTAG_TMS': CDS_PINID='JTAG_TMS';
NODE_NAME     R1455 2
 '@T6G_MB_LIB.T6G(SCH_1):PAGE392_I146@PURE_QUANTA.Q_RES(CHIPS)':
 'B': CDS_PINID='B';
NET_NAME
'JTAG_TMS_RT_CPU1_P2'
 '@T6G_MB_LIB.T6G(SCH_1):JTAG_TMS_RT_CPU1_P2':
 C_SIGNAL='@t6g_mb_lib.t6g(sch_1):jtag_tms_rt_cpu1_p2';
NODE_NAME     U6016 B12
 '@T6G_MB_LIB.T6G(SCH_1):PAGE451_I97@PURE_QUANTA.PT5161LRS(CHIPS)':
 'JTAG_TMS': CDS_PINID='JTAG_TMS';
NODE_NAME     R1489 2
 '@T6G_MB_LIB.T6G(SCH_1):PAGE451_I140@PURE_QUANTA.Q_RES(CHIPS)':
 'B': CDS_PINID='B';
NET_NAME
'JTAG_TMS_RT_CPU1_P3'
 '@T6G_MB_LIB.T6G(SCH_1):JTAG_TMS_RT_CPU1_P3':
 C_SIGNAL='@t6g_mb_lib.t6g(sch_1):jtag_tms_rt_cpu1_p3';
NODE_NAME     U6017 B12
 '@T6G_MB_LIB.T6G(SCH_1):PAGE462_I97@PURE_QUANTA.PT5161LRS(CHIPS)':
 'JTAG_TMS': CDS_PINID='JTAG_TMS';
NODE_NAME     R1511 2
 '@T6G_MB_LIB.T6G(SCH_1):PAGE462_I132@PURE_QUANTA.Q_RES(CHIPS)':
 'B': CDS_PINID='B';
NET_NAME
'JTAG_TRST_N'
 '@T6G_MB_LIB.T6G(SCH_1):JTAG_TRST_N':
 C_SIGNAL='@t6g_mb_lib.t6g(sch_1):jtag_trst_n';
NODE_NAME     R1635 2
 '@T6G_MB_LIB.T6G(SCH_1):PAGE149_I8@PURE_QUANTA.Q_RES(CHIPS)':
 'B': CDS_PINID='B';
NODE_NAME     C1511 1
 '@T6G_MB_LIB.T6G(SCH_1):PAGE149_I23@PURE_QUANTA.Q_CAP(CHIPS)':
 'A': CDS_PINID='A';
NODE_NAME     U150 5
 '@T6G_MB_LIB.T6G(SCH_1):PAGE150_I8@PURE_QUANTA.SN74AVC4T774PWR(CHIPS)':
 'A3': CDS_PINID='A3';
NODE_NAME     U151 5
 '@T6G_MB_LIB.T6G(SCH_1):PAGE150_I28@PURE_QUANTA.SN74AVC4T774PWR(CHIPS)':
 'A3': CDS_PINID='A3';
NET_NAME
'JTAG_TRST_RT_CPU0_P0_N'
 '@T6G_MB_LIB.T6G(SCH_1):JTAG_TRST_RT_CPU0_P0_N':
 C_SIGNAL='@t6g_mb_lib.t6g(sch_1):jtag_trst_rt_cpu0_p0_n';
NODE_NAME     U6010 E8
 '@T6G_MB_LIB.T6G(SCH_1):PAGE385_I53@PURE_QUANTA.PT5161LRS(CHIPS)':
 'JTAG_TRST_N': CDS_PINID='JTAG_TRST_N';
NODE_NAME     R1364 1
 '@T6G_MB_LIB.T6G(SCH_1):PAGE385_I111@PURE_QUANTA.Q_RES(CHIPS)':
 'A': CDS_PINID='A';
NET_NAME
'JTAG_TRST_RT_CPU0_P1_N'
 '@T6G_MB_LIB.T6G(SCH_1):JTAG_TRST_RT_CPU0_P1_N':
 C_SIGNAL='@t6g_mb_lib.t6g(sch_1):jtag_trst_rt_cpu0_p1_n';
NODE_NAME     U6011 E8
 '@T6G_MB_LIB.T6G(SCH_1):PAGE408_I83@PURE_QUANTA.PT5161LRS(CHIPS)':
 'JTAG_TRST_N': CDS_PINID='JTAG_TRST_N';
NODE_NAME     R1391 1
 '@T6G_MB_LIB.T6G(SCH_1):PAGE408_I84@PURE_QUANTA.Q_RES(CHIPS)':
 'A': CDS_PINID='A';
NET_NAME
'JTAG_TRST_RT_CPU0_P2_N'
 '@T6G_MB_LIB.T6G(SCH_1):JTAG_TRST_RT_CPU0_P2_N':
 C_SIGNAL='@t6g_mb_lib.t6g(sch_1):jtag_trst_rt_cpu0_p2_n';
NODE_NAME     U6012 E8
 '@T6G_MB_LIB.T6G(SCH_1):PAGE419_I83@PURE_QUANTA.PT5161LRS(CHIPS)':
 'JTAG_TRST_N': CDS_PINID='JTAG_TRST_N';
NODE_NAME     R1400 1
 '@T6G_MB_LIB.T6G(SCH_1):PAGE419_I84@PURE_QUANTA.Q_RES(CHIPS)':
 'A': CDS_PINID='A';
NET_NAME
'JTAG_TRST_RT_CPU0_P3_N'
 '@T6G_MB_LIB.T6G(SCH_1):JTAG_TRST_RT_CPU0_P3_N':
 C_SIGNAL='@t6g_mb_lib.t6g(sch_1):jtag_trst_rt_cpu0_p3_n';
NODE_NAME     U6013 E8
 '@T6G_MB_LIB.T6G(SCH_1):PAGE430_I83@PURE_QUANTA.PT5161LRS(CHIPS)':
 'JTAG_TRST_N': CDS_PINID='JTAG_TRST_N';
NODE_NAME     R1408 1
 '@T6G_MB_LIB.T6G(SCH_1):PAGE430_I85@PURE_QUANTA.Q_RES(CHIPS)':
 'A': CDS_PINID='A';
NET_NAME
'JTAG_TRST_RT_CPU1_P0_N'
 '@T6G_MB_LIB.T6G(SCH_1):JTAG_TRST_RT_CPU1_P0_N':
 C_SIGNAL='@t6g_mb_lib.t6g(sch_1):jtag_trst_rt_cpu1_p0_n';
NODE_NAME     U6014 E8
 '@T6G_MB_LIB.T6G(SCH_1):PAGE401_I1@PURE_QUANTA.PT5161LRS(CHIPS)':
 'JTAG_TRST_N': CDS_PINID='JTAG_TRST_N';
NODE_NAME     R1380 1
 '@T6G_MB_LIB.T6G(SCH_1):PAGE401_I112@PURE_QUANTA.Q_RES(CHIPS)':
 'A': CDS_PINID='A';
NET_NAME
'JTAG_TRST_RT_CPU1_P1_N'
 '@T6G_MB_LIB.T6G(SCH_1):JTAG_TRST_RT_CPU1_P1_N':
 C_SIGNAL='@t6g_mb_lib.t6g(sch_1):jtag_trst_rt_cpu1_p1_n';
NODE_NAME     U6015 E8
 '@T6G_MB_LIB.T6G(SCH_1):PAGE392_I47@PURE_QUANTA.PT5161LRS(CHIPS)':
 'JTAG_TRST_N': CDS_PINID='JTAG_TRST_N';
NODE_NAME     R1372 1
 '@T6G_MB_LIB.T6G(SCH_1):PAGE392_I115@PURE_QUANTA.Q_RES(CHIPS)':
 'A': CDS_PINID='A';
NET_NAME
'JTAG_TRST_RT_CPU1_P2_N'
 '@T6G_MB_LIB.T6G(SCH_1):JTAG_TRST_RT_CPU1_P2_N':
 C_SIGNAL='@t6g_mb_lib.t6g(sch_1):jtag_trst_rt_cpu1_p2_n';
NODE_NAME     U6016 E8
 '@T6G_MB_LIB.T6G(SCH_1):PAGE451_I97@PURE_QUANTA.PT5161LRS(CHIPS)':
 'JTAG_TRST_N': CDS_PINID='JTAG_TRST_N';
NODE_NAME     R1416 1
 '@T6G_MB_LIB.T6G(SCH_1):PAGE451_I102@PURE_QUANTA.Q_RES(CHIPS)':
 'A': CDS_PINID='A';
NET_NAME
'JTAG_TRST_RT_CPU1_P3_N'
 '@T6G_MB_LIB.T6G(SCH_1):JTAG_TRST_RT_CPU1_P3_N':
 C_SIGNAL='@t6g_mb_lib.t6g(sch_1):jtag_trst_rt_cpu1_p3_n';
NODE_NAME     U6017 E8
 '@T6G_MB_LIB.T6G(SCH_1):PAGE462_I97@PURE_QUANTA.PT5161LRS(CHIPS)':
 'JTAG_TRST_N': CDS_PINID='JTAG_TRST_N';
NODE_NAME     R1429 1
 '@T6G_MB_LIB.T6G(SCH_1):PAGE462_I103@PURE_QUANTA.Q_RES(CHIPS)':
 'A': CDS_PINID='A';
NET_NAME
'JTAG_TRST_R_N'
 '@T6G_MB_LIB.T6G(SCH_1):JTAG_TRST_R_N':
 C_SIGNAL='@t6g_mb_lib.t6g(sch_1):jtag_trst_r_n';
NODE_NAME     R1635 1
 '@T6G_MB_LIB.T6G(SCH_1):PAGE149_I8@PURE_QUANTA.Q_RES(CHIPS)':
 'A': CDS_PINID='A';
NODE_NAME     U149 12
 '@T6G_MB_LIB.T6G(SCH_1):PAGE149_I31@PURE_QUANTA.SN74AVC4T774PWR(CHIPS)':
 'B3': CDS_PINID='B3';
NODE_NAME     U148 12
 '@T6G_MB_LIB.T6G(SCH_1):PAGE149_I34@PURE_QUANTA.SN74AVC4T774PWR(CHIPS)':
 'B3': CDS_PINID='B3';
NET_NAME
'LED_BIOS_DBG_MODE'
 '@T6G_MB_LIB.T6G(SCH_1):LED_BIOS_DBG_MODE':
 C_SIGNAL='@t6g_mb_lib.t6g(sch_1):led_bios_dbg_mode';
NODE_NAME     D9 C
 '@T6G_MB_LIB.T6G(SCH_1):PAGE142_I79@PURE_QUANTA.Q_LED(CHIPS)':
 'C': CDS_PINID='C';
NODE_NAME     Q29 D
 '@T6G_MB_LIB.T6G(SCH_1):PAGE142_I80@PURE_QUANTA.MOSFET_N_GSD(CHIPS)':
 'DRAIN': CDS_PINID='DRAIN';
NET_NAME
'LED_BIOS_DBG_MODE_N'
 '@T6G_MB_LIB.T6G(SCH_1):LED_BIOS_DBG_MODE_N':
 C_SIGNAL='@t6g_mb_lib.t6g(sch_1):led_bios_dbg_mode_n';
NODE_NAME     Q29 G
 '@T6G_MB_LIB.T6G(SCH_1):PAGE142_I80@PURE_QUANTA.MOSFET_N_GSD(CHIPS)':
 'GATE': CDS_PINID='GATE';
NODE_NAME     Q30 D
 '@T6G_MB_LIB.T6G(SCH_1):PAGE142_I81@PURE_QUANTA.MOSFET_N_GSD(CHIPS)':
 'DRAIN': CDS_PINID='DRAIN';
NODE_NAME     R1507 2
 '@T6G_MB_LIB.T6G(SCH_1):PAGE142_I87@PURE_QUANTA.Q_RES(CHIPS)':
 'B': CDS_PINID='B';
NET_NAME
'LED_BIOS_DBG_MODE_R'
 '@T6G_MB_LIB.T6G(SCH_1):LED_BIOS_DBG_MODE_R':
 C_SIGNAL='@t6g_mb_lib.t6g(sch_1):led_bios_dbg_mode_r';
NODE_NAME     D9 A
 '@T6G_MB_LIB.T6G(SCH_1):PAGE142_I79@PURE_QUANTA.Q_LED(CHIPS)':
 'A': CDS_PINID='A';
NODE_NAME     R1444 2
 '@T6G_MB_LIB.T6G(SCH_1):PAGE142_I82@PURE_QUANTA.Q_RES(CHIPS)':
 'B': CDS_PINID='B';
NET_NAME
'LED_HDD_ACTIVITY_B_N'
 '@T6G_MB_LIB.T6G(SCH_1):LED_HDD_ACTIVITY_B_N':
 C_SIGNAL='@t6g_mb_lib.t6g(sch_1):led_hdd_activity_b_n';
NODE_NAME     R3254 2
 '@T6G_MB_LIB.T6G(SCH_1):PAGE348_I50@PURE_QUANTA.Q_RES(CHIPS)':
 'B': CDS_PINID='B';
NODE_NAME     U239 4
 '@T6G_MB_LIB.T6G(SCH_1):PAGE345_I53@PURE_QUANTA.74LVC1G126SE7(CHIPS)':
 'Y': CDS_PINID='Y';
NODE_NAME     R3297 1
 '@T6G_MB_LIB.T6G(SCH_1):PAGE345_I60@PURE_QUANTA.Q_RES(CHIPS)':
 'A': CDS_PINID='A';
NODE_NAME     R6075 1
 '@T6G_MB_LIB.T6G(SCH_1):PAGE84_I57@PURE_QUANTA.Q_RES(CHIPS)':
 'A': CDS_PINID='A';
NET_NAME
'LED_HDD_ACTIVITY_B_PLD_N'
 '@T6G_MB_LIB.T6G(SCH_1):LED_HDD_ACTIVITY_B_PLD_N':
 C_SIGNAL='@t6g_mb_lib.t6g(sch_1):led_hdd_activity_b_pld_n';
NODE_NAME     U18 L1
 '@T6G_MB_LIB.T6G(SCH_1):PAGE81_I143@PURE_QUANTA.LCMXO3LF9400C5BG484C(CHIPS)':
 'PL16A||PCLKT4_0': CDS_PINID='\pl16a||pclkt4_0\';
NODE_NAME     R6075 2
 '@T6G_MB_LIB.T6G(SCH_1):PAGE84_I57@PURE_QUANTA.Q_RES(CHIPS)':
 'B': CDS_PINID='B';
NET_NAME
'LED_HDD_ACTIVITY_N'
 '@T6G_MB_LIB.T6G(SCH_1):LED_HDD_ACTIVITY_N':
 C_SIGNAL='@t6g_mb_lib.t6g(sch_1):led_hdd_activity_n';
NODE_NAME     R3294 2
 '@T6G_MB_LIB.T6G(SCH_1):PAGE345_I19@PURE_QUANTA.Q_RES(CHIPS)':
 'B': CDS_PINID='B';
NODE_NAME     R3295 2
 '@T6G_MB_LIB.T6G(SCH_1):PAGE345_I21@PURE_QUANTA.Q_RES(CHIPS)':
 'B': CDS_PINID='B';
NODE_NAME     U239 2
 '@T6G_MB_LIB.T6G(SCH_1):PAGE345_I53@PURE_QUANTA.74LVC1G126SE7(CHIPS)':
 'A': CDS_PINID='A';
NET_NAME
'LED_M2_SSD_0_ACT_N'
 '@T6G_MB_LIB.T6G(SCH_1):LED_M2_SSD_0_ACT_N':
 C_SIGNAL='@t6g_mb_lib.t6g(sch_1):led_m2_ssd_0_act_n';
NODE_NAME     J59 10
 '@T6G_MB_LIB.T6G(SCH_1):PAGE345_I88@PURE_QUANTA.SCONN75K_APCI0155P004A(CHIPS)':
 'DAS_DSS#||LED1#': CDS_PINID='\das_dss#||led1#\';
NODE_NAME     R3294 1
 '@T6G_MB_LIB.T6G(SCH_1):PAGE345_I19@PURE_QUANTA.Q_RES(CHIPS)':
 'A': CDS_PINID='A';
NET_NAME
'LED_P12V_AUX_R1'
 '@T6G_MB_LIB.T6G(SCH_1):LED_P12V_AUX_R1':
 C_SIGNAL='@t6g_mb_lib.t6g(sch_1):led_p12v_aux_r1';
NODE_NAME     D8000 A
 '@T6G_MB_LIB.T6G(SCH_1):PAGE375_I42@PURE_QUANTA.Q_LED(CHIPS)':
 'A': CDS_PINID='A';
NODE_NAME     R8022 1
 '@T6G_MB_LIB.T6G(SCH_1):PAGE375_I44@PURE_QUANTA.Q_RES(CHIPS)':
 'A': CDS_PINID='A';
NET_NAME
'LED_P12V_AUX_R2'
 '@T6G_MB_LIB.T6G(SCH_1):LED_P12V_AUX_R2':
 C_SIGNAL='@t6g_mb_lib.t6g(sch_1):led_p12v_aux_r2';
NODE_NAME     R8022 2
 '@T6G_MB_LIB.T6G(SCH_1):PAGE375_I44@PURE_QUANTA.Q_RES(CHIPS)':
 'B': CDS_PINID='B';
NODE_NAME     R8023 1
 '@T6G_MB_LIB.T6G(SCH_1):PAGE375_I45@PURE_QUANTA.Q_RES(CHIPS)':
 'A': CDS_PINID='A';
NET_NAME
'LED_P12V_AUX_R3'
 '@T6G_MB_LIB.T6G(SCH_1):LED_P12V_AUX_R3':
 C_SIGNAL='@t6g_mb_lib.t6g(sch_1):led_p12v_aux_r3';
NODE_NAME     R8023 2
 '@T6G_MB_LIB.T6G(SCH_1):PAGE375_I45@PURE_QUANTA.Q_RES(CHIPS)':
 'B': CDS_PINID='B';
NODE_NAME     R8024 1
 '@T6G_MB_LIB.T6G(SCH_1):PAGE375_I46@PURE_QUANTA.Q_RES(CHIPS)':
 'A': CDS_PINID='A';
NET_NAME
'LED_P12V_PSU_R1'
 '@T6G_MB_LIB.T6G(SCH_1):LED_P12V_PSU_R1':
 C_SIGNAL='@t6g_mb_lib.t6g(sch_1):led_p12v_psu_r1';
NODE_NAME     R8025 1
 '@T6G_MB_LIB.T6G(SCH_1):PAGE375_I51@PURE_QUANTA.Q_RES(CHIPS)':
 'A': CDS_PINID='A';
NODE_NAME     D8001 A
 '@T6G_MB_LIB.T6G(SCH_1):PAGE375_I52@PURE_QUANTA.Q_LED(CHIPS)':
 'A': CDS_PINID='A';
NET_NAME
'LED_P12V_PSU_R2'
 '@T6G_MB_LIB.T6G(SCH_1):LED_P12V_PSU_R2':
 C_SIGNAL='@t6g_mb_lib.t6g(sch_1):led_p12v_psu_r2';
NODE_NAME     R8026 1
 '@T6G_MB_LIB.T6G(SCH_1):PAGE375_I50@PURE_QUANTA.Q_RES(CHIPS)':
 'A': CDS_PINID='A';
NODE_NAME     R8025 2
 '@T6G_MB_LIB.T6G(SCH_1):PAGE375_I51@PURE_QUANTA.Q_RES(CHIPS)':
 'B': CDS_PINID='B';
NET_NAME
'LED_P12V_PSU_R3'
 '@T6G_MB_LIB.T6G(SCH_1):LED_P12V_PSU_R3':
 C_SIGNAL='@t6g_mb_lib.t6g(sch_1):led_p12v_psu_r3';
NODE_NAME     R8027 1
 '@T6G_MB_LIB.T6G(SCH_1):PAGE375_I49@PURE_QUANTA.Q_RES(CHIPS)':
 'A': CDS_PINID='A';
NODE_NAME     R8026 2
 '@T6G_MB_LIB.T6G(SCH_1):PAGE375_I50@PURE_QUANTA.Q_RES(CHIPS)':
 'B': CDS_PINID='B';
NET_NAME
'LED_P12V_SCM_FAULT'
 '@T6G_MB_LIB.T6G(SCH_1):LED_P12V_SCM_FAULT':
 C_SIGNAL='@t6g_mb_lib.t6g(sch_1):led_p12v_scm_fault';
NODE_NAME     R8029 1
 '@T6G_MB_LIB.T6G(SCH_1):PAGE375_I55@PURE_QUANTA.Q_RES(CHIPS)':
 'A': CDS_PINID='A';
NODE_NAME     D8002 A
 '@T6G_MB_LIB.T6G(SCH_1):PAGE375_I56@PURE_QUANTA.Q_LED(CHIPS)':
 'A': CDS_PINID='A';
NET_NAME
'LED_P12V_SCM_FAULT_D1'
 '@T6G_MB_LIB.T6G(SCH_1):LED_P12V_SCM_FAULT_D1':
 C_SIGNAL='@t6g_mb_lib.t6g(sch_1):led_p12v_scm_fault_d1';
NODE_NAME     Q8001 6
 '@T6G_MB_LIB.T6G(SCH_1):PAGE375_I57@PURE_QUANTA.MOSFET_NCH_DUAL(CHIPS)':
 'D1': CDS_PINID='D1';
NODE_NAME     Q8001 5
 '@T6G_MB_LIB.T6G(SCH_1):PAGE375_I58@PURE_QUANTA.MOSFET_NCH_DUAL(CHIPS)':
 'G2': CDS_PINID='G2';
NODE_NAME     R8028 2
 '@T6G_MB_LIB.T6G(SCH_1):PAGE375_I62@PURE_QUANTA.Q_RES(CHIPS)':
 'B': CDS_PINID='B';
NET_NAME
'LED_P12V_SCM_FAULT_D2'
 '@T6G_MB_LIB.T6G(SCH_1):LED_P12V_SCM_FAULT_D2':
 C_SIGNAL='@t6g_mb_lib.t6g(sch_1):led_p12v_scm_fault_d2';
NODE_NAME     D8002 C
 '@T6G_MB_LIB.T6G(SCH_1):PAGE375_I56@PURE_QUANTA.Q_LED(CHIPS)':
 'C': CDS_PINID='C';
NODE_NAME     Q8001 3
 '@T6G_MB_LIB.T6G(SCH_1):PAGE375_I58@PURE_QUANTA.MOSFET_NCH_DUAL(CHIPS)':
 'D2': CDS_PINID='D2';
NET_NAME
'LED_P3V3'
 '@T6G_MB_LIB.T6G(SCH_1):LED_P3V3':
 C_SIGNAL='@t6g_mb_lib.t6g(sch_1):led_p3v3';
NODE_NAME     D99 A
 '@T6G_MB_LIB.T6G(SCH_1):PAGE254_I3@PURE_QUANTA.Q_LED(CHIPS)':
 'A': CDS_PINID='A';
NODE_NAME     R3100 1
 '@T6G_MB_LIB.T6G(SCH_1):PAGE254_I8@PURE_QUANTA.Q_RES(CHIPS)':
 'A': CDS_PINID='A';
NET_NAME
'LED_P5V'
 '@T6G_MB_LIB.T6G(SCH_1):LED_P5V':
 C_SIGNAL='@t6g_mb_lib.t6g(sch_1):led_p5v';
NODE_NAME     R3102 1
 '@T6G_MB_LIB.T6G(SCH_1):PAGE254_I9@PURE_QUANTA.Q_RES(CHIPS)':
 'A': CDS_PINID='A';
NODE_NAME     D98 A
 '@T6G_MB_LIB.T6G(SCH_1):PAGE254_I17@PURE_QUANTA.Q_LED(CHIPS)':
 'A': CDS_PINID='A';
NET_NAME
'LED_PWRGD_P1V2_AUX'
 '@T6G_MB_LIB.T6G(SCH_1):LED_PWRGD_P1V2_AUX':
 C_SIGNAL='@t6g_mb_lib.t6g(sch_1):led_pwrgd_p1v2_aux';
NODE_NAME     D6000 A
 '@T6G_MB_LIB.T6G(SCH_1):PAGE254_I43@PURE_QUANTA.Q_LED(CHIPS)':
 'A': CDS_PINID='A';
NODE_NAME     R6246 1
 '@T6G_MB_LIB.T6G(SCH_1):PAGE254_I45@PURE_QUANTA.Q_RES(CHIPS)':
 'A': CDS_PINID='A';
NET_NAME
'LED_PWRGD_P1V2_AUX_D'
 '@T6G_MB_LIB.T6G(SCH_1):LED_PWRGD_P1V2_AUX_D':
 C_SIGNAL='@t6g_mb_lib.t6g(sch_1):led_pwrgd_p1v2_aux_d';
NODE_NAME     D6000 C
 '@T6G_MB_LIB.T6G(SCH_1):PAGE254_I43@PURE_QUANTA.Q_LED(CHIPS)':
 'C': CDS_PINID='C';
NODE_NAME     Q6000 6
 '@T6G_MB_LIB.T6G(SCH_1):PAGE254_I47@PURE_QUANTA.MOSFET_NCH_DUAL(CHIPS)':
 'D1': CDS_PINID='D1';
NET_NAME
'LED_PWRGD_P1V8_AUX'
 '@T6G_MB_LIB.T6G(SCH_1):LED_PWRGD_P1V8_AUX':
 C_SIGNAL='@t6g_mb_lib.t6g(sch_1):led_pwrgd_p1v8_aux';
NODE_NAME     R3071 1
 '@T6G_MB_LIB.T6G(SCH_1):PAGE254_I21@PURE_QUANTA.Q_RES(CHIPS)':
 'A': CDS_PINID='A';
NODE_NAME     D91 A
 '@T6G_MB_LIB.T6G(SCH_1):PAGE254_I23@PURE_QUANTA.Q_LED(CHIPS)':
 'A': CDS_PINID='A';
NET_NAME
'LED_PWRGD_P1V8_AUX_D'
 '@T6G_MB_LIB.T6G(SCH_1):LED_PWRGD_P1V8_AUX_D':
 C_SIGNAL='@t6g_mb_lib.t6g(sch_1):led_pwrgd_p1v8_aux_d';
NODE_NAME     D91 C
 '@T6G_MB_LIB.T6G(SCH_1):PAGE254_I23@PURE_QUANTA.Q_LED(CHIPS)':
 'C': CDS_PINID='C';
NODE_NAME     Q78 6
 '@T6G_MB_LIB.T6G(SCH_1):PAGE254_I24@PURE_QUANTA.MOSFET_NCH_DUAL(CHIPS)':
 'D1': CDS_PINID='D1';
NET_NAME
'LED_PWRGD_PS_PWROK_PLD'
 '@T6G_MB_LIB.T6G(SCH_1):LED_PWRGD_PS_PWROK_PLD':
 C_SIGNAL='@t6g_mb_lib.t6g(sch_1):led_pwrgd_ps_pwrok_pld';
NODE_NAME     D96 A
 '@T6G_MB_LIB.T6G(SCH_1):PAGE254_I14@PURE_QUANTA.Q_LED(CHIPS)':
 'A': CDS_PINID='A';
NODE_NAME     R3075 1
 '@T6G_MB_LIB.T6G(SCH_1):PAGE254_I15@PURE_QUANTA.Q_RES(CHIPS)':
 'A': CDS_PINID='A';
NET_NAME
'LED_PWRGD_PS_PWROK_PLD_D'
 '@T6G_MB_LIB.T6G(SCH_1):LED_PWRGD_PS_PWROK_PLD_D':
 C_SIGNAL='@t6g_mb_lib.t6g(sch_1):led_pwrgd_ps_pwrok_pld_d';
NODE_NAME     D96 C
 '@T6G_MB_LIB.T6G(SCH_1):PAGE254_I14@PURE_QUANTA.Q_LED(CHIPS)':
 'C': CDS_PINID='C';
NODE_NAME     Q78 3
 '@T6G_MB_LIB.T6G(SCH_1):PAGE254_I18@PURE_QUANTA.MOSFET_NCH_DUAL(CHIPS)':
 'D2': CDS_PINID='D2';
NET_NAME
'LED_PWRGD_PVDD11_S3_P0_D'
 '@T6G_MB_LIB.T6G(SCH_1):LED_PWRGD_PVDD11_S3_P0_D':
 C_SIGNAL='@t6g_mb_lib.t6g(sch_1):led_pwrgd_pvdd11_s3_p0_d';
NODE_NAME     Q81 3
 '@T6G_MB_LIB.T6G(SCH_1):PAGE374_I27@PURE_QUANTA.MOSFET_NCH_DUAL(CHIPS)':
 'D2': CDS_PINID='D2';
NODE_NAME     D78 C
 '@T6G_MB_LIB.T6G(SCH_1):PAGE374_I32@PURE_QUANTA.Q_LED(CHIPS)':
 'C': CDS_PINID='C';
NET_NAME
'LED_PWRGD_PVDD11_S3_P0_R'
 '@T6G_MB_LIB.T6G(SCH_1):LED_PWRGD_PVDD11_S3_P0_R':
 C_SIGNAL='@t6g_mb_lib.t6g(sch_1):led_pwrgd_pvdd11_s3_p0_r';
NODE_NAME     D78 A
 '@T6G_MB_LIB.T6G(SCH_1):PAGE374_I32@PURE_QUANTA.Q_LED(CHIPS)':
 'A': CDS_PINID='A';
NODE_NAME     R3090 1
 '@T6G_MB_LIB.T6G(SCH_1):PAGE374_I38@PURE_QUANTA.Q_RES(CHIPS)':
 'A': CDS_PINID='A';
NET_NAME
'LED_PWRGD_PVDD11_S3_P1_D'
 '@T6G_MB_LIB.T6G(SCH_1):LED_PWRGD_PVDD11_S3_P1_D':
 C_SIGNAL='@t6g_mb_lib.t6g(sch_1):led_pwrgd_pvdd11_s3_p1_d';
NODE_NAME     Q86 6
 '@T6G_MB_LIB.T6G(SCH_1):PAGE375_I30@PURE_QUANTA.MOSFET_NCH_DUAL(CHIPS)':
 'D1': CDS_PINID='D1';
NODE_NAME     D84 C
 '@T6G_MB_LIB.T6G(SCH_1):PAGE375_I35@PURE_QUANTA.Q_LED(CHIPS)':
 'C': CDS_PINID='C';
NET_NAME
'LED_PWRGD_PVDD11_S3_P1_R'
 '@T6G_MB_LIB.T6G(SCH_1):LED_PWRGD_PVDD11_S3_P1_R':
 C_SIGNAL='@t6g_mb_lib.t6g(sch_1):led_pwrgd_pvdd11_s3_p1_r';
NODE_NAME     D84 A
 '@T6G_MB_LIB.T6G(SCH_1):PAGE375_I35@PURE_QUANTA.Q_LED(CHIPS)':
 'A': CDS_PINID='A';
NODE_NAME     R3099 1
 '@T6G_MB_LIB.T6G(SCH_1):PAGE375_I40@PURE_QUANTA.Q_RES(CHIPS)':
 'A': CDS_PINID='A';
NET_NAME
'LED_PWRGD_PVDD18_S5_P0_D'
 '@T6G_MB_LIB.T6G(SCH_1):LED_PWRGD_PVDD18_S5_P0_D':
 C_SIGNAL='@t6g_mb_lib.t6g(sch_1):led_pwrgd_pvdd18_s5_p0_d';
NODE_NAME     Q83 6
 '@T6G_MB_LIB.T6G(SCH_1):PAGE374_I23@PURE_QUANTA.MOSFET_NCH_DUAL(CHIPS)':
 'D1': CDS_PINID='D1';
NODE_NAME     D79 C
 '@T6G_MB_LIB.T6G(SCH_1):PAGE374_I30@PURE_QUANTA.Q_LED(CHIPS)':
 'C': CDS_PINID='C';
NET_NAME
'LED_PWRGD_PVDD18_S5_P0_R'
 '@T6G_MB_LIB.T6G(SCH_1):LED_PWRGD_PVDD18_S5_P0_R':
 C_SIGNAL='@t6g_mb_lib.t6g(sch_1):led_pwrgd_pvdd18_s5_p0_r';
NODE_NAME     D79 A
 '@T6G_MB_LIB.T6G(SCH_1):PAGE374_I30@PURE_QUANTA.Q_LED(CHIPS)':
 'A': CDS_PINID='A';
NODE_NAME     R3091 1
 '@T6G_MB_LIB.T6G(SCH_1):PAGE374_I37@PURE_QUANTA.Q_RES(CHIPS)':
 'A': CDS_PINID='A';
NET_NAME
'LED_PWRGD_PVDD18_S5_P1_D'
 '@T6G_MB_LIB.T6G(SCH_1):LED_PWRGD_PVDD18_S5_P1_D':
 C_SIGNAL='@t6g_mb_lib.t6g(sch_1):led_pwrgd_pvdd18_s5_p1_d';
NODE_NAME     Q86 3
 '@T6G_MB_LIB.T6G(SCH_1):PAGE375_I29@PURE_QUANTA.MOSFET_NCH_DUAL(CHIPS)':
 'D2': CDS_PINID='D2';
NODE_NAME     D85 C
 '@T6G_MB_LIB.T6G(SCH_1):PAGE375_I33@PURE_QUANTA.Q_LED(CHIPS)':
 'C': CDS_PINID='C';
NET_NAME
'LED_PWRGD_PVDD18_S5_P1_R'
 '@T6G_MB_LIB.T6G(SCH_1):LED_PWRGD_PVDD18_S5_P1_R':
 C_SIGNAL='@t6g_mb_lib.t6g(sch_1):led_pwrgd_pvdd18_s5_p1_r';
NODE_NAME     D85 A
 '@T6G_MB_LIB.T6G(SCH_1):PAGE375_I33@PURE_QUANTA.Q_LED(CHIPS)':
 'A': CDS_PINID='A';
NODE_NAME     R3097 1
 '@T6G_MB_LIB.T6G(SCH_1):PAGE375_I38@PURE_QUANTA.Q_RES(CHIPS)':
 'A': CDS_PINID='A';
NET_NAME
'LED_PWRGD_PVDD33_S5_D'
 '@T6G_MB_LIB.T6G(SCH_1):LED_PWRGD_PVDD33_S5_D':
 C_SIGNAL='@t6g_mb_lib.t6g(sch_1):led_pwrgd_pvdd33_s5_d';
NODE_NAME     Q79 6
 '@T6G_MB_LIB.T6G(SCH_1):PAGE374_I18@PURE_QUANTA.MOSFET_NCH_DUAL(CHIPS)':
 'D1': CDS_PINID='D1';
NODE_NAME     D73 C
 '@T6G_MB_LIB.T6G(SCH_1):PAGE374_I19@PURE_QUANTA.Q_LED(CHIPS)':
 'C': CDS_PINID='C';
NET_NAME
'LED_PWRGD_PVDD33_S5_R'
 '@T6G_MB_LIB.T6G(SCH_1):LED_PWRGD_PVDD33_S5_R':
 C_SIGNAL='@t6g_mb_lib.t6g(sch_1):led_pwrgd_pvdd33_s5_r';
NODE_NAME     D73 A
 '@T6G_MB_LIB.T6G(SCH_1):PAGE374_I19@PURE_QUANTA.Q_LED(CHIPS)':
 'A': CDS_PINID='A';
NODE_NAME     R3086 1
 '@T6G_MB_LIB.T6G(SCH_1):PAGE374_I20@PURE_QUANTA.Q_RES(CHIPS)':
 'A': CDS_PINID='A';
NET_NAME
'LED_PWRGD_PVDDCR_CPU0_P0_D'
 '@T6G_MB_LIB.T6G(SCH_1):LED_PWRGD_PVDDCR_CPU0_P0_D':
 C_SIGNAL='@t6g_mb_lib.t6g(sch_1):led_pwrgd_pvddcr_cpu0_p0_d';
NODE_NAME     Q79 3
 '@T6G_MB_LIB.T6G(SCH_1):PAGE374_I8@PURE_QUANTA.MOSFET_NCH_DUAL(CHIPS)':
 'D2': CDS_PINID='D2';
NODE_NAME     D74 C
 '@T6G_MB_LIB.T6G(SCH_1):PAGE374_I14@PURE_QUANTA.Q_LED(CHIPS)':
 'C': CDS_PINID='C';
NET_NAME
'LED_PWRGD_PVDDCR_CPU0_P0_R'
 '@T6G_MB_LIB.T6G(SCH_1):LED_PWRGD_PVDDCR_CPU0_P0_R':
 C_SIGNAL='@t6g_mb_lib.t6g(sch_1):led_pwrgd_pvddcr_cpu0_p0_r';
NODE_NAME     D74 A
 '@T6G_MB_LIB.T6G(SCH_1):PAGE374_I14@PURE_QUANTA.Q_LED(CHIPS)':
 'A': CDS_PINID='A';
NODE_NAME     R3087 1
 '@T6G_MB_LIB.T6G(SCH_1):PAGE374_I16@PURE_QUANTA.Q_RES(CHIPS)':
 'A': CDS_PINID='A';
NET_NAME
'LED_PWRGD_PVDDCR_CPU0_P1_D'
 '@T6G_MB_LIB.T6G(SCH_1):LED_PWRGD_PVDDCR_CPU0_P1_D':
 C_SIGNAL='@t6g_mb_lib.t6g(sch_1):led_pwrgd_pvddcr_cpu0_p1_d';
NODE_NAME     Q84 6
 '@T6G_MB_LIB.T6G(SCH_1):PAGE375_I11@PURE_QUANTA.MOSFET_NCH_DUAL(CHIPS)':
 'D1': CDS_PINID='D1';
NODE_NAME     D80 C
 '@T6G_MB_LIB.T6G(SCH_1):PAGE375_I19@PURE_QUANTA.Q_LED(CHIPS)':
 'C': CDS_PINID='C';
NET_NAME
'LED_PWRGD_PVDDCR_CPU0_P1_R'
 '@T6G_MB_LIB.T6G(SCH_1):LED_PWRGD_PVDDCR_CPU0_P1_R':
 C_SIGNAL='@t6g_mb_lib.t6g(sch_1):led_pwrgd_pvddcr_cpu0_p1_r';
NODE_NAME     D80 A
 '@T6G_MB_LIB.T6G(SCH_1):PAGE375_I19@PURE_QUANTA.Q_LED(CHIPS)':
 'A': CDS_PINID='A';
NODE_NAME     R3093 1
 '@T6G_MB_LIB.T6G(SCH_1):PAGE375_I20@PURE_QUANTA.Q_RES(CHIPS)':
 'A': CDS_PINID='A';
NET_NAME
'LED_PWRGD_PVDDCR_CPU1_P0_D'
 '@T6G_MB_LIB.T6G(SCH_1):LED_PWRGD_PVDDCR_CPU1_P0_D':
 C_SIGNAL='@t6g_mb_lib.t6g(sch_1):led_pwrgd_pvddcr_cpu1_p0_d';
NODE_NAME     Q80 3
 '@T6G_MB_LIB.T6G(SCH_1):PAGE374_I3@PURE_QUANTA.MOSFET_NCH_DUAL(CHIPS)':
 'D2': CDS_PINID='D2';
NODE_NAME     D76 C
 '@T6G_MB_LIB.T6G(SCH_1):PAGE374_I11@PURE_QUANTA.Q_LED(CHIPS)':
 'C': CDS_PINID='C';
NET_NAME
'LED_PWRGD_PVDDCR_CPU1_P0_R'
 '@T6G_MB_LIB.T6G(SCH_1):LED_PWRGD_PVDDCR_CPU1_P0_R':
 C_SIGNAL='@t6g_mb_lib.t6g(sch_1):led_pwrgd_pvddcr_cpu1_p0_r';
NODE_NAME     D76 A
 '@T6G_MB_LIB.T6G(SCH_1):PAGE374_I11@PURE_QUANTA.Q_LED(CHIPS)':
 'A': CDS_PINID='A';
NODE_NAME     R3088 1
 '@T6G_MB_LIB.T6G(SCH_1):PAGE374_I12@PURE_QUANTA.Q_RES(CHIPS)':
 'A': CDS_PINID='A';
NET_NAME
'LED_PWRGD_PVDDCR_CPU1_P1_D'
 '@T6G_MB_LIB.T6G(SCH_1):LED_PWRGD_PVDDCR_CPU1_P1_D':
 C_SIGNAL='@t6g_mb_lib.t6g(sch_1):led_pwrgd_pvddcr_cpu1_p1_d';
NODE_NAME     Q85 6
 '@T6G_MB_LIB.T6G(SCH_1):PAGE375_I7@PURE_QUANTA.MOSFET_NCH_DUAL(CHIPS)':
 'D1': CDS_PINID='D1';
NODE_NAME     D82 C
 '@T6G_MB_LIB.T6G(SCH_1):PAGE375_I14@PURE_QUANTA.Q_LED(CHIPS)':
 'C': CDS_PINID='C';
NET_NAME
'LED_PWRGD_PVDDCR_CPU1_P1_R'
 '@T6G_MB_LIB.T6G(SCH_1):LED_PWRGD_PVDDCR_CPU1_P1_R':
 C_SIGNAL='@t6g_mb_lib.t6g(sch_1):led_pwrgd_pvddcr_cpu1_p1_r';
NODE_NAME     D82 A
 '@T6G_MB_LIB.T6G(SCH_1):PAGE375_I14@PURE_QUANTA.Q_LED(CHIPS)':
 'A': CDS_PINID='A';
NODE_NAME     R3096 1
 '@T6G_MB_LIB.T6G(SCH_1):PAGE375_I16@PURE_QUANTA.Q_RES(CHIPS)':
 'A': CDS_PINID='A';
NET_NAME
'LED_PWRGD_PVDDCR_SOC_P0_D'
 '@T6G_MB_LIB.T6G(SCH_1):LED_PWRGD_PVDDCR_SOC_P0_D':
 C_SIGNAL='@t6g_mb_lib.t6g(sch_1):led_pwrgd_pvddcr_soc_p0_d';
NODE_NAME     Q80 6
 '@T6G_MB_LIB.T6G(SCH_1):PAGE374_I6@PURE_QUANTA.MOSFET_NCH_DUAL(CHIPS)':
 'D1': CDS_PINID='D1';
NODE_NAME     D75 C
 '@T6G_MB_LIB.T6G(SCH_1):PAGE374_I13@PURE_QUANTA.Q_LED(CHIPS)':
 'C': CDS_PINID='C';
NET_NAME
'LED_PWRGD_PVDDCR_SOC_P0_R'
 '@T6G_MB_LIB.T6G(SCH_1):LED_PWRGD_PVDDCR_SOC_P0_R':
 C_SIGNAL='@t6g_mb_lib.t6g(sch_1):led_pwrgd_pvddcr_soc_p0_r';
NODE_NAME     D75 A
 '@T6G_MB_LIB.T6G(SCH_1):PAGE374_I13@PURE_QUANTA.Q_LED(CHIPS)':
 'A': CDS_PINID='A';
NODE_NAME     R3089 1
 '@T6G_MB_LIB.T6G(SCH_1):PAGE374_I15@PURE_QUANTA.Q_RES(CHIPS)':
 'A': CDS_PINID='A';
NET_NAME
'LED_PWRGD_PVDDCR_SOC_P1_D'
 '@T6G_MB_LIB.T6G(SCH_1):LED_PWRGD_PVDDCR_SOC_P1_D':
 C_SIGNAL='@t6g_mb_lib.t6g(sch_1):led_pwrgd_pvddcr_soc_p1_d';
NODE_NAME     Q84 3
 '@T6G_MB_LIB.T6G(SCH_1):PAGE375_I10@PURE_QUANTA.MOSFET_NCH_DUAL(CHIPS)':
 'D2': CDS_PINID='D2';
NODE_NAME     D81 C
 '@T6G_MB_LIB.T6G(SCH_1):PAGE375_I17@PURE_QUANTA.Q_LED(CHIPS)':
 'C': CDS_PINID='C';
NET_NAME
'LED_PWRGD_PVDDCR_SOC_P1_R'
 '@T6G_MB_LIB.T6G(SCH_1):LED_PWRGD_PVDDCR_SOC_P1_R':
 C_SIGNAL='@t6g_mb_lib.t6g(sch_1):led_pwrgd_pvddcr_soc_p1_r';
NODE_NAME     D81 A
 '@T6G_MB_LIB.T6G(SCH_1):PAGE375_I17@PURE_QUANTA.Q_LED(CHIPS)':
 'A': CDS_PINID='A';
NODE_NAME     R3094 1
 '@T6G_MB_LIB.T6G(SCH_1):PAGE375_I18@PURE_QUANTA.Q_RES(CHIPS)':
 'A': CDS_PINID='A';
NET_NAME
'LED_PWRGD_PVDDIO_P0_D'
 '@T6G_MB_LIB.T6G(SCH_1):LED_PWRGD_PVDDIO_P0_D':
 C_SIGNAL='@t6g_mb_lib.t6g(sch_1):led_pwrgd_pvddio_p0_d';
NODE_NAME     Q81 6
 '@T6G_MB_LIB.T6G(SCH_1):PAGE374_I35@PURE_QUANTA.MOSFET_NCH_DUAL(CHIPS)':
 'D1': CDS_PINID='D1';
NODE_NAME     D77 C
 '@T6G_MB_LIB.T6G(SCH_1):PAGE374_I36@PURE_QUANTA.Q_LED(CHIPS)':
 'C': CDS_PINID='C';
NET_NAME
'LED_PWRGD_PVDDIO_P0_R'
 '@T6G_MB_LIB.T6G(SCH_1):LED_PWRGD_PVDDIO_P0_R':
 C_SIGNAL='@t6g_mb_lib.t6g(sch_1):led_pwrgd_pvddio_p0_r';
NODE_NAME     D77 A
 '@T6G_MB_LIB.T6G(SCH_1):PAGE374_I36@PURE_QUANTA.Q_LED(CHIPS)':
 'A': CDS_PINID='A';
NODE_NAME     R3092 1
 '@T6G_MB_LIB.T6G(SCH_1):PAGE374_I41@PURE_QUANTA.Q_RES(CHIPS)':
 'A': CDS_PINID='A';
NET_NAME
'LED_PWRGD_PVDDIO_P1_D'
 '@T6G_MB_LIB.T6G(SCH_1):LED_PWRGD_PVDDIO_P1_D':
 C_SIGNAL='@t6g_mb_lib.t6g(sch_1):led_pwrgd_pvddio_p1_d';
NODE_NAME     Q85 3
 '@T6G_MB_LIB.T6G(SCH_1):PAGE375_I2@PURE_QUANTA.MOSFET_NCH_DUAL(CHIPS)':
 'D2': CDS_PINID='D2';
NODE_NAME     D83 C
 '@T6G_MB_LIB.T6G(SCH_1):PAGE375_I13@PURE_QUANTA.Q_LED(CHIPS)':
 'C': CDS_PINID='C';
NET_NAME
'LED_PWRGD_PVDDIO_P1_R'
 '@T6G_MB_LIB.T6G(SCH_1):LED_PWRGD_PVDDIO_P1_R':
 C_SIGNAL='@t6g_mb_lib.t6g(sch_1):led_pwrgd_pvddio_p1_r';
NODE_NAME     D83 A
 '@T6G_MB_LIB.T6G(SCH_1):PAGE375_I13@PURE_QUANTA.Q_LED(CHIPS)':
 'A': CDS_PINID='A';
NODE_NAME     R3095 1
 '@T6G_MB_LIB.T6G(SCH_1):PAGE375_I15@PURE_QUANTA.Q_RES(CHIPS)':
 'A': CDS_PINID='A';
NET_NAME
'LED_PWRGD_SYS_PWROK_R'
 '@T6G_MB_LIB.T6G(SCH_1):LED_PWRGD_SYS_PWROK_R':
 C_SIGNAL='@t6g_mb_lib.t6g(sch_1):led_pwrgd_sys_pwrok_r';
NODE_NAME     R3069 1
 '@T6G_MB_LIB.T6G(SCH_1):PAGE254_I32@PURE_QUANTA.Q_RES(CHIPS)':
 'A': CDS_PINID='A';
NODE_NAME     D88 A
 '@T6G_MB_LIB.T6G(SCH_1):PAGE254_I33@PURE_QUANTA.Q_LED(CHIPS)':
 'A': CDS_PINID='A';
NET_NAME
'LED_PWRGD_SYS_PWROK_R_D'
 '@T6G_MB_LIB.T6G(SCH_1):LED_PWRGD_SYS_PWROK_R_D':
 C_SIGNAL='@t6g_mb_lib.t6g(sch_1):led_pwrgd_sys_pwrok_r_d';
NODE_NAME     D88 C
 '@T6G_MB_LIB.T6G(SCH_1):PAGE254_I33@PURE_QUANTA.Q_LED(CHIPS)':
 'C': CDS_PINID='C';
NODE_NAME     Q87 3
 '@T6G_MB_LIB.T6G(SCH_1):PAGE254_I35@PURE_QUANTA.MOSFET_NCH_DUAL(CHIPS)':
 'D2': CDS_PINID='D2';
NET_NAME
'LED_RST_RSMRST_PLD_R_N'
 '@T6G_MB_LIB.T6G(SCH_1):LED_RST_RSMRST_PLD_R_N':
 C_SIGNAL='@t6g_mb_lib.t6g(sch_1):led_rst_rsmrst_pld_r_n';
NODE_NAME     D93 A
 '@T6G_MB_LIB.T6G(SCH_1):PAGE254_I40@PURE_QUANTA.Q_LED(CHIPS)':
 'A': CDS_PINID='A';
NODE_NAME     R3074 1
 '@T6G_MB_LIB.T6G(SCH_1):PAGE254_I41@PURE_QUANTA.Q_RES(CHIPS)':
 'A': CDS_PINID='A';
NET_NAME
'LED_RST_RSMRST_PLD_R_N_D'
 '@T6G_MB_LIB.T6G(SCH_1):LED_RST_RSMRST_PLD_R_N_D':
 C_SIGNAL='@t6g_mb_lib.t6g(sch_1):led_rst_rsmrst_pld_r_n_d';
NODE_NAME     Q87 6
 '@T6G_MB_LIB.T6G(SCH_1):PAGE254_I38@PURE_QUANTA.MOSFET_NCH_DUAL(CHIPS)':
 'D1': CDS_PINID='D1';
NODE_NAME     D93 C
 '@T6G_MB_LIB.T6G(SCH_1):PAGE254_I40@PURE_QUANTA.Q_LED(CHIPS)':
 'C': CDS_PINID='C';
NET_NAME
'M2_0_P3V3_ADC_ALERT'
 '@T6G_MB_LIB.T6G(SCH_1):M2_0_P3V3_ADC_ALERT':
 C_SIGNAL='@t6g_mb_lib.t6g(sch_1):m2_0_p3v3_adc_alert';
NODE_NAME     R3560 2
 '@T6G_MB_LIB.T6G(SCH_1):PAGE360_I41@PURE_QUANTA.Q_RES(CHIPS)':
 'B': CDS_PINID='B';
NODE_NAME     U18 M1
 '@T6G_MB_LIB.T6G(SCH_1):PAGE81_I143@PURE_QUANTA.LCMXO3LF9400C5BG484C(CHIPS)':
 'PL17A': CDS_PINID='PL17A';
NET_NAME
'M2_0_P3V3_ADC_ALERT_R'
 '@T6G_MB_LIB.T6G(SCH_1):M2_0_P3V3_ADC_ALERT_R':
 C_SIGNAL='@t6g_mb_lib.t6g(sch_1):m2_0_p3v3_adc_alert_r';
NODE_NAME     R3560 1
 '@T6G_MB_LIB.T6G(SCH_1):PAGE360_I41@PURE_QUANTA.Q_RES(CHIPS)':
 'A': CDS_PINID='A';
NODE_NAME     U264 3
 '@T6G_MB_LIB.T6G(SCH_1):PAGE360_I46@PURE_QUANTA.ISL28022FRZT(CHIPS)':
 'EXT_CLK||INT': CDS_PINID='\ext_clk||int\';
NODE_NAME     R4090 2
 '@T6G_MB_LIB.T6G(SCH_1):PAGE360_I124@PURE_QUANTA.Q_RES(CHIPS)':
 'B': CDS_PINID='B';
NET_NAME
'M2_0_PEWAKE_N'
 '@T6G_MB_LIB.T6G(SCH_1):M2_0_PEWAKE_N':
 C_SIGNAL='@t6g_mb_lib.t6g(sch_1):m2_0_pewake_n';
NODE_NAME     J59 54
 '@T6G_MB_LIB.T6G(SCH_1):PAGE345_I88@PURE_QUANTA.SCONN75K_APCI0155P004A(CHIPS)':
 'PEWAKE#': CDS_PINID='\pewake#\';
NODE_NAME     R3301 2
 '@T6G_MB_LIB.T6G(SCH_1):PAGE345_I30@PURE_QUANTA.Q_RES(CHIPS)':
 'B': CDS_PINID='B';
NET_NAME
'M2_0_PEWAKE_R_N'
 '@T6G_MB_LIB.T6G(SCH_1):M2_0_PEWAKE_R_N':
 C_SIGNAL='@t6g_mb_lib.t6g(sch_1):m2_0_pewake_r_n';
NODE_NAME     R3301 1
 '@T6G_MB_LIB.T6G(SCH_1):PAGE345_I30@PURE_QUANTA.Q_RES(CHIPS)':
 'A': CDS_PINID='A';
NODE_NAME     R1005 1
 '@T6G_MB_LIB.T6G(SCH_1):PAGE132_I4@PURE_QUANTA.Q_RES(CHIPS)':
 'A': CDS_PINID='A';
NET_NAME
'M2_SSD0_CLKREQ_EN_N'
 '@T6G_MB_LIB.T6G(SCH_1):M2_SSD0_CLKREQ_EN_N':
 C_SIGNAL='@t6g_mb_lib.t6g(sch_1):m2_ssd0_clkreq_en_n';
NODE_NAME     U259 1
 '@T6G_MB_LIB.T6G(SCH_1):PAGE345_I5@PURE_QUANTA.SN74LVC2G07DCKR(CHIPS)':
 '1A': CDS_PINID='\1a\';
NODE_NAME     R138 1
 '@T6G_MB_LIB.T6G(SCH_1):PAGE345_I15@PURE_QUANTA.Q_RES(CHIPS)':
 'A': CDS_PINID='A';
NODE_NAME     R153 1
 '@T6G_MB_LIB.T6G(SCH_1):PAGE345_I27@PURE_QUANTA.Q_RES(CHIPS)':
 'A': CDS_PINID='A';
NODE_NAME     R6053 1
 '@T6G_MB_LIB.T6G(SCH_1):PAGE81_I85@PURE_QUANTA.Q_RES(CHIPS)':
 'A': CDS_PINID='A';
NET_NAME
'M2_SSD0_CLKREQ_EN_N_BUF'
 '@T6G_MB_LIB.T6G(SCH_1):M2_SSD0_CLKREQ_EN_N_BUF':
 C_SIGNAL='@t6g_mb_lib.t6g(sch_1):m2_ssd0_clkreq_en_n_buf';
NODE_NAME     J59 52
 '@T6G_MB_LIB.T6G(SCH_1):PAGE345_I88@PURE_QUANTA.SCONN75K_APCI0155P004A(CHIPS)':
 'CLKREQ#': CDS_PINID='\clkreq#\';
NODE_NAME     R153 2
 '@T6G_MB_LIB.T6G(SCH_1):PAGE345_I27@PURE_QUANTA.Q_RES(CHIPS)':
 'B': CDS_PINID='B';
NODE_NAME     R155 2
 '@T6G_MB_LIB.T6G(SCH_1):PAGE345_I32@PURE_QUANTA.Q_RES(CHIPS)':
 'B': CDS_PINID='B';
NET_NAME
'MAX11617_2_VREF'
 '@T6G_MB_LIB.T6G(SCH_1):MAX11617_2_VREF':
 C_SIGNAL='@t6g_mb_lib.t6g(sch_1):max11617_2_vref';
NODE_NAME     C1074 1
 '@T6G_MB_LIB.T6G(SCH_1):PAGE263_I115@PURE_QUANTA.Q_CAP(CHIPS)':
 'A': CDS_PINID='A';
NODE_NAME     C1076 1
 '@T6G_MB_LIB.T6G(SCH_1):PAGE263_I152@PURE_QUANTA.Q_CAP(CHIPS)':
 'A': CDS_PINID='A';
NODE_NAME     R1230 1
 '@T6G_MB_LIB.T6G(SCH_1):PAGE263_I154@PURE_QUANTA.Q_RES(CHIPS)':
 'A': CDS_PINID='A';
NET_NAME
'MAX11617_2_VREF_R'
 '@T6G_MB_LIB.T6G(SCH_1):MAX11617_2_VREF_R':
 C_SIGNAL='@t6g_mb_lib.t6g(sch_1):max11617_2_vref_r';
NODE_NAME     R1230 2
 '@T6G_MB_LIB.T6G(SCH_1):PAGE263_I154@PURE_QUANTA.Q_RES(CHIPS)':
 'B': CDS_PINID='B';
NODE_NAME     U50 1
 '@T6G_MB_LIB.T6G(SCH_1):PAGE263_I156@PURE_QUANTA.MAX11617EEET(CHIPS)':
 'AIN11||REF': CDS_PINID='\ain11||ref\';
NET_NAME
'MAX11617_VREF'
 '@T6G_MB_LIB.T6G(SCH_1):MAX11617_VREF':
 C_SIGNAL='@t6g_mb_lib.t6g(sch_1):max11617_vref';
NODE_NAME     C1347 1
 '@T6G_MB_LIB.T6G(SCH_1):PAGE369_I119@PURE_QUANTA.Q_CAP(CHIPS)':
 'A': CDS_PINID='A';
NODE_NAME     C1767 1
 '@T6G_MB_LIB.T6G(SCH_1):PAGE369_I121@PURE_QUANTA.Q_CAP(CHIPS)':
 'A': CDS_PINID='A';
NODE_NAME     R2900 1
 '@T6G_MB_LIB.T6G(SCH_1):PAGE369_I160@PURE_QUANTA.Q_RES(CHIPS)':
 'A': CDS_PINID='A';
NET_NAME
'MAX11617_VREF_R'
 '@T6G_MB_LIB.T6G(SCH_1):MAX11617_VREF_R':
 C_SIGNAL='@t6g_mb_lib.t6g(sch_1):max11617_vref_r';
NODE_NAME     R2900 2
 '@T6G_MB_LIB.T6G(SCH_1):PAGE369_I160@PURE_QUANTA.Q_RES(CHIPS)':
 'B': CDS_PINID='B';
NODE_NAME     U193 1
 '@T6G_MB_LIB.T6G(SCH_1):PAGE369_I169@PURE_QUANTA.MAX11617EEET(CHIPS)':
 'AIN11||REF': CDS_PINID='\ain11||ref\';
NET_NAME
'MB0_CM_GATE_G0'
 '@T6G_MB_LIB.T6G(SCH_1):MB0_CM_GATE_G0':
 C_SIGNAL='@t6g_mb_lib.t6g(sch_1):mb0_cm_gate_g0';
NODE_NAME     PR2538 1
 '@T6G_MB_LIB.T6G(SCH_1):PAGE302_I74@PURE_QUANTA.Q_RES(CHIPS)':
 'A': CDS_PINID='A';
NODE_NAME     PPQ9 4
 '@T6G_MB_LIB.T6G(SCH_1):PAGE302_I75@PURE_QUANTA.MOSFET_NCH_1D3S(CHIPS)':
 '4': CDS_PINID='\4\';
NET_NAME
'MB0_P12V_STBY_PWRGD'
 '@T6G_MB_LIB.T6G(SCH_1):MB0_P12V_STBY_PWRGD':
 C_SIGNAL='@t6g_mb_lib.t6g(sch_1):mb0_p12v_stby_pwrgd';
NODE_NAME     R2531 1
 '@T6G_MB_LIB.T6G(SCH_1):PAGE365_I3@PURE_QUANTA.Q_RES(CHIPS)':
 'A': CDS_PINID='A';
NODE_NAME     R3048 1
 '@T6G_MB_LIB.T6G(SCH_1):PAGE368_I7@PURE_QUANTA.Q_RES(CHIPS)':
 'A': CDS_PINID='A';
NODE_NAME     R3047 1
 '@T6G_MB_LIB.T6G(SCH_1):PAGE368_I8@PURE_QUANTA.Q_RES(CHIPS)':
 'A': CDS_PINID='A';
NODE_NAME     R6097 1
 '@T6G_MB_LIB.T6G(SCH_1):PAGE244_I40@PURE_QUANTA.Q_RES(CHIPS)':
 'A': CDS_PINID='A';
NODE_NAME     R1117 1
 '@T6G_MB_LIB.T6G(SCH_1):PAGE267_I22@PURE_QUANTA.Q_RES(CHIPS)':
 'A': CDS_PINID='A';
NODE_NAME     PU289 13
 '@T6G_MB_LIB.T6G(SCH_1):PAGE267_I58@PURE_QUANTA.MP5990GMA1111Z(CHIPS)':
 'PG||OCW#': CDS_PINID='\pg||ocw#\';
NODE_NAME     R3933 2
 '@T6G_MB_LIB.T6G(SCH_1):PAGE267_I63@PURE_QUANTA.Q_RES(CHIPS)':
 'B': CDS_PINID='B';
NODE_NAME     PJ38 15
 '@T6G_MB_LIB.T6G(SCH_1):PAGE371_I42@PURE_QUANTA.SCONN21_9193031121LF(CHIPS)':
 '15': CDS_PINID='\15\';
NET_NAME
'MB_FRU_ADDR0'
 '@T6G_MB_LIB.T6G(SCH_1):MB_FRU_ADDR0':
 C_SIGNAL='@t6g_mb_lib.t6g(sch_1):mb_fru_addr0';
NODE_NAME     U64 1
 '@T6G_MB_LIB.T6G(SCH_1):PAGE361_I35@PURE_QUANTA.M24128BWMN6TP(CHIPS)':
 'E0': CDS_PINID='E0';
NODE_NAME     R722 1
 '@T6G_MB_LIB.T6G(SCH_1):PAGE361_I61@PURE_QUANTA.Q_RES(CHIPS)':
 'A': CDS_PINID='A';
NODE_NAME     R721 2
 '@T6G_MB_LIB.T6G(SCH_1):PAGE361_I62@PURE_QUANTA.Q_RES(CHIPS)':
 'B': CDS_PINID='B';
NET_NAME
'MB_FRU_ADDR1'
 '@T6G_MB_LIB.T6G(SCH_1):MB_FRU_ADDR1':
 C_SIGNAL='@t6g_mb_lib.t6g(sch_1):mb_fru_addr1';
NODE_NAME     U64 2
 '@T6G_MB_LIB.T6G(SCH_1):PAGE361_I35@PURE_QUANTA.M24128BWMN6TP(CHIPS)':
 'E1': CDS_PINID='E1';
NODE_NAME     R717 2
 '@T6G_MB_LIB.T6G(SCH_1):PAGE361_I45@PURE_QUANTA.Q_RES(CHIPS)':
 'B': CDS_PINID='B';
NODE_NAME     R718 1
 '@T6G_MB_LIB.T6G(SCH_1):PAGE361_I50@PURE_QUANTA.Q_RES(CHIPS)':
 'A': CDS_PINID='A';
NET_NAME
'MB_FRU_ADDR2'
 '@T6G_MB_LIB.T6G(SCH_1):MB_FRU_ADDR2':
 C_SIGNAL='@t6g_mb_lib.t6g(sch_1):mb_fru_addr2';
NODE_NAME     U64 3
 '@T6G_MB_LIB.T6G(SCH_1):PAGE361_I35@PURE_QUANTA.M24128BWMN6TP(CHIPS)':
 'E2': CDS_PINID='E2';
NODE_NAME     R713 2
 '@T6G_MB_LIB.T6G(SCH_1):PAGE361_I47@PURE_QUANTA.Q_RES(CHIPS)':
 'B': CDS_PINID='B';
NODE_NAME     R714 1
 '@T6G_MB_LIB.T6G(SCH_1):PAGE361_I52@PURE_QUANTA.Q_RES(CHIPS)':
 'A': CDS_PINID='A';
NET_NAME
'MB_PDB_SMB9_R_EN'
 '@T6G_MB_LIB.T6G(SCH_1):MB_PDB_SMB9_R_EN':
 C_SIGNAL='@t6g_mb_lib.t6g(sch_1):mb_pdb_smb9_r_en';
NODE_NAME     U192 1
 '@T6G_MB_LIB.T6G(SCH_1):PAGE363_I398@PURE_QUANTA.LTC4307CMS8(CHIPS)':
 'ENABLE': CDS_PINID='ENABLE';
NODE_NAME     R2796 2
 '@T6G_MB_LIB.T6G(SCH_1):PAGE363_I420@PURE_QUANTA.Q_RES(CHIPS)':
 'B': CDS_PINID='B';
NET_NAME
'MODE_RT_CPU0_P0'
 '@T6G_MB_LIB.T6G(SCH_1):MODE_RT_CPU0_P0':
 C_SIGNAL='@t6g_mb_lib.t6g(sch_1):mode_rt_cpu0_p0';
NODE_NAME     U6010 FJ9
 '@T6G_MB_LIB.T6G(SCH_1):PAGE385_I53@PURE_QUANTA.PT5161LRS(CHIPS)':
 'MODE': CDS_PINID='MODE';
NODE_NAME     R1001 1
 '@T6G_MB_LIB.T6G(SCH_1):PAGE385_I71@PURE_QUANTA.Q_RES(CHIPS)':
 'A': CDS_PINID='A';
NODE_NAME     R998 2
 '@T6G_MB_LIB.T6G(SCH_1):PAGE385_I72@PURE_QUANTA.Q_RES(CHIPS)':
 'B': CDS_PINID='B';
NET_NAME
'MODE_RT_CPU0_P1'
 '@T6G_MB_LIB.T6G(SCH_1):MODE_RT_CPU0_P1':
 C_SIGNAL='@t6g_mb_lib.t6g(sch_1):mode_rt_cpu0_p1';
NODE_NAME     R1006 1
 '@T6G_MB_LIB.T6G(SCH_1):PAGE408_I50@PURE_QUANTA.Q_RES(CHIPS)':
 'A': CDS_PINID='A';
NODE_NAME     R1039 2
 '@T6G_MB_LIB.T6G(SCH_1):PAGE408_I51@PURE_QUANTA.Q_RES(CHIPS)':
 'B': CDS_PINID='B';
NODE_NAME     U6011 FJ9
 '@T6G_MB_LIB.T6G(SCH_1):PAGE408_I83@PURE_QUANTA.PT5161LRS(CHIPS)':
 'MODE': CDS_PINID='MODE';
NET_NAME
'MODE_RT_CPU0_P2'
 '@T6G_MB_LIB.T6G(SCH_1):MODE_RT_CPU0_P2':
 C_SIGNAL='@t6g_mb_lib.t6g(sch_1):mode_rt_cpu0_p2';
NODE_NAME     R1048 1
 '@T6G_MB_LIB.T6G(SCH_1):PAGE419_I50@PURE_QUANTA.Q_RES(CHIPS)':
 'A': CDS_PINID='A';
NODE_NAME     R1080 2
 '@T6G_MB_LIB.T6G(SCH_1):PAGE419_I51@PURE_QUANTA.Q_RES(CHIPS)':
 'B': CDS_PINID='B';
NODE_NAME     U6012 FJ9
 '@T6G_MB_LIB.T6G(SCH_1):PAGE419_I83@PURE_QUANTA.PT5161LRS(CHIPS)':
 'MODE': CDS_PINID='MODE';
NET_NAME
'MODE_RT_CPU0_P3'
 '@T6G_MB_LIB.T6G(SCH_1):MODE_RT_CPU0_P3':
 C_SIGNAL='@t6g_mb_lib.t6g(sch_1):mode_rt_cpu0_p3';
NODE_NAME     R1091 1
 '@T6G_MB_LIB.T6G(SCH_1):PAGE430_I50@PURE_QUANTA.Q_RES(CHIPS)':
 'A': CDS_PINID='A';
NODE_NAME     R1122 2
 '@T6G_MB_LIB.T6G(SCH_1):PAGE430_I51@PURE_QUANTA.Q_RES(CHIPS)':
 'B': CDS_PINID='B';
NODE_NAME     U6013 FJ9
 '@T6G_MB_LIB.T6G(SCH_1):PAGE430_I83@PURE_QUANTA.PT5161LRS(CHIPS)':
 'MODE': CDS_PINID='MODE';
NET_NAME
'MODE_RT_CPU1_P0'
 '@T6G_MB_LIB.T6G(SCH_1):MODE_RT_CPU1_P0':
 C_SIGNAL='@t6g_mb_lib.t6g(sch_1):mode_rt_cpu1_p0';
NODE_NAME     U6014 FJ9
 '@T6G_MB_LIB.T6G(SCH_1):PAGE401_I1@PURE_QUANTA.PT5161LRS(CHIPS)':
 'MODE': CDS_PINID='MODE';
NODE_NAME     R727 2
 '@T6G_MB_LIB.T6G(SCH_1):PAGE401_I54@PURE_QUANTA.Q_RES(CHIPS)':
 'B': CDS_PINID='B';
NODE_NAME     R728 1
 '@T6G_MB_LIB.T6G(SCH_1):PAGE401_I55@PURE_QUANTA.Q_RES(CHIPS)':
 'A': CDS_PINID='A';
NET_NAME
'MODE_RT_CPU1_P1'
 '@T6G_MB_LIB.T6G(SCH_1):MODE_RT_CPU1_P1':
 C_SIGNAL='@t6g_mb_lib.t6g(sch_1):mode_rt_cpu1_p1';
NODE_NAME     U6015 FJ9
 '@T6G_MB_LIB.T6G(SCH_1):PAGE392_I47@PURE_QUANTA.PT5161LRS(CHIPS)':
 'MODE': CDS_PINID='MODE';
NODE_NAME     R794 1
 '@T6G_MB_LIB.T6G(SCH_1):PAGE392_I65@PURE_QUANTA.Q_RES(CHIPS)':
 'A': CDS_PINID='A';
NODE_NAME     R793 2
 '@T6G_MB_LIB.T6G(SCH_1):PAGE392_I66@PURE_QUANTA.Q_RES(CHIPS)':
 'B': CDS_PINID='B';
NET_NAME
'MODE_RT_CPU1_P2'
 '@T6G_MB_LIB.T6G(SCH_1):MODE_RT_CPU1_P2':
 C_SIGNAL='@t6g_mb_lib.t6g(sch_1):mode_rt_cpu1_p2';
NODE_NAME     R886 1
 '@T6G_MB_LIB.T6G(SCH_1):PAGE451_I58@PURE_QUANTA.Q_RES(CHIPS)':
 'A': CDS_PINID='A';
NODE_NAME     R885 2
 '@T6G_MB_LIB.T6G(SCH_1):PAGE451_I59@PURE_QUANTA.Q_RES(CHIPS)':
 'B': CDS_PINID='B';
NODE_NAME     U6016 FJ9
 '@T6G_MB_LIB.T6G(SCH_1):PAGE451_I97@PURE_QUANTA.PT5161LRS(CHIPS)':
 'MODE': CDS_PINID='MODE';
NET_NAME
'MODE_RT_CPU1_P3'
 '@T6G_MB_LIB.T6G(SCH_1):MODE_RT_CPU1_P3':
 C_SIGNAL='@t6g_mb_lib.t6g(sch_1):mode_rt_cpu1_p3';
NODE_NAME     R926 1
 '@T6G_MB_LIB.T6G(SCH_1):PAGE462_I64@PURE_QUANTA.Q_RES(CHIPS)':
 'A': CDS_PINID='A';
NODE_NAME     R925 2
 '@T6G_MB_LIB.T6G(SCH_1):PAGE462_I65@PURE_QUANTA.Q_RES(CHIPS)':
 'B': CDS_PINID='B';
NODE_NAME     U6017 FJ9
 '@T6G_MB_LIB.T6G(SCH_1):PAGE462_I97@PURE_QUANTA.PT5161LRS(CHIPS)':
 'MODE': CDS_PINID='MODE';
NET_NAME
'M_A_CPU0_ALERT_N'
 '@T6G_MB_LIB.T6G(SCH_1):M_A_CPU0_ALERT_N':
 C_SIGNAL='@t6g_mb_lib.t6g(sch_1):m_a_cpu0_alert_n';
NODE_NAME     R375 1
 '@T6G_MB_LIB.T6G(SCH_1):PAGE10_I837@PURE_QUANTA.Q_RES(CHIPS)':
 'A': CDS_PINID='A';
NODE_NAME     J1 62
 '@T6G_MB_LIB.T6G(SCH_1):PAGE85_I536@PURE_QUANTA.SCONN288_DDR506112002KQ(CHIPS)':
 'ALERT_N': CDS_PINID='ALERT_N';
NET_NAME
'M_A_CPU0_ALERT_R_N'
 '@T6G_MB_LIB.T6G(SCH_1):M_A_CPU0_ALERT_R_N':
 C_SIGNAL='@t6g_mb_lib.t6g(sch_1):m_a_cpu0_alert_r_n';
NODE_NAME     U25 AR74
 '@T6G_MB_LIB.T6G(SCH_1):PAGE10_I200@PURE_QUANTA.GENOA_SP5(CHIPS)':
 'MA_ALERT_L': CDS_PINID='MA_ALERT_L';
NODE_NAME     R375 2
 '@T6G_MB_LIB.T6G(SCH_1):PAGE10_I837@PURE_QUANTA.Q_RES(CHIPS)':
 'B': CDS_PINID='B';
NET_NAME
'M_A_CPU0_CLK_DN<0>'
 '@T6G_MB_LIB.T6G(SCH_1):M_A_CPU0_CLK_DN'<0>:
 C_SIGNAL='@t6g_mb_lib.t6g(sch_1):m_a_cpu0_clk_dn(0)';
NODE_NAME     U25 BD74
 '@T6G_MB_LIB.T6G(SCH_1):PAGE10_I200@PURE_QUANTA.GENOA_SP5(CHIPS)':
 'MA0_CLK_L': CDS_PINID='MA0_CLK_L';
NODE_NAME     J1 218
 '@T6G_MB_LIB.T6G(SCH_1):PAGE85_I536@PURE_QUANTA.SCONN288_DDR506112002KQ(CHIPS)':
 'CK_C': CDS_PINID='CK_C';
NET_NAME
'M_A_CPU0_CLK_DP<0>'
 '@T6G_MB_LIB.T6G(SCH_1):M_A_CPU0_CLK_DP'<0>:
 C_SIGNAL='@t6g_mb_lib.t6g(sch_1):m_a_cpu0_clk_dp(0)';
NODE_NAME     U25 BC74
 '@T6G_MB_LIB.T6G(SCH_1):PAGE10_I200@PURE_QUANTA.GENOA_SP5(CHIPS)':
 'MA0_CLK_H': CDS_PINID='MA0_CLK_H';
NODE_NAME     J1 217
 '@T6G_MB_LIB.T6G(SCH_1):PAGE85_I536@PURE_QUANTA.SCONN288_DDR506112002KQ(CHIPS)':
 'CK_T': CDS_PINID='CK_T';
NET_NAME
'M_A_CPU0_RESET_N'
 '@T6G_MB_LIB.T6G(SCH_1):M_A_CPU0_RESET_N':
 C_SIGNAL='@t6g_mb_lib.t6g(sch_1):m_a_cpu0_reset_n';
NODE_NAME     U25 AT74
 '@T6G_MB_LIB.T6G(SCH_1):PAGE10_I200@PURE_QUANTA.GENOA_SP5(CHIPS)':
 'MA_RESET_L': CDS_PINID='MA_RESET_L';
NODE_NAME     J1 207
 '@T6G_MB_LIB.T6G(SCH_1):PAGE85_I536@PURE_QUANTA.SCONN288_DDR506112002KQ(CHIPS)':
 'RESET_N': CDS_PINID='RESET_N';
NET_NAME
'M_A_CPU0_SA_CA<0>'
 '@T6G_MB_LIB.T6G(SCH_1):M_A_CPU0_SA_CA'<0>:
 C_SIGNAL='@t6g_mb_lib.t6g(sch_1):m_a_cpu0_sa_ca(0)';
NODE_NAME     U25 AW74
 '@T6G_MB_LIB.T6G(SCH_1):PAGE10_I200@PURE_QUANTA.GENOA_SP5(CHIPS)':
 'MAA_CA0': CDS_PINID='MAA_CA0';
NODE_NAME     J1 66
 '@T6G_MB_LIB.T6G(SCH_1):PAGE85_I536@PURE_QUANTA.SCONN288_DDR506112002KQ(CHIPS)':
 'CA0_A': CDS_PINID='CA0_A';
NET_NAME
'M_A_CPU0_SA_CA<1>'
 '@T6G_MB_LIB.T6G(SCH_1):M_A_CPU0_SA_CA'<1>:
 C_SIGNAL='@t6g_mb_lib.t6g(sch_1):m_a_cpu0_sa_ca(1)';
NODE_NAME     U25 AY74
 '@T6G_MB_LIB.T6G(SCH_1):PAGE10_I200@PURE_QUANTA.GENOA_SP5(CHIPS)':
 'MAA_CA1': CDS_PINID='MAA_CA1';
NODE_NAME     J1 211
 '@T6G_MB_LIB.T6G(SCH_1):PAGE85_I536@PURE_QUANTA.SCONN288_DDR506112002KQ(CHIPS)':
 'CA1_A': CDS_PINID='CA1_A';
NET_NAME
'M_A_CPU0_SA_CA<2>'
 '@T6G_MB_LIB.T6G(SCH_1):M_A_CPU0_SA_CA'<2>:
 C_SIGNAL='@t6g_mb_lib.t6g(sch_1):m_a_cpu0_sa_ca(2)';
NODE_NAME     U25 AY72
 '@T6G_MB_LIB.T6G(SCH_1):PAGE10_I200@PURE_QUANTA.GENOA_SP5(CHIPS)':
 'MAA_CA2': CDS_PINID='MAA_CA2';
NODE_NAME     J1 68
 '@T6G_MB_LIB.T6G(SCH_1):PAGE85_I536@PURE_QUANTA.SCONN288_DDR506112002KQ(CHIPS)':
 'CA2_A': CDS_PINID='CA2_A';
NET_NAME
'M_A_CPU0_SA_CA<3>'
 '@T6G_MB_LIB.T6G(SCH_1):M_A_CPU0_SA_CA'<3>:
 C_SIGNAL='@t6g_mb_lib.t6g(sch_1):m_a_cpu0_sa_ca(3)';
NODE_NAME     U25 BA73
 '@T6G_MB_LIB.T6G(SCH_1):PAGE10_I200@PURE_QUANTA.GENOA_SP5(CHIPS)':
 'MAA_CA3': CDS_PINID='MAA_CA3';
NODE_NAME     J1 213
 '@T6G_MB_LIB.T6G(SCH_1):PAGE85_I536@PURE_QUANTA.SCONN288_DDR506112002KQ(CHIPS)':
 'CA3_A': CDS_PINID='CA3_A';
NET_NAME
'M_A_CPU0_SA_CA<4>'
 '@T6G_MB_LIB.T6G(SCH_1):M_A_CPU0_SA_CA'<4>:
 C_SIGNAL='@t6g_mb_lib.t6g(sch_1):m_a_cpu0_sa_ca(4)';
NODE_NAME     U25 BA74
 '@T6G_MB_LIB.T6G(SCH_1):PAGE10_I200@PURE_QUANTA.GENOA_SP5(CHIPS)':
 'MAA_CA4': CDS_PINID='MAA_CA4';
NODE_NAME     J1 70
 '@T6G_MB_LIB.T6G(SCH_1):PAGE85_I536@PURE_QUANTA.SCONN288_DDR506112002KQ(CHIPS)':
 'CA4_A': CDS_PINID='CA4_A';
NET_NAME
'M_A_CPU0_SA_CA<5>'
 '@T6G_MB_LIB.T6G(SCH_1):M_A_CPU0_SA_CA'<5>:
 C_SIGNAL='@t6g_mb_lib.t6g(sch_1):m_a_cpu0_sa_ca(5)';
NODE_NAME     U25 BB74
 '@T6G_MB_LIB.T6G(SCH_1):PAGE10_I200@PURE_QUANTA.GENOA_SP5(CHIPS)':
 'MAA_CA5': CDS_PINID='MAA_CA5';
NODE_NAME     J1 215
 '@T6G_MB_LIB.T6G(SCH_1):PAGE85_I536@PURE_QUANTA.SCONN288_DDR506112002KQ(CHIPS)':
 'CA5_A': CDS_PINID='CA5_A';
NET_NAME
'M_A_CPU0_SA_CA<6>'
 '@T6G_MB_LIB.T6G(SCH_1):M_A_CPU0_SA_CA'<6>:
 C_SIGNAL='@t6g_mb_lib.t6g(sch_1):m_a_cpu0_sa_ca(6)';
NODE_NAME     U25 BB72
 '@T6G_MB_LIB.T6G(SCH_1):PAGE10_I200@PURE_QUANTA.GENOA_SP5(CHIPS)':
 'MAA_CA6': CDS_PINID='MAA_CA6';
NODE_NAME     J1 72
 '@T6G_MB_LIB.T6G(SCH_1):PAGE85_I536@PURE_QUANTA.SCONN288_DDR506112002KQ(CHIPS)':
 'CA6_A': CDS_PINID='CA6_A';
NET_NAME
'M_A_CPU0_SA_CB<0>'
 '@T6G_MB_LIB.T6G(SCH_1):M_A_CPU0_SA_CB'<0>:
 C_SIGNAL='@t6g_mb_lib.t6g(sch_1):m_a_cpu0_sa_cb(0)';
NODE_NAME     U25 AJ74
 '@T6G_MB_LIB.T6G(SCH_1):PAGE10_I200@PURE_QUANTA.GENOA_SP5(CHIPS)':
 'MAA_CHECK0': CDS_PINID='MAA_CHECK0';
NODE_NAME     J1 51
 '@T6G_MB_LIB.T6G(SCH_1):PAGE85_I536@PURE_QUANTA.SCONN288_DDR506112002KQ(CHIPS)':
 'CB0_A': CDS_PINID='CB0_A';
NET_NAME
'M_A_CPU0_SA_CB<1>'
 '@T6G_MB_LIB.T6G(SCH_1):M_A_CPU0_SA_CB'<1>:
 C_SIGNAL='@t6g_mb_lib.t6g(sch_1):m_a_cpu0_sa_cb(1)';
NODE_NAME     U25 AK72
 '@T6G_MB_LIB.T6G(SCH_1):PAGE10_I200@PURE_QUANTA.GENOA_SP5(CHIPS)':
 'MAA_CHECK1': CDS_PINID='MAA_CHECK1';
NODE_NAME     J1 53
 '@T6G_MB_LIB.T6G(SCH_1):PAGE85_I536@PURE_QUANTA.SCONN288_DDR506112002KQ(CHIPS)':
 'CB1_A': CDS_PINID='CB1_A';
NET_NAME
'M_A_CPU0_SA_CB<2>'
 '@T6G_MB_LIB.T6G(SCH_1):M_A_CPU0_SA_CB'<2>:
 C_SIGNAL='@t6g_mb_lib.t6g(sch_1):m_a_cpu0_sa_cb(2)';
NODE_NAME     U25 AK74
 '@T6G_MB_LIB.T6G(SCH_1):PAGE10_I200@PURE_QUANTA.GENOA_SP5(CHIPS)':
 'MAA_CHECK2': CDS_PINID='MAA_CHECK2';
NODE_NAME     J1 196
 '@T6G_MB_LIB.T6G(SCH_1):PAGE85_I536@PURE_QUANTA.SCONN288_DDR506112002KQ(CHIPS)':
 'CB2_A': CDS_PINID='CB2_A';
NET_NAME
'M_A_CPU0_SA_CB<3>'
 '@T6G_MB_LIB.T6G(SCH_1):M_A_CPU0_SA_CB'<3>:
 C_SIGNAL='@t6g_mb_lib.t6g(sch_1):m_a_cpu0_sa_cb(3)';
NODE_NAME     U25 AL73
 '@T6G_MB_LIB.T6G(SCH_1):PAGE10_I200@PURE_QUANTA.GENOA_SP5(CHIPS)':
 'MAA_CHECK3': CDS_PINID='MAA_CHECK3';
NODE_NAME     J1 198
 '@T6G_MB_LIB.T6G(SCH_1):PAGE85_I536@PURE_QUANTA.SCONN288_DDR506112002KQ(CHIPS)':
 'CB3_A': CDS_PINID='CB3_A';
NET_NAME
'M_A_CPU0_SA_CB<4>'
 '@T6G_MB_LIB.T6G(SCH_1):M_A_CPU0_SA_CB'<4>:
 C_SIGNAL='@t6g_mb_lib.t6g(sch_1):m_a_cpu0_sa_cb(4)';
NODE_NAME     U25 AN74
 '@T6G_MB_LIB.T6G(SCH_1):PAGE10_I200@PURE_QUANTA.GENOA_SP5(CHIPS)':
 'MAA_CHECK4': CDS_PINID='MAA_CHECK4';
NODE_NAME     J1 58
 '@T6G_MB_LIB.T6G(SCH_1):PAGE85_I536@PURE_QUANTA.SCONN288_DDR506112002KQ(CHIPS)':
 'CB4_A': CDS_PINID='CB4_A';
NET_NAME
'M_A_CPU0_SA_CB<5>'
 '@T6G_MB_LIB.T6G(SCH_1):M_A_CPU0_SA_CB'<5>:
 C_SIGNAL='@t6g_mb_lib.t6g(sch_1):m_a_cpu0_sa_cb(5)';
NODE_NAME     U25 AP72
 '@T6G_MB_LIB.T6G(SCH_1):PAGE10_I200@PURE_QUANTA.GENOA_SP5(CHIPS)':
 'MAA_CHECK5': CDS_PINID='MAA_CHECK5';
NODE_NAME     J1 60
 '@T6G_MB_LIB.T6G(SCH_1):PAGE85_I536@PURE_QUANTA.SCONN288_DDR506112002KQ(CHIPS)':
 'CB5_A': CDS_PINID='CB5_A';
NET_NAME
'M_A_CPU0_SA_CB<6>'
 '@T6G_MB_LIB.T6G(SCH_1):M_A_CPU0_SA_CB'<6>:
 C_SIGNAL='@t6g_mb_lib.t6g(sch_1):m_a_cpu0_sa_cb(6)';
NODE_NAME     U25 AP74
 '@T6G_MB_LIB.T6G(SCH_1):PAGE10_I200@PURE_QUANTA.GENOA_SP5(CHIPS)':
 'MAA_CHECK6': CDS_PINID='MAA_CHECK6';
NODE_NAME     J1 203
 '@T6G_MB_LIB.T6G(SCH_1):PAGE85_I536@PURE_QUANTA.SCONN288_DDR506112002KQ(CHIPS)':
 'CB6_A': CDS_PINID='CB6_A';
NET_NAME
'M_A_CPU0_SA_CB<7>'
 '@T6G_MB_LIB.T6G(SCH_1):M_A_CPU0_SA_CB'<7>:
 C_SIGNAL='@t6g_mb_lib.t6g(sch_1):m_a_cpu0_sa_cb(7)';
NODE_NAME     U25 AR73
 '@T6G_MB_LIB.T6G(SCH_1):PAGE10_I200@PURE_QUANTA.GENOA_SP5(CHIPS)':
 'MAA_CHECK7': CDS_PINID='MAA_CHECK7';
NODE_NAME     J1 205
 '@T6G_MB_LIB.T6G(SCH_1):PAGE85_I536@PURE_QUANTA.SCONN288_DDR506112002KQ(CHIPS)':
 'CB7_A': CDS_PINID='CB7_A';
NET_NAME
'M_A_CPU0_SA_CS_N<0>'
 '@T6G_MB_LIB.T6G(SCH_1):M_A_CPU0_SA_CS_N'<0>:
 C_SIGNAL='@t6g_mb_lib.t6g(sch_1):m_a_cpu0_sa_cs_n(0)';
NODE_NAME     U25 AV74
 '@T6G_MB_LIB.T6G(SCH_1):PAGE10_I200@PURE_QUANTA.GENOA_SP5(CHIPS)':
 'MAA0_CS_L0': CDS_PINID='MAA0_CS_L0';
NODE_NAME     J1 64
 '@T6G_MB_LIB.T6G(SCH_1):PAGE85_I536@PURE_QUANTA.SCONN288_DDR506112002KQ(CHIPS)':
 'CS0_A_N': CDS_PINID='CS0_A_N';
NET_NAME
'M_A_CPU0_SA_CS_N<1>'
 '@T6G_MB_LIB.T6G(SCH_1):M_A_CPU0_SA_CS_N'<1>:
 C_SIGNAL='@t6g_mb_lib.t6g(sch_1):m_a_cpu0_sa_cs_n(1)';
NODE_NAME     U25 AW73
 '@T6G_MB_LIB.T6G(SCH_1):PAGE10_I200@PURE_QUANTA.GENOA_SP5(CHIPS)':
 'MAA0_CS_L1': CDS_PINID='MAA0_CS_L1';
NODE_NAME     J1 209
 '@T6G_MB_LIB.T6G(SCH_1):PAGE85_I536@PURE_QUANTA.SCONN288_DDR506112002KQ(CHIPS)':
 'CS1_A_N': CDS_PINID='CS1_A_N';
NET_NAME
'M_A_CPU0_SA_DQ<0>'
 '@T6G_MB_LIB.T6G(SCH_1):M_A_CPU0_SA_DQ'<0>:
 C_SIGNAL='@t6g_mb_lib.t6g(sch_1):m_a_cpu0_sa_dq(0)';
NODE_NAME     U25 E74
 '@T6G_MB_LIB.T6G(SCH_1):PAGE10_I200@PURE_QUANTA.GENOA_SP5(CHIPS)':
 'MAA_DATA0': CDS_PINID='MAA_DATA0';
NODE_NAME     J1 7
 '@T6G_MB_LIB.T6G(SCH_1):PAGE85_I536@PURE_QUANTA.SCONN288_DDR506112002KQ(CHIPS)':
 'DQ0_A': CDS_PINID='DQ0_A';
NET_NAME
'M_A_CPU0_SA_DQ<10>'
 '@T6G_MB_LIB.T6G(SCH_1):M_A_CPU0_SA_DQ'<10>:
 C_SIGNAL='@t6g_mb_lib.t6g(sch_1):m_a_cpu0_sa_dq(10)';
NODE_NAME     U25 M74
 '@T6G_MB_LIB.T6G(SCH_1):PAGE10_I200@PURE_QUANTA.GENOA_SP5(CHIPS)':
 'MAA_DATA10': CDS_PINID='MAA_DATA10';
NODE_NAME     J1 163
 '@T6G_MB_LIB.T6G(SCH_1):PAGE85_I536@PURE_QUANTA.SCONN288_DDR506112002KQ(CHIPS)':
 'DQ10_A': CDS_PINID='DQ10_A';
NET_NAME
'M_A_CPU0_SA_DQ<11>'
 '@T6G_MB_LIB.T6G(SCH_1):M_A_CPU0_SA_DQ'<11>:
 C_SIGNAL='@t6g_mb_lib.t6g(sch_1):m_a_cpu0_sa_dq(11)';
NODE_NAME     U25 N73
 '@T6G_MB_LIB.T6G(SCH_1):PAGE10_I200@PURE_QUANTA.GENOA_SP5(CHIPS)':
 'MAA_DATA11': CDS_PINID='MAA_DATA11';
NODE_NAME     J1 165
 '@T6G_MB_LIB.T6G(SCH_1):PAGE85_I536@PURE_QUANTA.SCONN288_DDR506112002KQ(CHIPS)':
 'DQ11_A': CDS_PINID='DQ11_A';
NET_NAME
'M_A_CPU0_SA_DQ<12>'
 '@T6G_MB_LIB.T6G(SCH_1):M_A_CPU0_SA_DQ'<12>:
 C_SIGNAL='@t6g_mb_lib.t6g(sch_1):m_a_cpu0_sa_dq(12)';
NODE_NAME     U25 R74
 '@T6G_MB_LIB.T6G(SCH_1):PAGE10_I200@PURE_QUANTA.GENOA_SP5(CHIPS)':
 'MAA_DATA12': CDS_PINID='MAA_DATA12';
NODE_NAME     J1 25
 '@T6G_MB_LIB.T6G(SCH_1):PAGE85_I536@PURE_QUANTA.SCONN288_DDR506112002KQ(CHIPS)':
 'DQ12_A': CDS_PINID='DQ12_A';
NET_NAME
'M_A_CPU0_SA_DQ<13>'
 '@T6G_MB_LIB.T6G(SCH_1):M_A_CPU0_SA_DQ'<13>:
 C_SIGNAL='@t6g_mb_lib.t6g(sch_1):m_a_cpu0_sa_dq(13)';
NODE_NAME     U25 T72
 '@T6G_MB_LIB.T6G(SCH_1):PAGE10_I200@PURE_QUANTA.GENOA_SP5(CHIPS)':
 'MAA_DATA13': CDS_PINID='MAA_DATA13';
NODE_NAME     J1 27
 '@T6G_MB_LIB.T6G(SCH_1):PAGE85_I536@PURE_QUANTA.SCONN288_DDR506112002KQ(CHIPS)':
 'DQ13_A': CDS_PINID='DQ13_A';
NET_NAME
'M_A_CPU0_SA_DQ<14>'
 '@T6G_MB_LIB.T6G(SCH_1):M_A_CPU0_SA_DQ'<14>:
 C_SIGNAL='@t6g_mb_lib.t6g(sch_1):m_a_cpu0_sa_dq(14)';
NODE_NAME     U25 T74
 '@T6G_MB_LIB.T6G(SCH_1):PAGE10_I200@PURE_QUANTA.GENOA_SP5(CHIPS)':
 'MAA_DATA14': CDS_PINID='MAA_DATA14';
NODE_NAME     J1 170
 '@T6G_MB_LIB.T6G(SCH_1):PAGE85_I536@PURE_QUANTA.SCONN288_DDR506112002KQ(CHIPS)':
 'DQ14_A': CDS_PINID='DQ14_A';
NET_NAME
'M_A_CPU0_SA_DQ<15>'
 '@T6G_MB_LIB.T6G(SCH_1):M_A_CPU0_SA_DQ'<15>:
 C_SIGNAL='@t6g_mb_lib.t6g(sch_1):m_a_cpu0_sa_dq(15)';
NODE_NAME     U25 U73
 '@T6G_MB_LIB.T6G(SCH_1):PAGE10_I200@PURE_QUANTA.GENOA_SP5(CHIPS)':
 'MAA_DATA15': CDS_PINID='MAA_DATA15';
NODE_NAME     J1 172
 '@T6G_MB_LIB.T6G(SCH_1):PAGE85_I536@PURE_QUANTA.SCONN288_DDR506112002KQ(CHIPS)':
 'DQ15_A': CDS_PINID='DQ15_A';
NET_NAME
'M_A_CPU0_SA_DQ<16>'
 '@T6G_MB_LIB.T6G(SCH_1):M_A_CPU0_SA_DQ'<16>:
 C_SIGNAL='@t6g_mb_lib.t6g(sch_1):m_a_cpu0_sa_dq(16)';
NODE_NAME     U25 U74
 '@T6G_MB_LIB.T6G(SCH_1):PAGE10_I200@PURE_QUANTA.GENOA_SP5(CHIPS)':
 'MAA_DATA16': CDS_PINID='MAA_DATA16';
NODE_NAME     J1 29
 '@T6G_MB_LIB.T6G(SCH_1):PAGE85_I536@PURE_QUANTA.SCONN288_DDR506112002KQ(CHIPS)':
 'DQ16_A': CDS_PINID='DQ16_A';
NET_NAME
'M_A_CPU0_SA_DQ<17>'
 '@T6G_MB_LIB.T6G(SCH_1):M_A_CPU0_SA_DQ'<17>:
 C_SIGNAL='@t6g_mb_lib.t6g(sch_1):m_a_cpu0_sa_dq(17)';
NODE_NAME     U25 V72
 '@T6G_MB_LIB.T6G(SCH_1):PAGE10_I200@PURE_QUANTA.GENOA_SP5(CHIPS)':
 'MAA_DATA17': CDS_PINID='MAA_DATA17';
NODE_NAME     J1 31
 '@T6G_MB_LIB.T6G(SCH_1):PAGE85_I536@PURE_QUANTA.SCONN288_DDR506112002KQ(CHIPS)':
 'DQ17_A': CDS_PINID='DQ17_A';
NET_NAME
'M_A_CPU0_SA_DQ<18>'
 '@T6G_MB_LIB.T6G(SCH_1):M_A_CPU0_SA_DQ'<18>:
 C_SIGNAL='@t6g_mb_lib.t6g(sch_1):m_a_cpu0_sa_dq(18)';
NODE_NAME     U25 V74
 '@T6G_MB_LIB.T6G(SCH_1):PAGE10_I200@PURE_QUANTA.GENOA_SP5(CHIPS)':
 'MAA_DATA18': CDS_PINID='MAA_DATA18';
NODE_NAME     J1 174
 '@T6G_MB_LIB.T6G(SCH_1):PAGE85_I536@PURE_QUANTA.SCONN288_DDR506112002KQ(CHIPS)':
 'DQ18_A': CDS_PINID='DQ18_A';
NET_NAME
'M_A_CPU0_SA_DQ<19>'
 '@T6G_MB_LIB.T6G(SCH_1):M_A_CPU0_SA_DQ'<19>:
 C_SIGNAL='@t6g_mb_lib.t6g(sch_1):m_a_cpu0_sa_dq(19)';
NODE_NAME     U25 W73
 '@T6G_MB_LIB.T6G(SCH_1):PAGE10_I200@PURE_QUANTA.GENOA_SP5(CHIPS)':
 'MAA_DATA19': CDS_PINID='MAA_DATA19';
NODE_NAME     J1 176
 '@T6G_MB_LIB.T6G(SCH_1):PAGE85_I536@PURE_QUANTA.SCONN288_DDR506112002KQ(CHIPS)':
 'DQ19_A': CDS_PINID='DQ19_A';
NET_NAME
'M_A_CPU0_SA_DQ<1>'
 '@T6G_MB_LIB.T6G(SCH_1):M_A_CPU0_SA_DQ'<1>:
 C_SIGNAL='@t6g_mb_lib.t6g(sch_1):m_a_cpu0_sa_dq(1)';
NODE_NAME     U25 F72
 '@T6G_MB_LIB.T6G(SCH_1):PAGE10_I200@PURE_QUANTA.GENOA_SP5(CHIPS)':
 'MAA_DATA1': CDS_PINID='MAA_DATA1';
NODE_NAME     J1 9
 '@T6G_MB_LIB.T6G(SCH_1):PAGE85_I536@PURE_QUANTA.SCONN288_DDR506112002KQ(CHIPS)':
 'DQ1_A': CDS_PINID='DQ1_A';
NET_NAME
'M_A_CPU0_SA_DQ<20>'
 '@T6G_MB_LIB.T6G(SCH_1):M_A_CPU0_SA_DQ'<20>:
 C_SIGNAL='@t6g_mb_lib.t6g(sch_1):m_a_cpu0_sa_dq(20)';
NODE_NAME     U25 AA74
 '@T6G_MB_LIB.T6G(SCH_1):PAGE10_I200@PURE_QUANTA.GENOA_SP5(CHIPS)':
 'MAA_DATA20': CDS_PINID='MAA_DATA20';
NODE_NAME     J1 36
 '@T6G_MB_LIB.T6G(SCH_1):PAGE85_I536@PURE_QUANTA.SCONN288_DDR506112002KQ(CHIPS)':
 'DQ20_A': CDS_PINID='DQ20_A';
NET_NAME
'M_A_CPU0_SA_DQ<21>'
 '@T6G_MB_LIB.T6G(SCH_1):M_A_CPU0_SA_DQ'<21>:
 C_SIGNAL='@t6g_mb_lib.t6g(sch_1):m_a_cpu0_sa_dq(21)';
NODE_NAME     U25 AB72
 '@T6G_MB_LIB.T6G(SCH_1):PAGE10_I200@PURE_QUANTA.GENOA_SP5(CHIPS)':
 'MAA_DATA21': CDS_PINID='MAA_DATA21';
NODE_NAME     J1 38
 '@T6G_MB_LIB.T6G(SCH_1):PAGE85_I536@PURE_QUANTA.SCONN288_DDR506112002KQ(CHIPS)':
 'DQ21_A': CDS_PINID='DQ21_A';
NET_NAME
'M_A_CPU0_SA_DQ<22>'
 '@T6G_MB_LIB.T6G(SCH_1):M_A_CPU0_SA_DQ'<22>:
 C_SIGNAL='@t6g_mb_lib.t6g(sch_1):m_a_cpu0_sa_dq(22)';
NODE_NAME     U25 AB74
 '@T6G_MB_LIB.T6G(SCH_1):PAGE10_I200@PURE_QUANTA.GENOA_SP5(CHIPS)':
 'MAA_DATA22': CDS_PINID='MAA_DATA22';
NODE_NAME     J1 181
 '@T6G_MB_LIB.T6G(SCH_1):PAGE85_I536@PURE_QUANTA.SCONN288_DDR506112002KQ(CHIPS)':
 'DQ22_A': CDS_PINID='DQ22_A';
NET_NAME
'M_A_CPU0_SA_DQ<23>'
 '@T6G_MB_LIB.T6G(SCH_1):M_A_CPU0_SA_DQ'<23>:
 C_SIGNAL='@t6g_mb_lib.t6g(sch_1):m_a_cpu0_sa_dq(23)';
NODE_NAME     U25 AC73
 '@T6G_MB_LIB.T6G(SCH_1):PAGE10_I200@PURE_QUANTA.GENOA_SP5(CHIPS)':
 'MAA_DATA23': CDS_PINID='MAA_DATA23';
NODE_NAME     J1 183
 '@T6G_MB_LIB.T6G(SCH_1):PAGE85_I536@PURE_QUANTA.SCONN288_DDR506112002KQ(CHIPS)':
 'DQ23_A': CDS_PINID='DQ23_A';
NET_NAME
'M_A_CPU0_SA_DQ<24>'
 '@T6G_MB_LIB.T6G(SCH_1):M_A_CPU0_SA_DQ'<24>:
 C_SIGNAL='@t6g_mb_lib.t6g(sch_1):m_a_cpu0_sa_dq(24)';
NODE_NAME     U25 AC74
 '@T6G_MB_LIB.T6G(SCH_1):PAGE10_I200@PURE_QUANTA.GENOA_SP5(CHIPS)':
 'MAA_DATA24': CDS_PINID='MAA_DATA24';
NODE_NAME     J1 40
 '@T6G_MB_LIB.T6G(SCH_1):PAGE85_I536@PURE_QUANTA.SCONN288_DDR506112002KQ(CHIPS)':
 'DQ24_A': CDS_PINID='DQ24_A';
NET_NAME
'M_A_CPU0_SA_DQ<25>'
 '@T6G_MB_LIB.T6G(SCH_1):M_A_CPU0_SA_DQ'<25>:
 C_SIGNAL='@t6g_mb_lib.t6g(sch_1):m_a_cpu0_sa_dq(25)';
NODE_NAME     U25 AD72
 '@T6G_MB_LIB.T6G(SCH_1):PAGE10_I200@PURE_QUANTA.GENOA_SP5(CHIPS)':
 'MAA_DATA25': CDS_PINID='MAA_DATA25';
NODE_NAME     J1 42
 '@T6G_MB_LIB.T6G(SCH_1):PAGE85_I536@PURE_QUANTA.SCONN288_DDR506112002KQ(CHIPS)':
 'DQ25_A': CDS_PINID='DQ25_A';
NET_NAME
'M_A_CPU0_SA_DQ<26>'
 '@T6G_MB_LIB.T6G(SCH_1):M_A_CPU0_SA_DQ'<26>:
 C_SIGNAL='@t6g_mb_lib.t6g(sch_1):m_a_cpu0_sa_dq(26)';
NODE_NAME     U25 AD74
 '@T6G_MB_LIB.T6G(SCH_1):PAGE10_I200@PURE_QUANTA.GENOA_SP5(CHIPS)':
 'MAA_DATA26': CDS_PINID='MAA_DATA26';
NODE_NAME     J1 185
 '@T6G_MB_LIB.T6G(SCH_1):PAGE85_I536@PURE_QUANTA.SCONN288_DDR506112002KQ(CHIPS)':
 'DQ26_A': CDS_PINID='DQ26_A';
NET_NAME
'M_A_CPU0_SA_DQ<27>'
 '@T6G_MB_LIB.T6G(SCH_1):M_A_CPU0_SA_DQ'<27>:
 C_SIGNAL='@t6g_mb_lib.t6g(sch_1):m_a_cpu0_sa_dq(27)';
NODE_NAME     U25 AE73
 '@T6G_MB_LIB.T6G(SCH_1):PAGE10_I200@PURE_QUANTA.GENOA_SP5(CHIPS)':
 'MAA_DATA27': CDS_PINID='MAA_DATA27';
NODE_NAME     J1 187
 '@T6G_MB_LIB.T6G(SCH_1):PAGE85_I536@PURE_QUANTA.SCONN288_DDR506112002KQ(CHIPS)':
 'DQ27_A': CDS_PINID='DQ27_A';
NET_NAME
'M_A_CPU0_SA_DQ<28>'
 '@T6G_MB_LIB.T6G(SCH_1):M_A_CPU0_SA_DQ'<28>:
 C_SIGNAL='@t6g_mb_lib.t6g(sch_1):m_a_cpu0_sa_dq(28)';
NODE_NAME     U25 AG74
 '@T6G_MB_LIB.T6G(SCH_1):PAGE10_I200@PURE_QUANTA.GENOA_SP5(CHIPS)':
 'MAA_DATA28': CDS_PINID='MAA_DATA28';
NODE_NAME     J1 47
 '@T6G_MB_LIB.T6G(SCH_1):PAGE85_I536@PURE_QUANTA.SCONN288_DDR506112002KQ(CHIPS)':
 'DQ28_A': CDS_PINID='DQ28_A';
NET_NAME
'M_A_CPU0_SA_DQ<29>'
 '@T6G_MB_LIB.T6G(SCH_1):M_A_CPU0_SA_DQ'<29>:
 C_SIGNAL='@t6g_mb_lib.t6g(sch_1):m_a_cpu0_sa_dq(29)';
NODE_NAME     U25 AH72
 '@T6G_MB_LIB.T6G(SCH_1):PAGE10_I200@PURE_QUANTA.GENOA_SP5(CHIPS)':
 'MAA_DATA29': CDS_PINID='MAA_DATA29';
NODE_NAME     J1 49
 '@T6G_MB_LIB.T6G(SCH_1):PAGE85_I536@PURE_QUANTA.SCONN288_DDR506112002KQ(CHIPS)':
 'DQ29_A': CDS_PINID='DQ29_A';
NET_NAME
'M_A_CPU0_SA_DQ<2>'
 '@T6G_MB_LIB.T6G(SCH_1):M_A_CPU0_SA_DQ'<2>:
 C_SIGNAL='@t6g_mb_lib.t6g(sch_1):m_a_cpu0_sa_dq(2)';
NODE_NAME     U25 F74
 '@T6G_MB_LIB.T6G(SCH_1):PAGE10_I200@PURE_QUANTA.GENOA_SP5(CHIPS)':
 'MAA_DATA2': CDS_PINID='MAA_DATA2';
NODE_NAME     J1 152
 '@T6G_MB_LIB.T6G(SCH_1):PAGE85_I536@PURE_QUANTA.SCONN288_DDR506112002KQ(CHIPS)':
 'DQ2_A': CDS_PINID='DQ2_A';
NET_NAME
'M_A_CPU0_SA_DQ<30>'
 '@T6G_MB_LIB.T6G(SCH_1):M_A_CPU0_SA_DQ'<30>:
 C_SIGNAL='@t6g_mb_lib.t6g(sch_1):m_a_cpu0_sa_dq(30)';
NODE_NAME     U25 AH74
 '@T6G_MB_LIB.T6G(SCH_1):PAGE10_I200@PURE_QUANTA.GENOA_SP5(CHIPS)':
 'MAA_DATA30': CDS_PINID='MAA_DATA30';
NODE_NAME     J1 192
 '@T6G_MB_LIB.T6G(SCH_1):PAGE85_I536@PURE_QUANTA.SCONN288_DDR506112002KQ(CHIPS)':
 'DQ30_A': CDS_PINID='DQ30_A';
NET_NAME
'M_A_CPU0_SA_DQ<31>'
 '@T6G_MB_LIB.T6G(SCH_1):M_A_CPU0_SA_DQ'<31>:
 C_SIGNAL='@t6g_mb_lib.t6g(sch_1):m_a_cpu0_sa_dq(31)';
NODE_NAME     U25 AJ73
 '@T6G_MB_LIB.T6G(SCH_1):PAGE10_I200@PURE_QUANTA.GENOA_SP5(CHIPS)':
 'MAA_DATA31': CDS_PINID='MAA_DATA31';
NODE_NAME     J1 194
 '@T6G_MB_LIB.T6G(SCH_1):PAGE85_I536@PURE_QUANTA.SCONN288_DDR506112002KQ(CHIPS)':
 'DQ31_A': CDS_PINID='DQ31_A';
NET_NAME
'M_A_CPU0_SA_DQ<3>'
 '@T6G_MB_LIB.T6G(SCH_1):M_A_CPU0_SA_DQ'<3>:
 C_SIGNAL='@t6g_mb_lib.t6g(sch_1):m_a_cpu0_sa_dq(3)';
NODE_NAME     U25 G73
 '@T6G_MB_LIB.T6G(SCH_1):PAGE10_I200@PURE_QUANTA.GENOA_SP5(CHIPS)':
 'MAA_DATA3': CDS_PINID='MAA_DATA3';
NODE_NAME     J1 154
 '@T6G_MB_LIB.T6G(SCH_1):PAGE85_I536@PURE_QUANTA.SCONN288_DDR506112002KQ(CHIPS)':
 'DQ3_A': CDS_PINID='DQ3_A';
NET_NAME
'M_A_CPU0_SA_DQ<4>'
 '@T6G_MB_LIB.T6G(SCH_1):M_A_CPU0_SA_DQ'<4>:
 C_SIGNAL='@t6g_mb_lib.t6g(sch_1):m_a_cpu0_sa_dq(4)';
NODE_NAME     U25 J74
 '@T6G_MB_LIB.T6G(SCH_1):PAGE10_I200@PURE_QUANTA.GENOA_SP5(CHIPS)':
 'MAA_DATA4': CDS_PINID='MAA_DATA4';
NODE_NAME     J1 14
 '@T6G_MB_LIB.T6G(SCH_1):PAGE85_I536@PURE_QUANTA.SCONN288_DDR506112002KQ(CHIPS)':
 'DQ4_A': CDS_PINID='DQ4_A';
NET_NAME
'M_A_CPU0_SA_DQ<5>'
 '@T6G_MB_LIB.T6G(SCH_1):M_A_CPU0_SA_DQ'<5>:
 C_SIGNAL='@t6g_mb_lib.t6g(sch_1):m_a_cpu0_sa_dq(5)';
NODE_NAME     U25 K72
 '@T6G_MB_LIB.T6G(SCH_1):PAGE10_I200@PURE_QUANTA.GENOA_SP5(CHIPS)':
 'MAA_DATA5': CDS_PINID='MAA_DATA5';
NODE_NAME     J1 16
 '@T6G_MB_LIB.T6G(SCH_1):PAGE85_I536@PURE_QUANTA.SCONN288_DDR506112002KQ(CHIPS)':
 'DQ5_A': CDS_PINID='DQ5_A';
NET_NAME
'M_A_CPU0_SA_DQ<6>'
 '@T6G_MB_LIB.T6G(SCH_1):M_A_CPU0_SA_DQ'<6>:
 C_SIGNAL='@t6g_mb_lib.t6g(sch_1):m_a_cpu0_sa_dq(6)';
NODE_NAME     U25 K74
 '@T6G_MB_LIB.T6G(SCH_1):PAGE10_I200@PURE_QUANTA.GENOA_SP5(CHIPS)':
 'MAA_DATA6': CDS_PINID='MAA_DATA6';
NODE_NAME     J1 159
 '@T6G_MB_LIB.T6G(SCH_1):PAGE85_I536@PURE_QUANTA.SCONN288_DDR506112002KQ(CHIPS)':
 'DQ6_A': CDS_PINID='DQ6_A';
NET_NAME
'M_A_CPU0_SA_DQ<7>'
 '@T6G_MB_LIB.T6G(SCH_1):M_A_CPU0_SA_DQ'<7>:
 C_SIGNAL='@t6g_mb_lib.t6g(sch_1):m_a_cpu0_sa_dq(7)';
NODE_NAME     U25 L73
 '@T6G_MB_LIB.T6G(SCH_1):PAGE10_I200@PURE_QUANTA.GENOA_SP5(CHIPS)':
 'MAA_DATA7': CDS_PINID='MAA_DATA7';
NODE_NAME     J1 161
 '@T6G_MB_LIB.T6G(SCH_1):PAGE85_I536@PURE_QUANTA.SCONN288_DDR506112002KQ(CHIPS)':
 'DQ7_A': CDS_PINID='DQ7_A';
NET_NAME
'M_A_CPU0_SA_DQ<8>'
 '@T6G_MB_LIB.T6G(SCH_1):M_A_CPU0_SA_DQ'<8>:
 C_SIGNAL='@t6g_mb_lib.t6g(sch_1):m_a_cpu0_sa_dq(8)';
NODE_NAME     U25 L74
 '@T6G_MB_LIB.T6G(SCH_1):PAGE10_I200@PURE_QUANTA.GENOA_SP5(CHIPS)':
 'MAA_DATA8': CDS_PINID='MAA_DATA8';
NODE_NAME     J1 18
 '@T6G_MB_LIB.T6G(SCH_1):PAGE85_I536@PURE_QUANTA.SCONN288_DDR506112002KQ(CHIPS)':
 'DQ8_A': CDS_PINID='DQ8_A';
NET_NAME
'M_A_CPU0_SA_DQ<9>'
 '@T6G_MB_LIB.T6G(SCH_1):M_A_CPU0_SA_DQ'<9>:
 C_SIGNAL='@t6g_mb_lib.t6g(sch_1):m_a_cpu0_sa_dq(9)';
NODE_NAME     U25 M72
 '@T6G_MB_LIB.T6G(SCH_1):PAGE10_I200@PURE_QUANTA.GENOA_SP5(CHIPS)':
 'MAA_DATA9': CDS_PINID='MAA_DATA9';
NODE_NAME     J1 20
 '@T6G_MB_LIB.T6G(SCH_1):PAGE85_I536@PURE_QUANTA.SCONN288_DDR506112002KQ(CHIPS)':
 'DQ9_A': CDS_PINID='DQ9_A';
NET_NAME
'M_A_CPU0_SA_DQS_DN<0>'
 '@T6G_MB_LIB.T6G(SCH_1):M_A_CPU0_SA_DQS_DN'<0>:
 C_SIGNAL='@t6g_mb_lib.t6g(sch_1):m_a_cpu0_sa_dqs_dn(0)';
NODE_NAME     U25 H74
 '@T6G_MB_LIB.T6G(SCH_1):PAGE10_I200@PURE_QUANTA.GENOA_SP5(CHIPS)':
 'MAA_DQS_L0': CDS_PINID='MAA_DQS_L0';
NODE_NAME     J1 12
 '@T6G_MB_LIB.T6G(SCH_1):PAGE85_I537@PURE_QUANTA.SCONN288_DDR506112002KQ(CHIPS)':
 'DQS0_A_C': CDS_PINID='DQS0_A_C';
NET_NAME
'M_A_CPU0_SA_DQS_DN<1>'
 '@T6G_MB_LIB.T6G(SCH_1):M_A_CPU0_SA_DQS_DN'<1>:
 C_SIGNAL='@t6g_mb_lib.t6g(sch_1):m_a_cpu0_sa_dqs_dn(1)';
NODE_NAME     U25 P74
 '@T6G_MB_LIB.T6G(SCH_1):PAGE10_I200@PURE_QUANTA.GENOA_SP5(CHIPS)':
 'MAA_DQS_L1': CDS_PINID='MAA_DQS_L1';
NODE_NAME     J1 23
 '@T6G_MB_LIB.T6G(SCH_1):PAGE85_I537@PURE_QUANTA.SCONN288_DDR506112002KQ(CHIPS)':
 'DQS1_A_C': CDS_PINID='DQS1_A_C';
NET_NAME
'M_A_CPU0_SA_DQS_DN<2>'
 '@T6G_MB_LIB.T6G(SCH_1):M_A_CPU0_SA_DQS_DN'<2>:
 C_SIGNAL='@t6g_mb_lib.t6g(sch_1):m_a_cpu0_sa_dqs_dn(2)';
NODE_NAME     U25 Y74
 '@T6G_MB_LIB.T6G(SCH_1):PAGE10_I200@PURE_QUANTA.GENOA_SP5(CHIPS)':
 'MAA_DQS_L2': CDS_PINID='MAA_DQS_L2';
NODE_NAME     J1 34
 '@T6G_MB_LIB.T6G(SCH_1):PAGE85_I537@PURE_QUANTA.SCONN288_DDR506112002KQ(CHIPS)':
 'DQS2_A_C': CDS_PINID='DQS2_A_C';
NET_NAME
'M_A_CPU0_SA_DQS_DN<3>'
 '@T6G_MB_LIB.T6G(SCH_1):M_A_CPU0_SA_DQS_DN'<3>:
 C_SIGNAL='@t6g_mb_lib.t6g(sch_1):m_a_cpu0_sa_dqs_dn(3)';
NODE_NAME     U25 AF74
 '@T6G_MB_LIB.T6G(SCH_1):PAGE10_I200@PURE_QUANTA.GENOA_SP5(CHIPS)':
 'MAA_DQS_L3': CDS_PINID='MAA_DQS_L3';
NODE_NAME     J1 45
 '@T6G_MB_LIB.T6G(SCH_1):PAGE85_I537@PURE_QUANTA.SCONN288_DDR506112002KQ(CHIPS)':
 'DQS3_A_C': CDS_PINID='DQS3_A_C';
NET_NAME
'M_A_CPU0_SA_DQS_DN<4>'
 '@T6G_MB_LIB.T6G(SCH_1):M_A_CPU0_SA_DQS_DN'<4>:
 C_SIGNAL='@t6g_mb_lib.t6g(sch_1):m_a_cpu0_sa_dqs_dn(4)';
NODE_NAME     U25 AM74
 '@T6G_MB_LIB.T6G(SCH_1):PAGE10_I200@PURE_QUANTA.GENOA_SP5(CHIPS)':
 'MAA_DQS_L4': CDS_PINID='MAA_DQS_L4';
NODE_NAME     J1 56
 '@T6G_MB_LIB.T6G(SCH_1):PAGE85_I537@PURE_QUANTA.SCONN288_DDR506112002KQ(CHIPS)':
 'DQS4_A_C': CDS_PINID='DQS4_A_C';
NET_NAME
'M_A_CPU0_SA_DQS_DN<5>'
 '@T6G_MB_LIB.T6G(SCH_1):M_A_CPU0_SA_DQS_DN'<5>:
 C_SIGNAL='@t6g_mb_lib.t6g(sch_1):m_a_cpu0_sa_dqs_dn(5)';
NODE_NAME     U25 H72
 '@T6G_MB_LIB.T6G(SCH_1):PAGE10_I200@PURE_QUANTA.GENOA_SP5(CHIPS)':
 'MAA_DQS_L5': CDS_PINID='MAA_DQS_L5';
NODE_NAME     J1 156
 '@T6G_MB_LIB.T6G(SCH_1):PAGE85_I537@PURE_QUANTA.SCONN288_DDR506112002KQ(CHIPS)':
 'DQS5_A_C||TDQS5_A_C||DQS5_A_T||TDQS5_A_T': CDS_PINID='\dqs5_a_c||tdqs5_a_c||dqs5_a_t||tdqs5_a_t\';
NET_NAME
'M_A_CPU0_SA_DQS_DN<6>'
 '@T6G_MB_LIB.T6G(SCH_1):M_A_CPU0_SA_DQS_DN'<6>:
 C_SIGNAL='@t6g_mb_lib.t6g(sch_1):m_a_cpu0_sa_dqs_dn(6)';
NODE_NAME     U25 P72
 '@T6G_MB_LIB.T6G(SCH_1):PAGE10_I200@PURE_QUANTA.GENOA_SP5(CHIPS)':
 'MAA_DQS_L6': CDS_PINID='MAA_DQS_L6';
NODE_NAME     J1 167
 '@T6G_MB_LIB.T6G(SCH_1):PAGE85_I537@PURE_QUANTA.SCONN288_DDR506112002KQ(CHIPS)':
 'DQS6_A_C||TDQS6_A_C||DQS6_A_T||TDQS6_A_T': CDS_PINID='\dqs6_a_c||tdqs6_a_c||dqs6_a_t||tdqs6_a_t\';
NET_NAME
'M_A_CPU0_SA_DQS_DN<7>'
 '@T6G_MB_LIB.T6G(SCH_1):M_A_CPU0_SA_DQS_DN'<7>:
 C_SIGNAL='@t6g_mb_lib.t6g(sch_1):m_a_cpu0_sa_dqs_dn(7)';
NODE_NAME     U25 Y72
 '@T6G_MB_LIB.T6G(SCH_1):PAGE10_I200@PURE_QUANTA.GENOA_SP5(CHIPS)':
 'MAA_DQS_L7': CDS_PINID='MAA_DQS_L7';
NODE_NAME     J1 178
 '@T6G_MB_LIB.T6G(SCH_1):PAGE85_I537@PURE_QUANTA.SCONN288_DDR506112002KQ(CHIPS)':
 'DQS7_A_C||TDQS7_A_C': CDS_PINID='\dqs7_a_c||tdqs7_a_c\';
NET_NAME
'M_A_CPU0_SA_DQS_DN<8>'
 '@T6G_MB_LIB.T6G(SCH_1):M_A_CPU0_SA_DQS_DN'<8>:
 C_SIGNAL='@t6g_mb_lib.t6g(sch_1):m_a_cpu0_sa_dqs_dn(8)';
NODE_NAME     U25 AF72
 '@T6G_MB_LIB.T6G(SCH_1):PAGE10_I200@PURE_QUANTA.GENOA_SP5(CHIPS)':
 'MAA_DQS_L8': CDS_PINID='MAA_DQS_L8';
NODE_NAME     J1 189
 '@T6G_MB_LIB.T6G(SCH_1):PAGE85_I537@PURE_QUANTA.SCONN288_DDR506112002KQ(CHIPS)':
 'DQS8_A_C||TDQS8_A_C': CDS_PINID='\dqs8_a_c||tdqs8_a_c\';
NET_NAME
'M_A_CPU0_SA_DQS_DN<9>'
 '@T6G_MB_LIB.T6G(SCH_1):M_A_CPU0_SA_DQS_DN'<9>:
 C_SIGNAL='@t6g_mb_lib.t6g(sch_1):m_a_cpu0_sa_dqs_dn(9)';
NODE_NAME     U25 AM72
 '@T6G_MB_LIB.T6G(SCH_1):PAGE10_I200@PURE_QUANTA.GENOA_SP5(CHIPS)':
 'MAA_DQS_L9': CDS_PINID='MAA_DQS_L9';
NODE_NAME     J1 200
 '@T6G_MB_LIB.T6G(SCH_1):PAGE85_I537@PURE_QUANTA.SCONN288_DDR506112002KQ(CHIPS)':
 'DQS9_A_C||TDQS9_A_C': CDS_PINID='\dqs9_a_c||tdqs9_a_c\';
NET_NAME
'M_A_CPU0_SA_DQS_DP<0>'
 '@T6G_MB_LIB.T6G(SCH_1):M_A_CPU0_SA_DQS_DP'<0>:
 C_SIGNAL='@t6g_mb_lib.t6g(sch_1):m_a_cpu0_sa_dqs_dp(0)';
NODE_NAME     U25 G74
 '@T6G_MB_LIB.T6G(SCH_1):PAGE10_I200@PURE_QUANTA.GENOA_SP5(CHIPS)':
 'MAA_DQS_H0': CDS_PINID='MAA_DQS_H0';
NODE_NAME     J1 11
 '@T6G_MB_LIB.T6G(SCH_1):PAGE85_I537@PURE_QUANTA.SCONN288_DDR506112002KQ(CHIPS)':
 'DQS0_A_T': CDS_PINID='DQS0_A_T';
NET_NAME
'M_A_CPU0_SA_DQS_DP<1>'
 '@T6G_MB_LIB.T6G(SCH_1):M_A_CPU0_SA_DQS_DP'<1>:
 C_SIGNAL='@t6g_mb_lib.t6g(sch_1):m_a_cpu0_sa_dqs_dp(1)';
NODE_NAME     U25 N74
 '@T6G_MB_LIB.T6G(SCH_1):PAGE10_I200@PURE_QUANTA.GENOA_SP5(CHIPS)':
 'MAA_DQS_H1': CDS_PINID='MAA_DQS_H1';
NODE_NAME     J1 22
 '@T6G_MB_LIB.T6G(SCH_1):PAGE85_I537@PURE_QUANTA.SCONN288_DDR506112002KQ(CHIPS)':
 'DQS1_A_T': CDS_PINID='DQS1_A_T';
NET_NAME
'M_A_CPU0_SA_DQS_DP<2>'
 '@T6G_MB_LIB.T6G(SCH_1):M_A_CPU0_SA_DQS_DP'<2>:
 C_SIGNAL='@t6g_mb_lib.t6g(sch_1):m_a_cpu0_sa_dqs_dp(2)';
NODE_NAME     U25 W74
 '@T6G_MB_LIB.T6G(SCH_1):PAGE10_I200@PURE_QUANTA.GENOA_SP5(CHIPS)':
 'MAA_DQS_H2': CDS_PINID='MAA_DQS_H2';
NODE_NAME     J1 33
 '@T6G_MB_LIB.T6G(SCH_1):PAGE85_I537@PURE_QUANTA.SCONN288_DDR506112002KQ(CHIPS)':
 'DQS2_A_T': CDS_PINID='DQS2_A_T';
NET_NAME
'M_A_CPU0_SA_DQS_DP<3>'
 '@T6G_MB_LIB.T6G(SCH_1):M_A_CPU0_SA_DQS_DP'<3>:
 C_SIGNAL='@t6g_mb_lib.t6g(sch_1):m_a_cpu0_sa_dqs_dp(3)';
NODE_NAME     U25 AE74
 '@T6G_MB_LIB.T6G(SCH_1):PAGE10_I200@PURE_QUANTA.GENOA_SP5(CHIPS)':
 'MAA_DQS_H3': CDS_PINID='MAA_DQS_H3';
NODE_NAME     J1 44
 '@T6G_MB_LIB.T6G(SCH_1):PAGE85_I537@PURE_QUANTA.SCONN288_DDR506112002KQ(CHIPS)':
 'DQS3_A_T': CDS_PINID='DQS3_A_T';
NET_NAME
'M_A_CPU0_SA_DQS_DP<4>'
 '@T6G_MB_LIB.T6G(SCH_1):M_A_CPU0_SA_DQS_DP'<4>:
 C_SIGNAL='@t6g_mb_lib.t6g(sch_1):m_a_cpu0_sa_dqs_dp(4)';
NODE_NAME     U25 AL74
 '@T6G_MB_LIB.T6G(SCH_1):PAGE10_I200@PURE_QUANTA.GENOA_SP5(CHIPS)':
 'MAA_DQS_H4': CDS_PINID='MAA_DQS_H4';
NODE_NAME     J1 55
 '@T6G_MB_LIB.T6G(SCH_1):PAGE85_I537@PURE_QUANTA.SCONN288_DDR506112002KQ(CHIPS)':
 'DQS4_A_T': CDS_PINID='DQS4_A_T';
NET_NAME
'M_A_CPU0_SA_DQS_DP<5>'
 '@T6G_MB_LIB.T6G(SCH_1):M_A_CPU0_SA_DQS_DP'<5>:
 C_SIGNAL='@t6g_mb_lib.t6g(sch_1):m_a_cpu0_sa_dqs_dp(5)';
NODE_NAME     U25 J73
 '@T6G_MB_LIB.T6G(SCH_1):PAGE10_I200@PURE_QUANTA.GENOA_SP5(CHIPS)':
 'MAA_DQS_H5': CDS_PINID='MAA_DQS_H5';
NODE_NAME     J1 157
 '@T6G_MB_LIB.T6G(SCH_1):PAGE85_I537@PURE_QUANTA.SCONN288_DDR506112002KQ(CHIPS)':
 'DQS5_A_T||TDQS5_A_T': CDS_PINID='\dqs5_a_t||tdqs5_a_t\';
NET_NAME
'M_A_CPU0_SA_DQS_DP<6>'
 '@T6G_MB_LIB.T6G(SCH_1):M_A_CPU0_SA_DQS_DP'<6>:
 C_SIGNAL='@t6g_mb_lib.t6g(sch_1):m_a_cpu0_sa_dqs_dp(6)';
NODE_NAME     U25 R73
 '@T6G_MB_LIB.T6G(SCH_1):PAGE10_I200@PURE_QUANTA.GENOA_SP5(CHIPS)':
 'MAA_DQS_H6': CDS_PINID='MAA_DQS_H6';
NODE_NAME     J1 168
 '@T6G_MB_LIB.T6G(SCH_1):PAGE85_I537@PURE_QUANTA.SCONN288_DDR506112002KQ(CHIPS)':
 'DQS6_A_T||TDQS6_A_T': CDS_PINID='\dqs6_a_t||tdqs6_a_t\';
NET_NAME
'M_A_CPU0_SA_DQS_DP<7>'
 '@T6G_MB_LIB.T6G(SCH_1):M_A_CPU0_SA_DQS_DP'<7>:
 C_SIGNAL='@t6g_mb_lib.t6g(sch_1):m_a_cpu0_sa_dqs_dp(7)';
NODE_NAME     U25 AA73
 '@T6G_MB_LIB.T6G(SCH_1):PAGE10_I200@PURE_QUANTA.GENOA_SP5(CHIPS)':
 'MAA_DQS_H7': CDS_PINID='MAA_DQS_H7';
NODE_NAME     J1 179
 '@T6G_MB_LIB.T6G(SCH_1):PAGE85_I537@PURE_QUANTA.SCONN288_DDR506112002KQ(CHIPS)':
 'DQS7_A_T||TDQS7_A_T': CDS_PINID='\dqs7_a_t||tdqs7_a_t\';
NET_NAME
'M_A_CPU0_SA_DQS_DP<8>'
 '@T6G_MB_LIB.T6G(SCH_1):M_A_CPU0_SA_DQS_DP'<8>:
 C_SIGNAL='@t6g_mb_lib.t6g(sch_1):m_a_cpu0_sa_dqs_dp(8)';
NODE_NAME     U25 AG73
 '@T6G_MB_LIB.T6G(SCH_1):PAGE10_I200@PURE_QUANTA.GENOA_SP5(CHIPS)':
 'MAA_DQS_H8': CDS_PINID='MAA_DQS_H8';
NODE_NAME     J1 190
 '@T6G_MB_LIB.T6G(SCH_1):PAGE85_I537@PURE_QUANTA.SCONN288_DDR506112002KQ(CHIPS)':
 'DQS8_A_T||TDQS8_A_T': CDS_PINID='\dqs8_a_t||tdqs8_a_t\';
NET_NAME
'M_A_CPU0_SA_DQS_DP<9>'
 '@T6G_MB_LIB.T6G(SCH_1):M_A_CPU0_SA_DQS_DP'<9>:
 C_SIGNAL='@t6g_mb_lib.t6g(sch_1):m_a_cpu0_sa_dqs_dp(9)';
NODE_NAME     U25 AN73
 '@T6G_MB_LIB.T6G(SCH_1):PAGE10_I200@PURE_QUANTA.GENOA_SP5(CHIPS)':
 'MAA_DQS_H9': CDS_PINID='MAA_DQS_H9';
NODE_NAME     J1 201
 '@T6G_MB_LIB.T6G(SCH_1):PAGE85_I537@PURE_QUANTA.SCONN288_DDR506112002KQ(CHIPS)':
 'DQS9_A_T||TDQS9_A_T': CDS_PINID='\dqs9_a_t||tdqs9_a_t\';
NET_NAME
'M_A_CPU0_SA_PAR'
 '@T6G_MB_LIB.T6G(SCH_1):M_A_CPU0_SA_PAR':
 C_SIGNAL='@t6g_mb_lib.t6g(sch_1):m_a_cpu0_sa_par';
NODE_NAME     U25 BC73
 '@T6G_MB_LIB.T6G(SCH_1):PAGE10_I200@PURE_QUANTA.GENOA_SP5(CHIPS)':
 'MAA_PAR': CDS_PINID='MAA_PAR';
NODE_NAME     J1 74
 '@T6G_MB_LIB.T6G(SCH_1):PAGE85_I536@PURE_QUANTA.SCONN288_DDR506112002KQ(CHIPS)':
 'PAR_A': CDS_PINID='PAR_A';
NET_NAME
'M_A_CPU0_SA_RSP<0>'
 '@T6G_MB_LIB.T6G(SCH_1):M_A_CPU0_SA_RSP'<0>:
 C_SIGNAL='@t6g_mb_lib.t6g(sch_1):m_a_cpu0_sa_rsp(0)';
NODE_NAME     U25 BN73
 '@T6G_MB_LIB.T6G(SCH_1):PAGE10_I200@PURE_QUANTA.GENOA_SP5(CHIPS)':
 'MAA0_RSP_L': CDS_PINID='MAA0_RSP_L';
NODE_NAME     J1 86
 '@T6G_MB_LIB.T6G(SCH_1):PAGE85_I536@PURE_QUANTA.SCONN288_DDR506112002KQ(CHIPS)':
 'LBD||RSP_A_N': CDS_PINID='\lbd||rsp_a_n\';
NET_NAME
'M_A_CPU0_SB_CA<0>'
 '@T6G_MB_LIB.T6G(SCH_1):M_A_CPU0_SB_CA'<0>:
 C_SIGNAL='@t6g_mb_lib.t6g(sch_1):m_a_cpu0_sb_ca(0)';
NODE_NAME     U25 BG73
 '@T6G_MB_LIB.T6G(SCH_1):PAGE10_I200@PURE_QUANTA.GENOA_SP5(CHIPS)':
 'MAB_CA0': CDS_PINID='MAB_CA0';
NODE_NAME     J1 76
 '@T6G_MB_LIB.T6G(SCH_1):PAGE85_I536@PURE_QUANTA.SCONN288_DDR506112002KQ(CHIPS)':
 'CA0_B': CDS_PINID='CA0_B';
NET_NAME
'M_A_CPU0_SB_CA<1>'
 '@T6G_MB_LIB.T6G(SCH_1):M_A_CPU0_SB_CA'<1>:
 C_SIGNAL='@t6g_mb_lib.t6g(sch_1):m_a_cpu0_sb_ca(1)';
NODE_NAME     U25 BH72
 '@T6G_MB_LIB.T6G(SCH_1):PAGE10_I200@PURE_QUANTA.GENOA_SP5(CHIPS)':
 'MAB_CA1': CDS_PINID='MAB_CA1';
NODE_NAME     J1 221
 '@T6G_MB_LIB.T6G(SCH_1):PAGE85_I536@PURE_QUANTA.SCONN288_DDR506112002KQ(CHIPS)':
 'CA1_B': CDS_PINID='CA1_B';
NET_NAME
'M_A_CPU0_SB_CA<2>'
 '@T6G_MB_LIB.T6G(SCH_1):M_A_CPU0_SB_CA'<2>:
 C_SIGNAL='@t6g_mb_lib.t6g(sch_1):m_a_cpu0_sb_ca(2)';
NODE_NAME     U25 BH74
 '@T6G_MB_LIB.T6G(SCH_1):PAGE10_I200@PURE_QUANTA.GENOA_SP5(CHIPS)':
 'MAB_CA2': CDS_PINID='MAB_CA2';
NODE_NAME     J1 78
 '@T6G_MB_LIB.T6G(SCH_1):PAGE85_I536@PURE_QUANTA.SCONN288_DDR506112002KQ(CHIPS)':
 'CA2_B': CDS_PINID='CA2_B';
NET_NAME
'M_A_CPU0_SB_CA<3>'
 '@T6G_MB_LIB.T6G(SCH_1):M_A_CPU0_SB_CA'<3>:
 C_SIGNAL='@t6g_mb_lib.t6g(sch_1):m_a_cpu0_sb_ca(3)';
NODE_NAME     U25 BJ74
 '@T6G_MB_LIB.T6G(SCH_1):PAGE10_I200@PURE_QUANTA.GENOA_SP5(CHIPS)':
 'MAB_CA3': CDS_PINID='MAB_CA3';
NODE_NAME     J1 223
 '@T6G_MB_LIB.T6G(SCH_1):PAGE85_I536@PURE_QUANTA.SCONN288_DDR506112002KQ(CHIPS)':
 'CA3_B': CDS_PINID='CA3_B';
NET_NAME
'M_A_CPU0_SB_CA<4>'
 '@T6G_MB_LIB.T6G(SCH_1):M_A_CPU0_SB_CA'<4>:
 C_SIGNAL='@t6g_mb_lib.t6g(sch_1):m_a_cpu0_sb_ca(4)';
NODE_NAME     U25 BJ73
 '@T6G_MB_LIB.T6G(SCH_1):PAGE10_I200@PURE_QUANTA.GENOA_SP5(CHIPS)':
 'MAB_CA4': CDS_PINID='MAB_CA4';
NODE_NAME     J1 80
 '@T6G_MB_LIB.T6G(SCH_1):PAGE85_I536@PURE_QUANTA.SCONN288_DDR506112002KQ(CHIPS)':
 'CA4_B': CDS_PINID='CA4_B';
NET_NAME
'M_A_CPU0_SB_CA<5>'
 '@T6G_MB_LIB.T6G(SCH_1):M_A_CPU0_SB_CA'<5>:
 C_SIGNAL='@t6g_mb_lib.t6g(sch_1):m_a_cpu0_sb_ca(5)';
NODE_NAME     U25 BK72
 '@T6G_MB_LIB.T6G(SCH_1):PAGE10_I200@PURE_QUANTA.GENOA_SP5(CHIPS)':
 'MAB_CA5': CDS_PINID='MAB_CA5';
NODE_NAME     J1 225
 '@T6G_MB_LIB.T6G(SCH_1):PAGE85_I536@PURE_QUANTA.SCONN288_DDR506112002KQ(CHIPS)':
 'CA5_B': CDS_PINID='CA5_B';
NET_NAME
'M_A_CPU0_SB_CA<6>'
 '@T6G_MB_LIB.T6G(SCH_1):M_A_CPU0_SB_CA'<6>:
 C_SIGNAL='@t6g_mb_lib.t6g(sch_1):m_a_cpu0_sb_ca(6)';
NODE_NAME     U25 BK74
 '@T6G_MB_LIB.T6G(SCH_1):PAGE10_I200@PURE_QUANTA.GENOA_SP5(CHIPS)':
 'MAB_CA6': CDS_PINID='MAB_CA6';
NODE_NAME     J1 82
 '@T6G_MB_LIB.T6G(SCH_1):PAGE85_I536@PURE_QUANTA.SCONN288_DDR506112002KQ(CHIPS)':
 'CA6_B': CDS_PINID='CA6_B';
NET_NAME
'M_A_CPU0_SB_CB<0>'
 '@T6G_MB_LIB.T6G(SCH_1):M_A_CPU0_SB_CB'<0>:
 C_SIGNAL='@t6g_mb_lib.t6g(sch_1):m_a_cpu0_sb_cb(0)';
NODE_NAME     U25 BY74
 '@T6G_MB_LIB.T6G(SCH_1):PAGE10_I200@PURE_QUANTA.GENOA_SP5(CHIPS)':
 'MAB_CHECK0': CDS_PINID='MAB_CHECK0';
NODE_NAME     J1 96
 '@T6G_MB_LIB.T6G(SCH_1):PAGE85_I536@PURE_QUANTA.SCONN288_DDR506112002KQ(CHIPS)':
 'CB0_B': CDS_PINID='CB0_B';
NET_NAME
'M_A_CPU0_SB_CB<1>'
 '@T6G_MB_LIB.T6G(SCH_1):M_A_CPU0_SB_CB'<1>:
 C_SIGNAL='@t6g_mb_lib.t6g(sch_1):m_a_cpu0_sb_cb(1)';
NODE_NAME     U25 CA73
 '@T6G_MB_LIB.T6G(SCH_1):PAGE10_I200@PURE_QUANTA.GENOA_SP5(CHIPS)':
 'MAB_CHECK1': CDS_PINID='MAB_CHECK1';
NODE_NAME     J1 98
 '@T6G_MB_LIB.T6G(SCH_1):PAGE85_I536@PURE_QUANTA.SCONN288_DDR506112002KQ(CHIPS)':
 'CB1_B': CDS_PINID='CB1_B';
NET_NAME
'M_A_CPU0_SB_CB<2>'
 '@T6G_MB_LIB.T6G(SCH_1):M_A_CPU0_SB_CB'<2>:
 C_SIGNAL='@t6g_mb_lib.t6g(sch_1):m_a_cpu0_sb_cb(2)';
NODE_NAME     U25 CA74
 '@T6G_MB_LIB.T6G(SCH_1):PAGE10_I200@PURE_QUANTA.GENOA_SP5(CHIPS)':
 'MAB_CHECK2': CDS_PINID='MAB_CHECK2';
NODE_NAME     J1 241
 '@T6G_MB_LIB.T6G(SCH_1):PAGE85_I536@PURE_QUANTA.SCONN288_DDR506112002KQ(CHIPS)':
 'CB2_B': CDS_PINID='CB2_B';
NET_NAME
'M_A_CPU0_SB_CB<3>'
 '@T6G_MB_LIB.T6G(SCH_1):M_A_CPU0_SB_CB'<3>:
 C_SIGNAL='@t6g_mb_lib.t6g(sch_1):m_a_cpu0_sb_cb(3)';
NODE_NAME     U25 CB72
 '@T6G_MB_LIB.T6G(SCH_1):PAGE10_I200@PURE_QUANTA.GENOA_SP5(CHIPS)':
 'MAB_CHECK3': CDS_PINID='MAB_CHECK3';
NODE_NAME     J1 243
 '@T6G_MB_LIB.T6G(SCH_1):PAGE85_I536@PURE_QUANTA.SCONN288_DDR506112002KQ(CHIPS)':
 'CB3_B': CDS_PINID='CB3_B';
NET_NAME
'M_A_CPU0_SB_CB<4>'
 '@T6G_MB_LIB.T6G(SCH_1):M_A_CPU0_SB_CB'<4>:
 C_SIGNAL='@t6g_mb_lib.t6g(sch_1):m_a_cpu0_sb_cb(4)';
NODE_NAME     U25 BT74
 '@T6G_MB_LIB.T6G(SCH_1):PAGE10_I200@PURE_QUANTA.GENOA_SP5(CHIPS)':
 'MAB_CHECK4': CDS_PINID='MAB_CHECK4';
NODE_NAME     J1 89
 '@T6G_MB_LIB.T6G(SCH_1):PAGE85_I536@PURE_QUANTA.SCONN288_DDR506112002KQ(CHIPS)':
 'CB4_B': CDS_PINID='CB4_B';
NET_NAME
'M_A_CPU0_SB_CB<5>'
 '@T6G_MB_LIB.T6G(SCH_1):M_A_CPU0_SB_CB'<5>:
 C_SIGNAL='@t6g_mb_lib.t6g(sch_1):m_a_cpu0_sb_cb(5)';
NODE_NAME     U25 BU73
 '@T6G_MB_LIB.T6G(SCH_1):PAGE10_I200@PURE_QUANTA.GENOA_SP5(CHIPS)':
 'MAB_CHECK5': CDS_PINID='MAB_CHECK5';
NODE_NAME     J1 91
 '@T6G_MB_LIB.T6G(SCH_1):PAGE85_I536@PURE_QUANTA.SCONN288_DDR506112002KQ(CHIPS)':
 'CB5_B': CDS_PINID='CB5_B';
NET_NAME
'M_A_CPU0_SB_CB<6>'
 '@T6G_MB_LIB.T6G(SCH_1):M_A_CPU0_SB_CB'<6>:
 C_SIGNAL='@t6g_mb_lib.t6g(sch_1):m_a_cpu0_sb_cb(6)';
NODE_NAME     U25 BU74
 '@T6G_MB_LIB.T6G(SCH_1):PAGE10_I200@PURE_QUANTA.GENOA_SP5(CHIPS)':
 'MAB_CHECK6': CDS_PINID='MAB_CHECK6';
NODE_NAME     J1 234
 '@T6G_MB_LIB.T6G(SCH_1):PAGE85_I536@PURE_QUANTA.SCONN288_DDR506112002KQ(CHIPS)':
 'CB6_B': CDS_PINID='CB6_B';
NET_NAME
'M_A_CPU0_SB_CB<7>'
 '@T6G_MB_LIB.T6G(SCH_1):M_A_CPU0_SB_CB'<7>:
 C_SIGNAL='@t6g_mb_lib.t6g(sch_1):m_a_cpu0_sb_cb(7)';
NODE_NAME     U25 BV72
 '@T6G_MB_LIB.T6G(SCH_1):PAGE10_I200@PURE_QUANTA.GENOA_SP5(CHIPS)':
 'MAB_CHECK7': CDS_PINID='MAB_CHECK7';
NODE_NAME     J1 236
 '@T6G_MB_LIB.T6G(SCH_1):PAGE85_I536@PURE_QUANTA.SCONN288_DDR506112002KQ(CHIPS)':
 'CB7_B': CDS_PINID='CB7_B';
NET_NAME
'M_A_CPU0_SB_CS_N<0>'
 '@T6G_MB_LIB.T6G(SCH_1):M_A_CPU0_SB_CS_N'<0>:
 C_SIGNAL='@t6g_mb_lib.t6g(sch_1):m_a_cpu0_sb_cs_n(0)';
NODE_NAME     U25 BM72
 '@T6G_MB_LIB.T6G(SCH_1):PAGE10_I200@PURE_QUANTA.GENOA_SP5(CHIPS)':
 'MAB0_CS_L0': CDS_PINID='MAB0_CS_L0';
NODE_NAME     J1 84
 '@T6G_MB_LIB.T6G(SCH_1):PAGE85_I536@PURE_QUANTA.SCONN288_DDR506112002KQ(CHIPS)':
 'CS0_B_N': CDS_PINID='CS0_B_N';
NET_NAME
'M_A_CPU0_SB_CS_N<1>'
 '@T6G_MB_LIB.T6G(SCH_1):M_A_CPU0_SB_CS_N'<1>:
 C_SIGNAL='@t6g_mb_lib.t6g(sch_1):m_a_cpu0_sb_cs_n(1)';
NODE_NAME     U25 BN74
 '@T6G_MB_LIB.T6G(SCH_1):PAGE10_I200@PURE_QUANTA.GENOA_SP5(CHIPS)':
 'MAB0_CS_L1': CDS_PINID='MAB0_CS_L1';
NODE_NAME     J1 229
 '@T6G_MB_LIB.T6G(SCH_1):PAGE85_I536@PURE_QUANTA.SCONN288_DDR506112002KQ(CHIPS)':
 'CS1_B_N': CDS_PINID='CS1_B_N';
NET_NAME
'M_A_CPU0_SB_DQ<0>'
 '@T6G_MB_LIB.T6G(SCH_1):M_A_CPU0_SB_DQ'<0>:
 C_SIGNAL='@t6g_mb_lib.t6g(sch_1):m_a_cpu0_sb_dq(0)';
NODE_NAME     U25 CB74
 '@T6G_MB_LIB.T6G(SCH_1):PAGE10_I200@PURE_QUANTA.GENOA_SP5(CHIPS)':
 'MAB_DATA0': CDS_PINID='MAB_DATA0';
NODE_NAME     J1 100
 '@T6G_MB_LIB.T6G(SCH_1):PAGE85_I536@PURE_QUANTA.SCONN288_DDR506112002KQ(CHIPS)':
 'DQ0_B': CDS_PINID='DQ0_B';
NET_NAME
'M_A_CPU0_SB_DQ<10>'
 '@T6G_MB_LIB.T6G(SCH_1):M_A_CPU0_SB_DQ'<10>:
 C_SIGNAL='@t6g_mb_lib.t6g(sch_1):m_a_cpu0_sb_dq(10)';
NODE_NAME     U25 CJ74
 '@T6G_MB_LIB.T6G(SCH_1):PAGE10_I200@PURE_QUANTA.GENOA_SP5(CHIPS)':
 'MAB_DATA10': CDS_PINID='MAB_DATA10';
NODE_NAME     J1 256
 '@T6G_MB_LIB.T6G(SCH_1):PAGE85_I536@PURE_QUANTA.SCONN288_DDR506112002KQ(CHIPS)':
 'DQ10_B': CDS_PINID='DQ10_B';
NET_NAME
'M_A_CPU0_SB_DQ<11>'
 '@T6G_MB_LIB.T6G(SCH_1):M_A_CPU0_SB_DQ'<11>:
 C_SIGNAL='@t6g_mb_lib.t6g(sch_1):m_a_cpu0_sb_dq(11)';
NODE_NAME     U25 CK72
 '@T6G_MB_LIB.T6G(SCH_1):PAGE10_I200@PURE_QUANTA.GENOA_SP5(CHIPS)':
 'MAB_DATA11': CDS_PINID='MAB_DATA11';
NODE_NAME     J1 258
 '@T6G_MB_LIB.T6G(SCH_1):PAGE85_I536@PURE_QUANTA.SCONN288_DDR506112002KQ(CHIPS)':
 'DQ11_B': CDS_PINID='DQ11_B';
NET_NAME
'M_A_CPU0_SB_DQ<12>'
 '@T6G_MB_LIB.T6G(SCH_1):M_A_CPU0_SB_DQ'<12>:
 C_SIGNAL='@t6g_mb_lib.t6g(sch_1):m_a_cpu0_sb_dq(12)';
NODE_NAME     U25 CM74
 '@T6G_MB_LIB.T6G(SCH_1):PAGE10_I200@PURE_QUANTA.GENOA_SP5(CHIPS)':
 'MAB_DATA12': CDS_PINID='MAB_DATA12';
NODE_NAME     J1 118
 '@T6G_MB_LIB.T6G(SCH_1):PAGE85_I536@PURE_QUANTA.SCONN288_DDR506112002KQ(CHIPS)':
 'DQ12_B': CDS_PINID='DQ12_B';
NET_NAME
'M_A_CPU0_SB_DQ<13>'
 '@T6G_MB_LIB.T6G(SCH_1):M_A_CPU0_SB_DQ'<13>:
 C_SIGNAL='@t6g_mb_lib.t6g(sch_1):m_a_cpu0_sb_dq(13)';
NODE_NAME     U25 CN73
 '@T6G_MB_LIB.T6G(SCH_1):PAGE10_I200@PURE_QUANTA.GENOA_SP5(CHIPS)':
 'MAB_DATA13': CDS_PINID='MAB_DATA13';
NODE_NAME     J1 120
 '@T6G_MB_LIB.T6G(SCH_1):PAGE85_I536@PURE_QUANTA.SCONN288_DDR506112002KQ(CHIPS)':
 'DQ13_B': CDS_PINID='DQ13_B';
NET_NAME
'M_A_CPU0_SB_DQ<14>'
 '@T6G_MB_LIB.T6G(SCH_1):M_A_CPU0_SB_DQ'<14>:
 C_SIGNAL='@t6g_mb_lib.t6g(sch_1):m_a_cpu0_sb_dq(14)';
NODE_NAME     U25 CN74
 '@T6G_MB_LIB.T6G(SCH_1):PAGE10_I200@PURE_QUANTA.GENOA_SP5(CHIPS)':
 'MAB_DATA14': CDS_PINID='MAB_DATA14';
NODE_NAME     J1 263
 '@T6G_MB_LIB.T6G(SCH_1):PAGE85_I536@PURE_QUANTA.SCONN288_DDR506112002KQ(CHIPS)':
 'DQ14_B': CDS_PINID='DQ14_B';
NET_NAME
'M_A_CPU0_SB_DQ<15>'
 '@T6G_MB_LIB.T6G(SCH_1):M_A_CPU0_SB_DQ'<15>:
 C_SIGNAL='@t6g_mb_lib.t6g(sch_1):m_a_cpu0_sb_dq(15)';
NODE_NAME     U25 CP72
 '@T6G_MB_LIB.T6G(SCH_1):PAGE10_I200@PURE_QUANTA.GENOA_SP5(CHIPS)':
 'MAB_DATA15': CDS_PINID='MAB_DATA15';
NODE_NAME     J1 265
 '@T6G_MB_LIB.T6G(SCH_1):PAGE85_I536@PURE_QUANTA.SCONN288_DDR506112002KQ(CHIPS)':
 'DQ15_B': CDS_PINID='DQ15_B';
NET_NAME
'M_A_CPU0_SB_DQ<16>'
 '@T6G_MB_LIB.T6G(SCH_1):M_A_CPU0_SB_DQ'<16>:
 C_SIGNAL='@t6g_mb_lib.t6g(sch_1):m_a_cpu0_sb_dq(16)';
NODE_NAME     U25 CP74
 '@T6G_MB_LIB.T6G(SCH_1):PAGE10_I200@PURE_QUANTA.GENOA_SP5(CHIPS)':
 'MAB_DATA16': CDS_PINID='MAB_DATA16';
NODE_NAME     J1 122
 '@T6G_MB_LIB.T6G(SCH_1):PAGE85_I536@PURE_QUANTA.SCONN288_DDR506112002KQ(CHIPS)':
 'DQ16_B': CDS_PINID='DQ16_B';
NET_NAME
'M_A_CPU0_SB_DQ<17>'
 '@T6G_MB_LIB.T6G(SCH_1):M_A_CPU0_SB_DQ'<17>:
 C_SIGNAL='@t6g_mb_lib.t6g(sch_1):m_a_cpu0_sb_dq(17)';
NODE_NAME     U25 CR73
 '@T6G_MB_LIB.T6G(SCH_1):PAGE10_I200@PURE_QUANTA.GENOA_SP5(CHIPS)':
 'MAB_DATA17': CDS_PINID='MAB_DATA17';
NODE_NAME     J1 124
 '@T6G_MB_LIB.T6G(SCH_1):PAGE85_I536@PURE_QUANTA.SCONN288_DDR506112002KQ(CHIPS)':
 'DQ17_B': CDS_PINID='DQ17_B';
NET_NAME
'M_A_CPU0_SB_DQ<18>'
 '@T6G_MB_LIB.T6G(SCH_1):M_A_CPU0_SB_DQ'<18>:
 C_SIGNAL='@t6g_mb_lib.t6g(sch_1):m_a_cpu0_sb_dq(18)';
NODE_NAME     U25 CR74
 '@T6G_MB_LIB.T6G(SCH_1):PAGE10_I200@PURE_QUANTA.GENOA_SP5(CHIPS)':
 'MAB_DATA18': CDS_PINID='MAB_DATA18';
NODE_NAME     J1 267
 '@T6G_MB_LIB.T6G(SCH_1):PAGE85_I536@PURE_QUANTA.SCONN288_DDR506112002KQ(CHIPS)':
 'DQ18_B': CDS_PINID='DQ18_B';
NET_NAME
'M_A_CPU0_SB_DQ<19>'
 '@T6G_MB_LIB.T6G(SCH_1):M_A_CPU0_SB_DQ'<19>:
 C_SIGNAL='@t6g_mb_lib.t6g(sch_1):m_a_cpu0_sb_dq(19)';
NODE_NAME     U25 CT72
 '@T6G_MB_LIB.T6G(SCH_1):PAGE10_I200@PURE_QUANTA.GENOA_SP5(CHIPS)':
 'MAB_DATA19': CDS_PINID='MAB_DATA19';
NODE_NAME     J1 269
 '@T6G_MB_LIB.T6G(SCH_1):PAGE85_I536@PURE_QUANTA.SCONN288_DDR506112002KQ(CHIPS)':
 'DQ19_B': CDS_PINID='DQ19_B';
NET_NAME
'M_A_CPU0_SB_DQ<1>'
 '@T6G_MB_LIB.T6G(SCH_1):M_A_CPU0_SB_DQ'<1>:
 C_SIGNAL='@t6g_mb_lib.t6g(sch_1):m_a_cpu0_sb_dq(1)';
NODE_NAME     U25 CC73
 '@T6G_MB_LIB.T6G(SCH_1):PAGE10_I200@PURE_QUANTA.GENOA_SP5(CHIPS)':
 'MAB_DATA1': CDS_PINID='MAB_DATA1';
NODE_NAME     J1 102
 '@T6G_MB_LIB.T6G(SCH_1):PAGE85_I536@PURE_QUANTA.SCONN288_DDR506112002KQ(CHIPS)':
 'DQ1_B': CDS_PINID='DQ1_B';
NET_NAME
'M_A_CPU0_SB_DQ<20>'
 '@T6G_MB_LIB.T6G(SCH_1):M_A_CPU0_SB_DQ'<20>:
 C_SIGNAL='@t6g_mb_lib.t6g(sch_1):m_a_cpu0_sb_dq(20)';
NODE_NAME     U25 CV74
 '@T6G_MB_LIB.T6G(SCH_1):PAGE10_I200@PURE_QUANTA.GENOA_SP5(CHIPS)':
 'MAB_DATA20': CDS_PINID='MAB_DATA20';
NODE_NAME     J1 129
 '@T6G_MB_LIB.T6G(SCH_1):PAGE85_I536@PURE_QUANTA.SCONN288_DDR506112002KQ(CHIPS)':
 'DQ20_B': CDS_PINID='DQ20_B';
NET_NAME
'M_A_CPU0_SB_DQ<21>'
 '@T6G_MB_LIB.T6G(SCH_1):M_A_CPU0_SB_DQ'<21>:
 C_SIGNAL='@t6g_mb_lib.t6g(sch_1):m_a_cpu0_sb_dq(21)';
NODE_NAME     U25 CW73
 '@T6G_MB_LIB.T6G(SCH_1):PAGE10_I200@PURE_QUANTA.GENOA_SP5(CHIPS)':
 'MAB_DATA21': CDS_PINID='MAB_DATA21';
NODE_NAME     J1 131
 '@T6G_MB_LIB.T6G(SCH_1):PAGE85_I536@PURE_QUANTA.SCONN288_DDR506112002KQ(CHIPS)':
 'DQ21_B': CDS_PINID='DQ21_B';
NET_NAME
'M_A_CPU0_SB_DQ<22>'
 '@T6G_MB_LIB.T6G(SCH_1):M_A_CPU0_SB_DQ'<22>:
 C_SIGNAL='@t6g_mb_lib.t6g(sch_1):m_a_cpu0_sb_dq(22)';
NODE_NAME     U25 CW74
 '@T6G_MB_LIB.T6G(SCH_1):PAGE10_I200@PURE_QUANTA.GENOA_SP5(CHIPS)':
 'MAB_DATA22': CDS_PINID='MAB_DATA22';
NODE_NAME     J1 274
 '@T6G_MB_LIB.T6G(SCH_1):PAGE85_I536@PURE_QUANTA.SCONN288_DDR506112002KQ(CHIPS)':
 'DQ22_B': CDS_PINID='DQ22_B';
NET_NAME
'M_A_CPU0_SB_DQ<23>'
 '@T6G_MB_LIB.T6G(SCH_1):M_A_CPU0_SB_DQ'<23>:
 C_SIGNAL='@t6g_mb_lib.t6g(sch_1):m_a_cpu0_sb_dq(23)';
NODE_NAME     U25 CY72
 '@T6G_MB_LIB.T6G(SCH_1):PAGE10_I200@PURE_QUANTA.GENOA_SP5(CHIPS)':
 'MAB_DATA23': CDS_PINID='MAB_DATA23';
NODE_NAME     J1 276
 '@T6G_MB_LIB.T6G(SCH_1):PAGE85_I536@PURE_QUANTA.SCONN288_DDR506112002KQ(CHIPS)':
 'DQ23_B': CDS_PINID='DQ23_B';
NET_NAME
'M_A_CPU0_SB_DQ<24>'
 '@T6G_MB_LIB.T6G(SCH_1):M_A_CPU0_SB_DQ'<24>:
 C_SIGNAL='@t6g_mb_lib.t6g(sch_1):m_a_cpu0_sb_dq(24)';
NODE_NAME     U25 CY74
 '@T6G_MB_LIB.T6G(SCH_1):PAGE10_I200@PURE_QUANTA.GENOA_SP5(CHIPS)':
 'MAB_DATA24': CDS_PINID='MAB_DATA24';
NODE_NAME     J1 133
 '@T6G_MB_LIB.T6G(SCH_1):PAGE85_I536@PURE_QUANTA.SCONN288_DDR506112002KQ(CHIPS)':
 'DQ24_B': CDS_PINID='DQ24_B';
NET_NAME
'M_A_CPU0_SB_DQ<25>'
 '@T6G_MB_LIB.T6G(SCH_1):M_A_CPU0_SB_DQ'<25>:
 C_SIGNAL='@t6g_mb_lib.t6g(sch_1):m_a_cpu0_sb_dq(25)';
NODE_NAME     U25 DA73
 '@T6G_MB_LIB.T6G(SCH_1):PAGE10_I200@PURE_QUANTA.GENOA_SP5(CHIPS)':
 'MAB_DATA25': CDS_PINID='MAB_DATA25';
NODE_NAME     J1 135
 '@T6G_MB_LIB.T6G(SCH_1):PAGE85_I536@PURE_QUANTA.SCONN288_DDR506112002KQ(CHIPS)':
 'DQ25_B': CDS_PINID='DQ25_B';
NET_NAME
'M_A_CPU0_SB_DQ<26>'
 '@T6G_MB_LIB.T6G(SCH_1):M_A_CPU0_SB_DQ'<26>:
 C_SIGNAL='@t6g_mb_lib.t6g(sch_1):m_a_cpu0_sb_dq(26)';
NODE_NAME     U25 DA74
 '@T6G_MB_LIB.T6G(SCH_1):PAGE10_I200@PURE_QUANTA.GENOA_SP5(CHIPS)':
 'MAB_DATA26': CDS_PINID='MAB_DATA26';
NODE_NAME     J1 278
 '@T6G_MB_LIB.T6G(SCH_1):PAGE85_I536@PURE_QUANTA.SCONN288_DDR506112002KQ(CHIPS)':
 'DQ26_B': CDS_PINID='DQ26_B';
NET_NAME
'M_A_CPU0_SB_DQ<27>'
 '@T6G_MB_LIB.T6G(SCH_1):M_A_CPU0_SB_DQ'<27>:
 C_SIGNAL='@t6g_mb_lib.t6g(sch_1):m_a_cpu0_sb_dq(27)';
NODE_NAME     U25 DB72
 '@T6G_MB_LIB.T6G(SCH_1):PAGE10_I200@PURE_QUANTA.GENOA_SP5(CHIPS)':
 'MAB_DATA27': CDS_PINID='MAB_DATA27';
NODE_NAME     J1 280
 '@T6G_MB_LIB.T6G(SCH_1):PAGE85_I536@PURE_QUANTA.SCONN288_DDR506112002KQ(CHIPS)':
 'DQ27_B': CDS_PINID='DQ27_B';
NET_NAME
'M_A_CPU0_SB_DQ<28>'
 '@T6G_MB_LIB.T6G(SCH_1):M_A_CPU0_SB_DQ'<28>:
 C_SIGNAL='@t6g_mb_lib.t6g(sch_1):m_a_cpu0_sb_dq(28)';
NODE_NAME     U25 DD74
 '@T6G_MB_LIB.T6G(SCH_1):PAGE10_I200@PURE_QUANTA.GENOA_SP5(CHIPS)':
 'MAB_DATA28': CDS_PINID='MAB_DATA28';
NODE_NAME     J1 140
 '@T6G_MB_LIB.T6G(SCH_1):PAGE85_I536@PURE_QUANTA.SCONN288_DDR506112002KQ(CHIPS)':
 'DQ28_B': CDS_PINID='DQ28_B';
NET_NAME
'M_A_CPU0_SB_DQ<29>'
 '@T6G_MB_LIB.T6G(SCH_1):M_A_CPU0_SB_DQ'<29>:
 C_SIGNAL='@t6g_mb_lib.t6g(sch_1):m_a_cpu0_sb_dq(29)';
NODE_NAME     U25 DE73
 '@T6G_MB_LIB.T6G(SCH_1):PAGE10_I200@PURE_QUANTA.GENOA_SP5(CHIPS)':
 'MAB_DATA29': CDS_PINID='MAB_DATA29';
NODE_NAME     J1 142
 '@T6G_MB_LIB.T6G(SCH_1):PAGE85_I536@PURE_QUANTA.SCONN288_DDR506112002KQ(CHIPS)':
 'DQ29_B': CDS_PINID='DQ29_B';
NET_NAME
'M_A_CPU0_SB_DQ<2>'
 '@T6G_MB_LIB.T6G(SCH_1):M_A_CPU0_SB_DQ'<2>:
 C_SIGNAL='@t6g_mb_lib.t6g(sch_1):m_a_cpu0_sb_dq(2)';
NODE_NAME     U25 CC74
 '@T6G_MB_LIB.T6G(SCH_1):PAGE10_I200@PURE_QUANTA.GENOA_SP5(CHIPS)':
 'MAB_DATA2': CDS_PINID='MAB_DATA2';
NODE_NAME     J1 245
 '@T6G_MB_LIB.T6G(SCH_1):PAGE85_I536@PURE_QUANTA.SCONN288_DDR506112002KQ(CHIPS)':
 'DQ2_B': CDS_PINID='DQ2_B';
NET_NAME
'M_A_CPU0_SB_DQ<30>'
 '@T6G_MB_LIB.T6G(SCH_1):M_A_CPU0_SB_DQ'<30>:
 C_SIGNAL='@t6g_mb_lib.t6g(sch_1):m_a_cpu0_sb_dq(30)';
NODE_NAME     U25 DE74
 '@T6G_MB_LIB.T6G(SCH_1):PAGE10_I200@PURE_QUANTA.GENOA_SP5(CHIPS)':
 'MAB_DATA30': CDS_PINID='MAB_DATA30';
NODE_NAME     J1 285
 '@T6G_MB_LIB.T6G(SCH_1):PAGE85_I536@PURE_QUANTA.SCONN288_DDR506112002KQ(CHIPS)':
 'DQ30_B': CDS_PINID='DQ30_B';
NET_NAME
'M_A_CPU0_SB_DQ<31>'
 '@T6G_MB_LIB.T6G(SCH_1):M_A_CPU0_SB_DQ'<31>:
 C_SIGNAL='@t6g_mb_lib.t6g(sch_1):m_a_cpu0_sb_dq(31)';
NODE_NAME     U25 DF74
 '@T6G_MB_LIB.T6G(SCH_1):PAGE10_I200@PURE_QUANTA.GENOA_SP5(CHIPS)':
 'MAB_DATA31': CDS_PINID='MAB_DATA31';
NODE_NAME     J1 287
 '@T6G_MB_LIB.T6G(SCH_1):PAGE85_I536@PURE_QUANTA.SCONN288_DDR506112002KQ(CHIPS)':
 'DQ31_B': CDS_PINID='DQ31_B';
NET_NAME
'M_A_CPU0_SB_DQ<3>'
 '@T6G_MB_LIB.T6G(SCH_1):M_A_CPU0_SB_DQ'<3>:
 C_SIGNAL='@t6g_mb_lib.t6g(sch_1):m_a_cpu0_sb_dq(3)';
NODE_NAME     U25 CD72
 '@T6G_MB_LIB.T6G(SCH_1):PAGE10_I200@PURE_QUANTA.GENOA_SP5(CHIPS)':
 'MAB_DATA3': CDS_PINID='MAB_DATA3';
NODE_NAME     J1 247
 '@T6G_MB_LIB.T6G(SCH_1):PAGE85_I536@PURE_QUANTA.SCONN288_DDR506112002KQ(CHIPS)':
 'DQ3_B': CDS_PINID='DQ3_B';
NET_NAME
'M_A_CPU0_SB_DQ<4>'
 '@T6G_MB_LIB.T6G(SCH_1):M_A_CPU0_SB_DQ'<4>:
 C_SIGNAL='@t6g_mb_lib.t6g(sch_1):m_a_cpu0_sb_dq(4)';
NODE_NAME     U25 CF74
 '@T6G_MB_LIB.T6G(SCH_1):PAGE10_I200@PURE_QUANTA.GENOA_SP5(CHIPS)':
 'MAB_DATA4': CDS_PINID='MAB_DATA4';
NODE_NAME     J1 107
 '@T6G_MB_LIB.T6G(SCH_1):PAGE85_I536@PURE_QUANTA.SCONN288_DDR506112002KQ(CHIPS)':
 'DQ4_B': CDS_PINID='DQ4_B';
NET_NAME
'M_A_CPU0_SB_DQ<5>'
 '@T6G_MB_LIB.T6G(SCH_1):M_A_CPU0_SB_DQ'<5>:
 C_SIGNAL='@t6g_mb_lib.t6g(sch_1):m_a_cpu0_sb_dq(5)';
NODE_NAME     U25 CG73
 '@T6G_MB_LIB.T6G(SCH_1):PAGE10_I200@PURE_QUANTA.GENOA_SP5(CHIPS)':
 'MAB_DATA5': CDS_PINID='MAB_DATA5';
NODE_NAME     J1 109
 '@T6G_MB_LIB.T6G(SCH_1):PAGE85_I536@PURE_QUANTA.SCONN288_DDR506112002KQ(CHIPS)':
 'DQ5_B': CDS_PINID='DQ5_B';
NET_NAME
'M_A_CPU0_SB_DQ<6>'
 '@T6G_MB_LIB.T6G(SCH_1):M_A_CPU0_SB_DQ'<6>:
 C_SIGNAL='@t6g_mb_lib.t6g(sch_1):m_a_cpu0_sb_dq(6)';
NODE_NAME     U25 CG74
 '@T6G_MB_LIB.T6G(SCH_1):PAGE10_I200@PURE_QUANTA.GENOA_SP5(CHIPS)':
 'MAB_DATA6': CDS_PINID='MAB_DATA6';
NODE_NAME     J1 252
 '@T6G_MB_LIB.T6G(SCH_1):PAGE85_I536@PURE_QUANTA.SCONN288_DDR506112002KQ(CHIPS)':
 'DQ6_B': CDS_PINID='DQ6_B';
NET_NAME
'M_A_CPU0_SB_DQ<7>'
 '@T6G_MB_LIB.T6G(SCH_1):M_A_CPU0_SB_DQ'<7>:
 C_SIGNAL='@t6g_mb_lib.t6g(sch_1):m_a_cpu0_sb_dq(7)';
NODE_NAME     U25 CH72
 '@T6G_MB_LIB.T6G(SCH_1):PAGE10_I200@PURE_QUANTA.GENOA_SP5(CHIPS)':
 'MAB_DATA7': CDS_PINID='MAB_DATA7';
NODE_NAME     J1 254
 '@T6G_MB_LIB.T6G(SCH_1):PAGE85_I536@PURE_QUANTA.SCONN288_DDR506112002KQ(CHIPS)':
 'DQ7_B': CDS_PINID='DQ7_B';
NET_NAME
'M_A_CPU0_SB_DQ<8>'
 '@T6G_MB_LIB.T6G(SCH_1):M_A_CPU0_SB_DQ'<8>:
 C_SIGNAL='@t6g_mb_lib.t6g(sch_1):m_a_cpu0_sb_dq(8)';
NODE_NAME     U25 CH74
 '@T6G_MB_LIB.T6G(SCH_1):PAGE10_I200@PURE_QUANTA.GENOA_SP5(CHIPS)':
 'MAB_DATA8': CDS_PINID='MAB_DATA8';
NODE_NAME     J1 111
 '@T6G_MB_LIB.T6G(SCH_1):PAGE85_I536@PURE_QUANTA.SCONN288_DDR506112002KQ(CHIPS)':
 'DQ8_B': CDS_PINID='DQ8_B';
NET_NAME
'M_A_CPU0_SB_DQ<9>'
 '@T6G_MB_LIB.T6G(SCH_1):M_A_CPU0_SB_DQ'<9>:
 C_SIGNAL='@t6g_mb_lib.t6g(sch_1):m_a_cpu0_sb_dq(9)';
NODE_NAME     U25 CJ73
 '@T6G_MB_LIB.T6G(SCH_1):PAGE10_I200@PURE_QUANTA.GENOA_SP5(CHIPS)':
 'MAB_DATA9': CDS_PINID='MAB_DATA9';
NODE_NAME     J1 113
 '@T6G_MB_LIB.T6G(SCH_1):PAGE85_I536@PURE_QUANTA.SCONN288_DDR506112002KQ(CHIPS)':
 'DQ9_B': CDS_PINID='DQ9_B';
NET_NAME
'M_A_CPU0_SB_DQS_DN<0>'
 '@T6G_MB_LIB.T6G(SCH_1):M_A_CPU0_SB_DQS_DN'<0>:
 C_SIGNAL='@t6g_mb_lib.t6g(sch_1):m_a_cpu0_sb_dqs_dn(0)';
NODE_NAME     U25 CE74
 '@T6G_MB_LIB.T6G(SCH_1):PAGE10_I200@PURE_QUANTA.GENOA_SP5(CHIPS)':
 'MAB_DQS_L0': CDS_PINID='MAB_DQS_L0';
NODE_NAME     J1 105
 '@T6G_MB_LIB.T6G(SCH_1):PAGE85_I537@PURE_QUANTA.SCONN288_DDR506112002KQ(CHIPS)':
 'DQS0_B_C': CDS_PINID='DQS0_B_C';
NET_NAME
'M_A_CPU0_SB_DQS_DN<1>'
 '@T6G_MB_LIB.T6G(SCH_1):M_A_CPU0_SB_DQS_DN'<1>:
 C_SIGNAL='@t6g_mb_lib.t6g(sch_1):m_a_cpu0_sb_dqs_dn(1)';
NODE_NAME     U25 CL74
 '@T6G_MB_LIB.T6G(SCH_1):PAGE10_I200@PURE_QUANTA.GENOA_SP5(CHIPS)':
 'MAB_DQS_L1': CDS_PINID='MAB_DQS_L1';
NODE_NAME     J1 116
 '@T6G_MB_LIB.T6G(SCH_1):PAGE85_I537@PURE_QUANTA.SCONN288_DDR506112002KQ(CHIPS)':
 'DQS1_B_C': CDS_PINID='DQS1_B_C';
NET_NAME
'M_A_CPU0_SB_DQS_DN<2>'
 '@T6G_MB_LIB.T6G(SCH_1):M_A_CPU0_SB_DQS_DN'<2>:
 C_SIGNAL='@t6g_mb_lib.t6g(sch_1):m_a_cpu0_sb_dqs_dn(2)';
NODE_NAME     U25 CU74
 '@T6G_MB_LIB.T6G(SCH_1):PAGE10_I200@PURE_QUANTA.GENOA_SP5(CHIPS)':
 'MAB_DQS_L2': CDS_PINID='MAB_DQS_L2';
NODE_NAME     J1 127
 '@T6G_MB_LIB.T6G(SCH_1):PAGE85_I537@PURE_QUANTA.SCONN288_DDR506112002KQ(CHIPS)':
 'DQS2_B_C': CDS_PINID='DQS2_B_C';
NET_NAME
'M_A_CPU0_SB_DQS_DN<3>'
 '@T6G_MB_LIB.T6G(SCH_1):M_A_CPU0_SB_DQS_DN'<3>:
 C_SIGNAL='@t6g_mb_lib.t6g(sch_1):m_a_cpu0_sb_dqs_dn(3)';
NODE_NAME     U25 DC74
 '@T6G_MB_LIB.T6G(SCH_1):PAGE10_I200@PURE_QUANTA.GENOA_SP5(CHIPS)':
 'MAB_DQS_L3': CDS_PINID='MAB_DQS_L3';
NODE_NAME     J1 138
 '@T6G_MB_LIB.T6G(SCH_1):PAGE85_I537@PURE_QUANTA.SCONN288_DDR506112002KQ(CHIPS)':
 'DQS3_B_C': CDS_PINID='DQS3_B_C';
NET_NAME
'M_A_CPU0_SB_DQS_DN<4>'
 '@T6G_MB_LIB.T6G(SCH_1):M_A_CPU0_SB_DQS_DN'<4>:
 C_SIGNAL='@t6g_mb_lib.t6g(sch_1):m_a_cpu0_sb_dqs_dn(4)';
NODE_NAME     U25 BW73
 '@T6G_MB_LIB.T6G(SCH_1):PAGE10_I200@PURE_QUANTA.GENOA_SP5(CHIPS)':
 'MAB_DQS_L4': CDS_PINID='MAB_DQS_L4';
NODE_NAME     J1 238
 '@T6G_MB_LIB.T6G(SCH_1):PAGE85_I537@PURE_QUANTA.SCONN288_DDR506112002KQ(CHIPS)':
 'DQS4_B_C': CDS_PINID='DQS4_B_C';
NET_NAME
'M_A_CPU0_SB_DQS_DN<5>'
 '@T6G_MB_LIB.T6G(SCH_1):M_A_CPU0_SB_DQS_DN'<5>:
 C_SIGNAL='@t6g_mb_lib.t6g(sch_1):m_a_cpu0_sb_dqs_dn(5)';
NODE_NAME     U25 CE73
 '@T6G_MB_LIB.T6G(SCH_1):PAGE10_I200@PURE_QUANTA.GENOA_SP5(CHIPS)':
 'MAB_DQS_L5': CDS_PINID='MAB_DQS_L5';
NODE_NAME     J1 249
 '@T6G_MB_LIB.T6G(SCH_1):PAGE85_I537@PURE_QUANTA.SCONN288_DDR506112002KQ(CHIPS)':
 'DQS5_B_C||TDQS5_B_C': CDS_PINID='\dqs5_b_c||tdqs5_b_c\';
NET_NAME
'M_A_CPU0_SB_DQS_DN<6>'
 '@T6G_MB_LIB.T6G(SCH_1):M_A_CPU0_SB_DQS_DN'<6>:
 C_SIGNAL='@t6g_mb_lib.t6g(sch_1):m_a_cpu0_sb_dqs_dn(6)';
NODE_NAME     U25 CL73
 '@T6G_MB_LIB.T6G(SCH_1):PAGE10_I200@PURE_QUANTA.GENOA_SP5(CHIPS)':
 'MAB_DQS_L6': CDS_PINID='MAB_DQS_L6';
NODE_NAME     J1 260
 '@T6G_MB_LIB.T6G(SCH_1):PAGE85_I537@PURE_QUANTA.SCONN288_DDR506112002KQ(CHIPS)':
 'DQS6_B_C||TDQS6_B_C': CDS_PINID='\dqs6_b_c||tdqs6_b_c\';
NET_NAME
'M_A_CPU0_SB_DQS_DN<7>'
 '@T6G_MB_LIB.T6G(SCH_1):M_A_CPU0_SB_DQS_DN'<7>:
 C_SIGNAL='@t6g_mb_lib.t6g(sch_1):m_a_cpu0_sb_dqs_dn(7)';
NODE_NAME     U25 CU73
 '@T6G_MB_LIB.T6G(SCH_1):PAGE10_I200@PURE_QUANTA.GENOA_SP5(CHIPS)':
 'MAB_DQS_L7': CDS_PINID='MAB_DQS_L7';
NODE_NAME     J1 271
 '@T6G_MB_LIB.T6G(SCH_1):PAGE85_I537@PURE_QUANTA.SCONN288_DDR506112002KQ(CHIPS)':
 'DQS7_B_C||TDQS7_B_C': CDS_PINID='\dqs7_b_c||tdqs7_b_c\';
NET_NAME
'M_A_CPU0_SB_DQS_DN<8>'
 '@T6G_MB_LIB.T6G(SCH_1):M_A_CPU0_SB_DQS_DN'<8>:
 C_SIGNAL='@t6g_mb_lib.t6g(sch_1):m_a_cpu0_sb_dqs_dn(8)';
NODE_NAME     U25 DC73
 '@T6G_MB_LIB.T6G(SCH_1):PAGE10_I200@PURE_QUANTA.GENOA_SP5(CHIPS)':
 'MAB_DQS_L8': CDS_PINID='MAB_DQS_L8';
NODE_NAME     J1 282
 '@T6G_MB_LIB.T6G(SCH_1):PAGE85_I537@PURE_QUANTA.SCONN288_DDR506112002KQ(CHIPS)':
 'DQS8_B_C||TDQS8_B_C': CDS_PINID='\dqs8_b_c||tdqs8_b_c\';
NET_NAME
'M_A_CPU0_SB_DQS_DN<9>'
 '@T6G_MB_LIB.T6G(SCH_1):M_A_CPU0_SB_DQS_DN'<9>:
 C_SIGNAL='@t6g_mb_lib.t6g(sch_1):m_a_cpu0_sb_dqs_dn(9)';
NODE_NAME     U25 BW74
 '@T6G_MB_LIB.T6G(SCH_1):PAGE10_I200@PURE_QUANTA.GENOA_SP5(CHIPS)':
 'MAB_DQS_L9': CDS_PINID='MAB_DQS_L9';
NODE_NAME     J1 94
 '@T6G_MB_LIB.T6G(SCH_1):PAGE85_I537@PURE_QUANTA.SCONN288_DDR506112002KQ(CHIPS)':
 'DQS9_B_C||TDQS9_B_C': CDS_PINID='\dqs9_b_c||tdqs9_b_c\';
NET_NAME
'M_A_CPU0_SB_DQS_DP<0>'
 '@T6G_MB_LIB.T6G(SCH_1):M_A_CPU0_SB_DQS_DP'<0>:
 C_SIGNAL='@t6g_mb_lib.t6g(sch_1):m_a_cpu0_sb_dqs_dp(0)';
NODE_NAME     U25 CD74
 '@T6G_MB_LIB.T6G(SCH_1):PAGE10_I200@PURE_QUANTA.GENOA_SP5(CHIPS)':
 'MAB_DQS_H0': CDS_PINID='MAB_DQS_H0';
NODE_NAME     J1 104
 '@T6G_MB_LIB.T6G(SCH_1):PAGE85_I537@PURE_QUANTA.SCONN288_DDR506112002KQ(CHIPS)':
 'DQS0_B_T': CDS_PINID='DQS0_B_T';
NET_NAME
'M_A_CPU0_SB_DQS_DP<1>'
 '@T6G_MB_LIB.T6G(SCH_1):M_A_CPU0_SB_DQS_DP'<1>:
 C_SIGNAL='@t6g_mb_lib.t6g(sch_1):m_a_cpu0_sb_dqs_dp(1)';
NODE_NAME     U25 CK74
 '@T6G_MB_LIB.T6G(SCH_1):PAGE10_I200@PURE_QUANTA.GENOA_SP5(CHIPS)':
 'MAB_DQS_H1': CDS_PINID='MAB_DQS_H1';
NODE_NAME     J1 115
 '@T6G_MB_LIB.T6G(SCH_1):PAGE85_I537@PURE_QUANTA.SCONN288_DDR506112002KQ(CHIPS)':
 'DQS1_B_T': CDS_PINID='DQS1_B_T';
NET_NAME
'M_A_CPU0_SB_DQS_DP<2>'
 '@T6G_MB_LIB.T6G(SCH_1):M_A_CPU0_SB_DQS_DP'<2>:
 C_SIGNAL='@t6g_mb_lib.t6g(sch_1):m_a_cpu0_sb_dqs_dp(2)';
NODE_NAME     U25 CT74
 '@T6G_MB_LIB.T6G(SCH_1):PAGE10_I200@PURE_QUANTA.GENOA_SP5(CHIPS)':
 'MAB_DQS_H2': CDS_PINID='MAB_DQS_H2';
NODE_NAME     J1 126
 '@T6G_MB_LIB.T6G(SCH_1):PAGE85_I537@PURE_QUANTA.SCONN288_DDR506112002KQ(CHIPS)':
 'DQS2_B_T': CDS_PINID='DQS2_B_T';
NET_NAME
'M_A_CPU0_SB_DQS_DP<3>'
 '@T6G_MB_LIB.T6G(SCH_1):M_A_CPU0_SB_DQS_DP'<3>:
 C_SIGNAL='@t6g_mb_lib.t6g(sch_1):m_a_cpu0_sb_dqs_dp(3)';
NODE_NAME     U25 DB74
 '@T6G_MB_LIB.T6G(SCH_1):PAGE10_I200@PURE_QUANTA.GENOA_SP5(CHIPS)':
 'MAB_DQS_H3': CDS_PINID='MAB_DQS_H3';
NODE_NAME     J1 137
 '@T6G_MB_LIB.T6G(SCH_1):PAGE85_I537@PURE_QUANTA.SCONN288_DDR506112002KQ(CHIPS)':
 'DQS3_B_T': CDS_PINID='DQS3_B_T';
NET_NAME
'M_A_CPU0_SB_DQS_DP<4>'
 '@T6G_MB_LIB.T6G(SCH_1):M_A_CPU0_SB_DQS_DP'<4>:
 C_SIGNAL='@t6g_mb_lib.t6g(sch_1):m_a_cpu0_sb_dqs_dp(4)';
NODE_NAME     U25 BY72
 '@T6G_MB_LIB.T6G(SCH_1):PAGE10_I200@PURE_QUANTA.GENOA_SP5(CHIPS)':
 'MAB_DQS_H4': CDS_PINID='MAB_DQS_H4';
NODE_NAME     J1 239
 '@T6G_MB_LIB.T6G(SCH_1):PAGE85_I537@PURE_QUANTA.SCONN288_DDR506112002KQ(CHIPS)':
 'DQS4_B_T': CDS_PINID='DQS4_B_T';
NET_NAME
'M_A_CPU0_SB_DQS_DP<5>'
 '@T6G_MB_LIB.T6G(SCH_1):M_A_CPU0_SB_DQS_DP'<5>:
 C_SIGNAL='@t6g_mb_lib.t6g(sch_1):m_a_cpu0_sb_dqs_dp(5)';
NODE_NAME     U25 CF72
 '@T6G_MB_LIB.T6G(SCH_1):PAGE10_I200@PURE_QUANTA.GENOA_SP5(CHIPS)':
 'MAB_DQS_H5': CDS_PINID='MAB_DQS_H5';
NODE_NAME     J1 250
 '@T6G_MB_LIB.T6G(SCH_1):PAGE85_I537@PURE_QUANTA.SCONN288_DDR506112002KQ(CHIPS)':
 'DQS5_B_T||TDQS5_B_T': CDS_PINID='\dqs5_b_t||tdqs5_b_t\';
NET_NAME
'M_A_CPU0_SB_DQS_DP<6>'
 '@T6G_MB_LIB.T6G(SCH_1):M_A_CPU0_SB_DQS_DP'<6>:
 C_SIGNAL='@t6g_mb_lib.t6g(sch_1):m_a_cpu0_sb_dqs_dp(6)';
NODE_NAME     U25 CM72
 '@T6G_MB_LIB.T6G(SCH_1):PAGE10_I200@PURE_QUANTA.GENOA_SP5(CHIPS)':
 'MAB_DQS_H6': CDS_PINID='MAB_DQS_H6';
NODE_NAME     J1 261
 '@T6G_MB_LIB.T6G(SCH_1):PAGE85_I537@PURE_QUANTA.SCONN288_DDR506112002KQ(CHIPS)':
 'DQS6_B_T||TDQS6_B_T': CDS_PINID='\dqs6_b_t||tdqs6_b_t\';
NET_NAME
'M_A_CPU0_SB_DQS_DP<7>'
 '@T6G_MB_LIB.T6G(SCH_1):M_A_CPU0_SB_DQS_DP'<7>:
 C_SIGNAL='@t6g_mb_lib.t6g(sch_1):m_a_cpu0_sb_dqs_dp(7)';
NODE_NAME     U25 CV72
 '@T6G_MB_LIB.T6G(SCH_1):PAGE10_I200@PURE_QUANTA.GENOA_SP5(CHIPS)':
 'MAB_DQS_H7': CDS_PINID='MAB_DQS_H7';
NODE_NAME     J1 272
 '@T6G_MB_LIB.T6G(SCH_1):PAGE85_I537@PURE_QUANTA.SCONN288_DDR506112002KQ(CHIPS)':
 'DQS7_B_T||TDQS7_B_T': CDS_PINID='\dqs7_b_t||tdqs7_b_t\';
NET_NAME
'M_A_CPU0_SB_DQS_DP<8>'
 '@T6G_MB_LIB.T6G(SCH_1):M_A_CPU0_SB_DQS_DP'<8>:
 C_SIGNAL='@t6g_mb_lib.t6g(sch_1):m_a_cpu0_sb_dqs_dp(8)';
NODE_NAME     U25 DD72
 '@T6G_MB_LIB.T6G(SCH_1):PAGE10_I200@PURE_QUANTA.GENOA_SP5(CHIPS)':
 'MAB_DQS_H8': CDS_PINID='MAB_DQS_H8';
NODE_NAME     J1 283
 '@T6G_MB_LIB.T6G(SCH_1):PAGE85_I537@PURE_QUANTA.SCONN288_DDR506112002KQ(CHIPS)':
 'DQS8_B_T||TDQS8_B_T': CDS_PINID='\dqs8_b_t||tdqs8_b_t\';
NET_NAME
'M_A_CPU0_SB_DQS_DP<9>'
 '@T6G_MB_LIB.T6G(SCH_1):M_A_CPU0_SB_DQS_DP'<9>:
 C_SIGNAL='@t6g_mb_lib.t6g(sch_1):m_a_cpu0_sb_dqs_dp(9)';
NODE_NAME     U25 BV74
 '@T6G_MB_LIB.T6G(SCH_1):PAGE10_I200@PURE_QUANTA.GENOA_SP5(CHIPS)':
 'MAB_DQS_H9': CDS_PINID='MAB_DQS_H9';
NODE_NAME     J1 93
 '@T6G_MB_LIB.T6G(SCH_1):PAGE85_I537@PURE_QUANTA.SCONN288_DDR506112002KQ(CHIPS)':
 'DQS9_B_T||TDQS9_B_T||DBI4_B_N': CDS_PINID='\dqs9_b_t||tdqs9_b_t||dbi4_b_n\';
NET_NAME
'M_A_CPU0_SB_PAR'
 '@T6G_MB_LIB.T6G(SCH_1):M_A_CPU0_SB_PAR':
 C_SIGNAL='@t6g_mb_lib.t6g(sch_1):m_a_cpu0_sb_par';
NODE_NAME     U25 BL74
 '@T6G_MB_LIB.T6G(SCH_1):PAGE10_I200@PURE_QUANTA.GENOA_SP5(CHIPS)':
 'MAB_PAR': CDS_PINID='MAB_PAR';
NODE_NAME     J1 227
 '@T6G_MB_LIB.T6G(SCH_1):PAGE85_I536@PURE_QUANTA.SCONN288_DDR506112002KQ(CHIPS)':
 'PAR_B': CDS_PINID='PAR_B';
NET_NAME
'M_A_CPU0_SB_RSP<0>'
 '@T6G_MB_LIB.T6G(SCH_1):M_A_CPU0_SB_RSP'<0>:
 C_SIGNAL='@t6g_mb_lib.t6g(sch_1):m_a_cpu0_sb_rsp(0)';
NODE_NAME     U25 BP74
 '@T6G_MB_LIB.T6G(SCH_1):PAGE10_I200@PURE_QUANTA.GENOA_SP5(CHIPS)':
 'MAB0_RSP_L': CDS_PINID='MAB0_RSP_L';
NODE_NAME     J1 87
 '@T6G_MB_LIB.T6G(SCH_1):PAGE85_I536@PURE_QUANTA.SCONN288_DDR506112002KQ(CHIPS)':
 'LBS||RSP_B_N': CDS_PINID='\lbs||rsp_b_n\';
NET_NAME
'M_A_CPU1_ALERT_N'
 '@T6G_MB_LIB.T6G(SCH_1):M_A_CPU1_ALERT_N':
 C_SIGNAL='@t6g_mb_lib.t6g(sch_1):m_a_cpu1_alert_n';
NODE_NAME     R500 1
 '@T6G_MB_LIB.T6G(SCH_1):PAGE37_I322@PURE_QUANTA.Q_RES(CHIPS)':
 'A': CDS_PINID='A';
NODE_NAME     J24 62
 '@T6G_MB_LIB.T6G(SCH_1):PAGE97_I22@PURE_QUANTA.SCONN288_DDR506112002KQ(CHIPS)':
 'ALERT_N': CDS_PINID='ALERT_N';
NET_NAME
'M_A_CPU1_ALERT_R_N'
 '@T6G_MB_LIB.T6G(SCH_1):M_A_CPU1_ALERT_R_N':
 C_SIGNAL='@t6g_mb_lib.t6g(sch_1):m_a_cpu1_alert_r_n';
NODE_NAME     U26 AR74
 '@T6G_MB_LIB.T6G(SCH_1):PAGE37_I167@PURE_QUANTA.GENOA_SP5(CHIPS)':
 'MA_ALERT_L': CDS_PINID='MA_ALERT_L';
NODE_NAME     R500 2
 '@T6G_MB_LIB.T6G(SCH_1):PAGE37_I322@PURE_QUANTA.Q_RES(CHIPS)':
 'B': CDS_PINID='B';
NET_NAME
'M_A_CPU1_CLK_DN<0>'
 '@T6G_MB_LIB.T6G(SCH_1):M_A_CPU1_CLK_DN'<0>:
 C_SIGNAL='@t6g_mb_lib.t6g(sch_1):m_a_cpu1_clk_dn(0)';
NODE_NAME     U26 BD74
 '@T6G_MB_LIB.T6G(SCH_1):PAGE37_I167@PURE_QUANTA.GENOA_SP5(CHIPS)':
 'MA0_CLK_L': CDS_PINID='MA0_CLK_L';
NODE_NAME     J24 218
 '@T6G_MB_LIB.T6G(SCH_1):PAGE97_I22@PURE_QUANTA.SCONN288_DDR506112002KQ(CHIPS)':
 'CK_C': CDS_PINID='CK_C';
NET_NAME
'M_A_CPU1_CLK_DP<0>'
 '@T6G_MB_LIB.T6G(SCH_1):M_A_CPU1_CLK_DP'<0>:
 C_SIGNAL='@t6g_mb_lib.t6g(sch_1):m_a_cpu1_clk_dp(0)';
NODE_NAME     U26 BC74
 '@T6G_MB_LIB.T6G(SCH_1):PAGE37_I167@PURE_QUANTA.GENOA_SP5(CHIPS)':
 'MA0_CLK_H': CDS_PINID='MA0_CLK_H';
NODE_NAME     J24 217
 '@T6G_MB_LIB.T6G(SCH_1):PAGE97_I22@PURE_QUANTA.SCONN288_DDR506112002KQ(CHIPS)':
 'CK_T': CDS_PINID='CK_T';
NET_NAME
'M_A_CPU1_RESET_N'
 '@T6G_MB_LIB.T6G(SCH_1):M_A_CPU1_RESET_N':
 C_SIGNAL='@t6g_mb_lib.t6g(sch_1):m_a_cpu1_reset_n';
NODE_NAME     U26 AT74
 '@T6G_MB_LIB.T6G(SCH_1):PAGE37_I167@PURE_QUANTA.GENOA_SP5(CHIPS)':
 'MA_RESET_L': CDS_PINID='MA_RESET_L';
NODE_NAME     J24 207
 '@T6G_MB_LIB.T6G(SCH_1):PAGE97_I22@PURE_QUANTA.SCONN288_DDR506112002KQ(CHIPS)':
 'RESET_N': CDS_PINID='RESET_N';
NET_NAME
'M_A_CPU1_SA_CA<0>'
 '@T6G_MB_LIB.T6G(SCH_1):M_A_CPU1_SA_CA'<0>:
 C_SIGNAL='@t6g_mb_lib.t6g(sch_1):m_a_cpu1_sa_ca(0)';
NODE_NAME     U26 AW74
 '@T6G_MB_LIB.T6G(SCH_1):PAGE37_I167@PURE_QUANTA.GENOA_SP5(CHIPS)':
 'MAA_CA0': CDS_PINID='MAA_CA0';
NODE_NAME     J24 66
 '@T6G_MB_LIB.T6G(SCH_1):PAGE97_I22@PURE_QUANTA.SCONN288_DDR506112002KQ(CHIPS)':
 'CA0_A': CDS_PINID='CA0_A';
NET_NAME
'M_A_CPU1_SA_CA<1>'
 '@T6G_MB_LIB.T6G(SCH_1):M_A_CPU1_SA_CA'<1>:
 C_SIGNAL='@t6g_mb_lib.t6g(sch_1):m_a_cpu1_sa_ca(1)';
NODE_NAME     U26 AY74
 '@T6G_MB_LIB.T6G(SCH_1):PAGE37_I167@PURE_QUANTA.GENOA_SP5(CHIPS)':
 'MAA_CA1': CDS_PINID='MAA_CA1';
NODE_NAME     J24 211
 '@T6G_MB_LIB.T6G(SCH_1):PAGE97_I22@PURE_QUANTA.SCONN288_DDR506112002KQ(CHIPS)':
 'CA1_A': CDS_PINID='CA1_A';
NET_NAME
'M_A_CPU1_SA_CA<2>'
 '@T6G_MB_LIB.T6G(SCH_1):M_A_CPU1_SA_CA'<2>:
 C_SIGNAL='@t6g_mb_lib.t6g(sch_1):m_a_cpu1_sa_ca(2)';
NODE_NAME     U26 AY72
 '@T6G_MB_LIB.T6G(SCH_1):PAGE37_I167@PURE_QUANTA.GENOA_SP5(CHIPS)':
 'MAA_CA2': CDS_PINID='MAA_CA2';
NODE_NAME     J24 68
 '@T6G_MB_LIB.T6G(SCH_1):PAGE97_I22@PURE_QUANTA.SCONN288_DDR506112002KQ(CHIPS)':
 'CA2_A': CDS_PINID='CA2_A';
NET_NAME
'M_A_CPU1_SA_CA<3>'
 '@T6G_MB_LIB.T6G(SCH_1):M_A_CPU1_SA_CA'<3>:
 C_SIGNAL='@t6g_mb_lib.t6g(sch_1):m_a_cpu1_sa_ca(3)';
NODE_NAME     U26 BA73
 '@T6G_MB_LIB.T6G(SCH_1):PAGE37_I167@PURE_QUANTA.GENOA_SP5(CHIPS)':
 'MAA_CA3': CDS_PINID='MAA_CA3';
NODE_NAME     J24 213
 '@T6G_MB_LIB.T6G(SCH_1):PAGE97_I22@PURE_QUANTA.SCONN288_DDR506112002KQ(CHIPS)':
 'CA3_A': CDS_PINID='CA3_A';
NET_NAME
'M_A_CPU1_SA_CA<4>'
 '@T6G_MB_LIB.T6G(SCH_1):M_A_CPU1_SA_CA'<4>:
 C_SIGNAL='@t6g_mb_lib.t6g(sch_1):m_a_cpu1_sa_ca(4)';
NODE_NAME     U26 BA74
 '@T6G_MB_LIB.T6G(SCH_1):PAGE37_I167@PURE_QUANTA.GENOA_SP5(CHIPS)':
 'MAA_CA4': CDS_PINID='MAA_CA4';
NODE_NAME     J24 70
 '@T6G_MB_LIB.T6G(SCH_1):PAGE97_I22@PURE_QUANTA.SCONN288_DDR506112002KQ(CHIPS)':
 'CA4_A': CDS_PINID='CA4_A';
NET_NAME
'M_A_CPU1_SA_CA<5>'
 '@T6G_MB_LIB.T6G(SCH_1):M_A_CPU1_SA_CA'<5>:
 C_SIGNAL='@t6g_mb_lib.t6g(sch_1):m_a_cpu1_sa_ca(5)';
NODE_NAME     U26 BB74
 '@T6G_MB_LIB.T6G(SCH_1):PAGE37_I167@PURE_QUANTA.GENOA_SP5(CHIPS)':
 'MAA_CA5': CDS_PINID='MAA_CA5';
NODE_NAME     J24 215
 '@T6G_MB_LIB.T6G(SCH_1):PAGE97_I22@PURE_QUANTA.SCONN288_DDR506112002KQ(CHIPS)':
 'CA5_A': CDS_PINID='CA5_A';
NET_NAME
'M_A_CPU1_SA_CA<6>'
 '@T6G_MB_LIB.T6G(SCH_1):M_A_CPU1_SA_CA'<6>:
 C_SIGNAL='@t6g_mb_lib.t6g(sch_1):m_a_cpu1_sa_ca(6)';
NODE_NAME     U26 BB72
 '@T6G_MB_LIB.T6G(SCH_1):PAGE37_I167@PURE_QUANTA.GENOA_SP5(CHIPS)':
 'MAA_CA6': CDS_PINID='MAA_CA6';
NODE_NAME     J24 72
 '@T6G_MB_LIB.T6G(SCH_1):PAGE97_I22@PURE_QUANTA.SCONN288_DDR506112002KQ(CHIPS)':
 'CA6_A': CDS_PINID='CA6_A';
NET_NAME
'M_A_CPU1_SA_CB<0>'
 '@T6G_MB_LIB.T6G(SCH_1):M_A_CPU1_SA_CB'<0>:
 C_SIGNAL='@t6g_mb_lib.t6g(sch_1):m_a_cpu1_sa_cb(0)';
NODE_NAME     U26 AJ74
 '@T6G_MB_LIB.T6G(SCH_1):PAGE37_I167@PURE_QUANTA.GENOA_SP5(CHIPS)':
 'MAA_CHECK0': CDS_PINID='MAA_CHECK0';
NODE_NAME     J24 51
 '@T6G_MB_LIB.T6G(SCH_1):PAGE97_I22@PURE_QUANTA.SCONN288_DDR506112002KQ(CHIPS)':
 'CB0_A': CDS_PINID='CB0_A';
NET_NAME
'M_A_CPU1_SA_CB<1>'
 '@T6G_MB_LIB.T6G(SCH_1):M_A_CPU1_SA_CB'<1>:
 C_SIGNAL='@t6g_mb_lib.t6g(sch_1):m_a_cpu1_sa_cb(1)';
NODE_NAME     U26 AK72
 '@T6G_MB_LIB.T6G(SCH_1):PAGE37_I167@PURE_QUANTA.GENOA_SP5(CHIPS)':
 'MAA_CHECK1': CDS_PINID='MAA_CHECK1';
NODE_NAME     J24 53
 '@T6G_MB_LIB.T6G(SCH_1):PAGE97_I22@PURE_QUANTA.SCONN288_DDR506112002KQ(CHIPS)':
 'CB1_A': CDS_PINID='CB1_A';
NET_NAME
'M_A_CPU1_SA_CB<2>'
 '@T6G_MB_LIB.T6G(SCH_1):M_A_CPU1_SA_CB'<2>:
 C_SIGNAL='@t6g_mb_lib.t6g(sch_1):m_a_cpu1_sa_cb(2)';
NODE_NAME     U26 AK74
 '@T6G_MB_LIB.T6G(SCH_1):PAGE37_I167@PURE_QUANTA.GENOA_SP5(CHIPS)':
 'MAA_CHECK2': CDS_PINID='MAA_CHECK2';
NODE_NAME     J24 196
 '@T6G_MB_LIB.T6G(SCH_1):PAGE97_I22@PURE_QUANTA.SCONN288_DDR506112002KQ(CHIPS)':
 'CB2_A': CDS_PINID='CB2_A';
NET_NAME
'M_A_CPU1_SA_CB<3>'
 '@T6G_MB_LIB.T6G(SCH_1):M_A_CPU1_SA_CB'<3>:
 C_SIGNAL='@t6g_mb_lib.t6g(sch_1):m_a_cpu1_sa_cb(3)';
NODE_NAME     U26 AL73
 '@T6G_MB_LIB.T6G(SCH_1):PAGE37_I167@PURE_QUANTA.GENOA_SP5(CHIPS)':
 'MAA_CHECK3': CDS_PINID='MAA_CHECK3';
NODE_NAME     J24 198
 '@T6G_MB_LIB.T6G(SCH_1):PAGE97_I22@PURE_QUANTA.SCONN288_DDR506112002KQ(CHIPS)':
 'CB3_A': CDS_PINID='CB3_A';
NET_NAME
'M_A_CPU1_SA_CB<4>'
 '@T6G_MB_LIB.T6G(SCH_1):M_A_CPU1_SA_CB'<4>:
 C_SIGNAL='@t6g_mb_lib.t6g(sch_1):m_a_cpu1_sa_cb(4)';
NODE_NAME     U26 AN74
 '@T6G_MB_LIB.T6G(SCH_1):PAGE37_I167@PURE_QUANTA.GENOA_SP5(CHIPS)':
 'MAA_CHECK4': CDS_PINID='MAA_CHECK4';
NODE_NAME     J24 58
 '@T6G_MB_LIB.T6G(SCH_1):PAGE97_I22@PURE_QUANTA.SCONN288_DDR506112002KQ(CHIPS)':
 'CB4_A': CDS_PINID='CB4_A';
NET_NAME
'M_A_CPU1_SA_CB<5>'
 '@T6G_MB_LIB.T6G(SCH_1):M_A_CPU1_SA_CB'<5>:
 C_SIGNAL='@t6g_mb_lib.t6g(sch_1):m_a_cpu1_sa_cb(5)';
NODE_NAME     U26 AP72
 '@T6G_MB_LIB.T6G(SCH_1):PAGE37_I167@PURE_QUANTA.GENOA_SP5(CHIPS)':
 'MAA_CHECK5': CDS_PINID='MAA_CHECK5';
NODE_NAME     J24 60
 '@T6G_MB_LIB.T6G(SCH_1):PAGE97_I22@PURE_QUANTA.SCONN288_DDR506112002KQ(CHIPS)':
 'CB5_A': CDS_PINID='CB5_A';
NET_NAME
'M_A_CPU1_SA_CB<6>'
 '@T6G_MB_LIB.T6G(SCH_1):M_A_CPU1_SA_CB'<6>:
 C_SIGNAL='@t6g_mb_lib.t6g(sch_1):m_a_cpu1_sa_cb(6)';
NODE_NAME     U26 AP74
 '@T6G_MB_LIB.T6G(SCH_1):PAGE37_I167@PURE_QUANTA.GENOA_SP5(CHIPS)':
 'MAA_CHECK6': CDS_PINID='MAA_CHECK6';
NODE_NAME     J24 203
 '@T6G_MB_LIB.T6G(SCH_1):PAGE97_I22@PURE_QUANTA.SCONN288_DDR506112002KQ(CHIPS)':
 'CB6_A': CDS_PINID='CB6_A';
NET_NAME
'M_A_CPU1_SA_CB<7>'
 '@T6G_MB_LIB.T6G(SCH_1):M_A_CPU1_SA_CB'<7>:
 C_SIGNAL='@t6g_mb_lib.t6g(sch_1):m_a_cpu1_sa_cb(7)';
NODE_NAME     U26 AR73
 '@T6G_MB_LIB.T6G(SCH_1):PAGE37_I167@PURE_QUANTA.GENOA_SP5(CHIPS)':
 'MAA_CHECK7': CDS_PINID='MAA_CHECK7';
NODE_NAME     J24 205
 '@T6G_MB_LIB.T6G(SCH_1):PAGE97_I22@PURE_QUANTA.SCONN288_DDR506112002KQ(CHIPS)':
 'CB7_A': CDS_PINID='CB7_A';
NET_NAME
'M_A_CPU1_SA_CS_N<0>'
 '@T6G_MB_LIB.T6G(SCH_1):M_A_CPU1_SA_CS_N'<0>:
 C_SIGNAL='@t6g_mb_lib.t6g(sch_1):m_a_cpu1_sa_cs_n(0)';
NODE_NAME     U26 AV74
 '@T6G_MB_LIB.T6G(SCH_1):PAGE37_I167@PURE_QUANTA.GENOA_SP5(CHIPS)':
 'MAA0_CS_L0': CDS_PINID='MAA0_CS_L0';
NODE_NAME     J24 64
 '@T6G_MB_LIB.T6G(SCH_1):PAGE97_I22@PURE_QUANTA.SCONN288_DDR506112002KQ(CHIPS)':
 'CS0_A_N': CDS_PINID='CS0_A_N';
NET_NAME
'M_A_CPU1_SA_CS_N<1>'
 '@T6G_MB_LIB.T6G(SCH_1):M_A_CPU1_SA_CS_N'<1>:
 C_SIGNAL='@t6g_mb_lib.t6g(sch_1):m_a_cpu1_sa_cs_n(1)';
NODE_NAME     U26 AW73
 '@T6G_MB_LIB.T6G(SCH_1):PAGE37_I167@PURE_QUANTA.GENOA_SP5(CHIPS)':
 'MAA0_CS_L1': CDS_PINID='MAA0_CS_L1';
NODE_NAME     J24 209
 '@T6G_MB_LIB.T6G(SCH_1):PAGE97_I22@PURE_QUANTA.SCONN288_DDR506112002KQ(CHIPS)':
 'CS1_A_N': CDS_PINID='CS1_A_N';
NET_NAME
'M_A_CPU1_SA_DQ<0>'
 '@T6G_MB_LIB.T6G(SCH_1):M_A_CPU1_SA_DQ'<0>:
 C_SIGNAL='@t6g_mb_lib.t6g(sch_1):m_a_cpu1_sa_dq(0)';
NODE_NAME     U26 E74
 '@T6G_MB_LIB.T6G(SCH_1):PAGE37_I167@PURE_QUANTA.GENOA_SP5(CHIPS)':
 'MAA_DATA0': CDS_PINID='MAA_DATA0';
NODE_NAME     J24 7
 '@T6G_MB_LIB.T6G(SCH_1):PAGE97_I22@PURE_QUANTA.SCONN288_DDR506112002KQ(CHIPS)':
 'DQ0_A': CDS_PINID='DQ0_A';
NET_NAME
'M_A_CPU1_SA_DQ<10>'
 '@T6G_MB_LIB.T6G(SCH_1):M_A_CPU1_SA_DQ'<10>:
 C_SIGNAL='@t6g_mb_lib.t6g(sch_1):m_a_cpu1_sa_dq(10)';
NODE_NAME     U26 M74
 '@T6G_MB_LIB.T6G(SCH_1):PAGE37_I167@PURE_QUANTA.GENOA_SP5(CHIPS)':
 'MAA_DATA10': CDS_PINID='MAA_DATA10';
NODE_NAME     J24 163
 '@T6G_MB_LIB.T6G(SCH_1):PAGE97_I22@PURE_QUANTA.SCONN288_DDR506112002KQ(CHIPS)':
 'DQ10_A': CDS_PINID='DQ10_A';
NET_NAME
'M_A_CPU1_SA_DQ<11>'
 '@T6G_MB_LIB.T6G(SCH_1):M_A_CPU1_SA_DQ'<11>:
 C_SIGNAL='@t6g_mb_lib.t6g(sch_1):m_a_cpu1_sa_dq(11)';
NODE_NAME     U26 N73
 '@T6G_MB_LIB.T6G(SCH_1):PAGE37_I167@PURE_QUANTA.GENOA_SP5(CHIPS)':
 'MAA_DATA11': CDS_PINID='MAA_DATA11';
NODE_NAME     J24 165
 '@T6G_MB_LIB.T6G(SCH_1):PAGE97_I22@PURE_QUANTA.SCONN288_DDR506112002KQ(CHIPS)':
 'DQ11_A': CDS_PINID='DQ11_A';
NET_NAME
'M_A_CPU1_SA_DQ<12>'
 '@T6G_MB_LIB.T6G(SCH_1):M_A_CPU1_SA_DQ'<12>:
 C_SIGNAL='@t6g_mb_lib.t6g(sch_1):m_a_cpu1_sa_dq(12)';
NODE_NAME     U26 R74
 '@T6G_MB_LIB.T6G(SCH_1):PAGE37_I167@PURE_QUANTA.GENOA_SP5(CHIPS)':
 'MAA_DATA12': CDS_PINID='MAA_DATA12';
NODE_NAME     J24 25
 '@T6G_MB_LIB.T6G(SCH_1):PAGE97_I22@PURE_QUANTA.SCONN288_DDR506112002KQ(CHIPS)':
 'DQ12_A': CDS_PINID='DQ12_A';
NET_NAME
'M_A_CPU1_SA_DQ<13>'
 '@T6G_MB_LIB.T6G(SCH_1):M_A_CPU1_SA_DQ'<13>:
 C_SIGNAL='@t6g_mb_lib.t6g(sch_1):m_a_cpu1_sa_dq(13)';
NODE_NAME     U26 T72
 '@T6G_MB_LIB.T6G(SCH_1):PAGE37_I167@PURE_QUANTA.GENOA_SP5(CHIPS)':
 'MAA_DATA13': CDS_PINID='MAA_DATA13';
NODE_NAME     J24 27
 '@T6G_MB_LIB.T6G(SCH_1):PAGE97_I22@PURE_QUANTA.SCONN288_DDR506112002KQ(CHIPS)':
 'DQ13_A': CDS_PINID='DQ13_A';
NET_NAME
'M_A_CPU1_SA_DQ<14>'
 '@T6G_MB_LIB.T6G(SCH_1):M_A_CPU1_SA_DQ'<14>:
 C_SIGNAL='@t6g_mb_lib.t6g(sch_1):m_a_cpu1_sa_dq(14)';
NODE_NAME     U26 T74
 '@T6G_MB_LIB.T6G(SCH_1):PAGE37_I167@PURE_QUANTA.GENOA_SP5(CHIPS)':
 'MAA_DATA14': CDS_PINID='MAA_DATA14';
NODE_NAME     J24 170
 '@T6G_MB_LIB.T6G(SCH_1):PAGE97_I22@PURE_QUANTA.SCONN288_DDR506112002KQ(CHIPS)':
 'DQ14_A': CDS_PINID='DQ14_A';
NET_NAME
'M_A_CPU1_SA_DQ<15>'
 '@T6G_MB_LIB.T6G(SCH_1):M_A_CPU1_SA_DQ'<15>:
 C_SIGNAL='@t6g_mb_lib.t6g(sch_1):m_a_cpu1_sa_dq(15)';
NODE_NAME     U26 U73
 '@T6G_MB_LIB.T6G(SCH_1):PAGE37_I167@PURE_QUANTA.GENOA_SP5(CHIPS)':
 'MAA_DATA15': CDS_PINID='MAA_DATA15';
NODE_NAME     J24 172
 '@T6G_MB_LIB.T6G(SCH_1):PAGE97_I22@PURE_QUANTA.SCONN288_DDR506112002KQ(CHIPS)':
 'DQ15_A': CDS_PINID='DQ15_A';
NET_NAME
'M_A_CPU1_SA_DQ<16>'
 '@T6G_MB_LIB.T6G(SCH_1):M_A_CPU1_SA_DQ'<16>:
 C_SIGNAL='@t6g_mb_lib.t6g(sch_1):m_a_cpu1_sa_dq(16)';
NODE_NAME     U26 U74
 '@T6G_MB_LIB.T6G(SCH_1):PAGE37_I167@PURE_QUANTA.GENOA_SP5(CHIPS)':
 'MAA_DATA16': CDS_PINID='MAA_DATA16';
NODE_NAME     J24 29
 '@T6G_MB_LIB.T6G(SCH_1):PAGE97_I22@PURE_QUANTA.SCONN288_DDR506112002KQ(CHIPS)':
 'DQ16_A': CDS_PINID='DQ16_A';
NET_NAME
'M_A_CPU1_SA_DQ<17>'
 '@T6G_MB_LIB.T6G(SCH_1):M_A_CPU1_SA_DQ'<17>:
 C_SIGNAL='@t6g_mb_lib.t6g(sch_1):m_a_cpu1_sa_dq(17)';
NODE_NAME     U26 V72
 '@T6G_MB_LIB.T6G(SCH_1):PAGE37_I167@PURE_QUANTA.GENOA_SP5(CHIPS)':
 'MAA_DATA17': CDS_PINID='MAA_DATA17';
NODE_NAME     J24 31
 '@T6G_MB_LIB.T6G(SCH_1):PAGE97_I22@PURE_QUANTA.SCONN288_DDR506112002KQ(CHIPS)':
 'DQ17_A': CDS_PINID='DQ17_A';
NET_NAME
'M_A_CPU1_SA_DQ<18>'
 '@T6G_MB_LIB.T6G(SCH_1):M_A_CPU1_SA_DQ'<18>:
 C_SIGNAL='@t6g_mb_lib.t6g(sch_1):m_a_cpu1_sa_dq(18)';
NODE_NAME     U26 V74
 '@T6G_MB_LIB.T6G(SCH_1):PAGE37_I167@PURE_QUANTA.GENOA_SP5(CHIPS)':
 'MAA_DATA18': CDS_PINID='MAA_DATA18';
NODE_NAME     J24 174
 '@T6G_MB_LIB.T6G(SCH_1):PAGE97_I22@PURE_QUANTA.SCONN288_DDR506112002KQ(CHIPS)':
 'DQ18_A': CDS_PINID='DQ18_A';
NET_NAME
'M_A_CPU1_SA_DQ<19>'
 '@T6G_MB_LIB.T6G(SCH_1):M_A_CPU1_SA_DQ'<19>:
 C_SIGNAL='@t6g_mb_lib.t6g(sch_1):m_a_cpu1_sa_dq(19)';
NODE_NAME     U26 W73
 '@T6G_MB_LIB.T6G(SCH_1):PAGE37_I167@PURE_QUANTA.GENOA_SP5(CHIPS)':
 'MAA_DATA19': CDS_PINID='MAA_DATA19';
NODE_NAME     J24 176
 '@T6G_MB_LIB.T6G(SCH_1):PAGE97_I22@PURE_QUANTA.SCONN288_DDR506112002KQ(CHIPS)':
 'DQ19_A': CDS_PINID='DQ19_A';
NET_NAME
'M_A_CPU1_SA_DQ<1>'
 '@T6G_MB_LIB.T6G(SCH_1):M_A_CPU1_SA_DQ'<1>:
 C_SIGNAL='@t6g_mb_lib.t6g(sch_1):m_a_cpu1_sa_dq(1)';
NODE_NAME     U26 F72
 '@T6G_MB_LIB.T6G(SCH_1):PAGE37_I167@PURE_QUANTA.GENOA_SP5(CHIPS)':
 'MAA_DATA1': CDS_PINID='MAA_DATA1';
NODE_NAME     J24 9
 '@T6G_MB_LIB.T6G(SCH_1):PAGE97_I22@PURE_QUANTA.SCONN288_DDR506112002KQ(CHIPS)':
 'DQ1_A': CDS_PINID='DQ1_A';
NET_NAME
'M_A_CPU1_SA_DQ<20>'
 '@T6G_MB_LIB.T6G(SCH_1):M_A_CPU1_SA_DQ'<20>:
 C_SIGNAL='@t6g_mb_lib.t6g(sch_1):m_a_cpu1_sa_dq(20)';
NODE_NAME     U26 AA74
 '@T6G_MB_LIB.T6G(SCH_1):PAGE37_I167@PURE_QUANTA.GENOA_SP5(CHIPS)':
 'MAA_DATA20': CDS_PINID='MAA_DATA20';
NODE_NAME     J24 36
 '@T6G_MB_LIB.T6G(SCH_1):PAGE97_I22@PURE_QUANTA.SCONN288_DDR506112002KQ(CHIPS)':
 'DQ20_A': CDS_PINID='DQ20_A';
NET_NAME
'M_A_CPU1_SA_DQ<21>'
 '@T6G_MB_LIB.T6G(SCH_1):M_A_CPU1_SA_DQ'<21>:
 C_SIGNAL='@t6g_mb_lib.t6g(sch_1):m_a_cpu1_sa_dq(21)';
NODE_NAME     U26 AB72
 '@T6G_MB_LIB.T6G(SCH_1):PAGE37_I167@PURE_QUANTA.GENOA_SP5(CHIPS)':
 'MAA_DATA21': CDS_PINID='MAA_DATA21';
NODE_NAME     J24 38
 '@T6G_MB_LIB.T6G(SCH_1):PAGE97_I22@PURE_QUANTA.SCONN288_DDR506112002KQ(CHIPS)':
 'DQ21_A': CDS_PINID='DQ21_A';
NET_NAME
'M_A_CPU1_SA_DQ<22>'
 '@T6G_MB_LIB.T6G(SCH_1):M_A_CPU1_SA_DQ'<22>:
 C_SIGNAL='@t6g_mb_lib.t6g(sch_1):m_a_cpu1_sa_dq(22)';
NODE_NAME     U26 AB74
 '@T6G_MB_LIB.T6G(SCH_1):PAGE37_I167@PURE_QUANTA.GENOA_SP5(CHIPS)':
 'MAA_DATA22': CDS_PINID='MAA_DATA22';
NODE_NAME     J24 181
 '@T6G_MB_LIB.T6G(SCH_1):PAGE97_I22@PURE_QUANTA.SCONN288_DDR506112002KQ(CHIPS)':
 'DQ22_A': CDS_PINID='DQ22_A';
NET_NAME
'M_A_CPU1_SA_DQ<23>'
 '@T6G_MB_LIB.T6G(SCH_1):M_A_CPU1_SA_DQ'<23>:
 C_SIGNAL='@t6g_mb_lib.t6g(sch_1):m_a_cpu1_sa_dq(23)';
NODE_NAME     U26 AC73
 '@T6G_MB_LIB.T6G(SCH_1):PAGE37_I167@PURE_QUANTA.GENOA_SP5(CHIPS)':
 'MAA_DATA23': CDS_PINID='MAA_DATA23';
NODE_NAME     J24 183
 '@T6G_MB_LIB.T6G(SCH_1):PAGE97_I22@PURE_QUANTA.SCONN288_DDR506112002KQ(CHIPS)':
 'DQ23_A': CDS_PINID='DQ23_A';
NET_NAME
'M_A_CPU1_SA_DQ<24>'
 '@T6G_MB_LIB.T6G(SCH_1):M_A_CPU1_SA_DQ'<24>:
 C_SIGNAL='@t6g_mb_lib.t6g(sch_1):m_a_cpu1_sa_dq(24)';
NODE_NAME     U26 AC74
 '@T6G_MB_LIB.T6G(SCH_1):PAGE37_I167@PURE_QUANTA.GENOA_SP5(CHIPS)':
 'MAA_DATA24': CDS_PINID='MAA_DATA24';
NODE_NAME     J24 40
 '@T6G_MB_LIB.T6G(SCH_1):PAGE97_I22@PURE_QUANTA.SCONN288_DDR506112002KQ(CHIPS)':
 'DQ24_A': CDS_PINID='DQ24_A';
NET_NAME
'M_A_CPU1_SA_DQ<25>'
 '@T6G_MB_LIB.T6G(SCH_1):M_A_CPU1_SA_DQ'<25>:
 C_SIGNAL='@t6g_mb_lib.t6g(sch_1):m_a_cpu1_sa_dq(25)';
NODE_NAME     U26 AD72
 '@T6G_MB_LIB.T6G(SCH_1):PAGE37_I167@PURE_QUANTA.GENOA_SP5(CHIPS)':
 'MAA_DATA25': CDS_PINID='MAA_DATA25';
NODE_NAME     J24 42
 '@T6G_MB_LIB.T6G(SCH_1):PAGE97_I22@PURE_QUANTA.SCONN288_DDR506112002KQ(CHIPS)':
 'DQ25_A': CDS_PINID='DQ25_A';
NET_NAME
'M_A_CPU1_SA_DQ<26>'
 '@T6G_MB_LIB.T6G(SCH_1):M_A_CPU1_SA_DQ'<26>:
 C_SIGNAL='@t6g_mb_lib.t6g(sch_1):m_a_cpu1_sa_dq(26)';
NODE_NAME     U26 AD74
 '@T6G_MB_LIB.T6G(SCH_1):PAGE37_I167@PURE_QUANTA.GENOA_SP5(CHIPS)':
 'MAA_DATA26': CDS_PINID='MAA_DATA26';
NODE_NAME     J24 185
 '@T6G_MB_LIB.T6G(SCH_1):PAGE97_I22@PURE_QUANTA.SCONN288_DDR506112002KQ(CHIPS)':
 'DQ26_A': CDS_PINID='DQ26_A';
NET_NAME
'M_A_CPU1_SA_DQ<27>'
 '@T6G_MB_LIB.T6G(SCH_1):M_A_CPU1_SA_DQ'<27>:
 C_SIGNAL='@t6g_mb_lib.t6g(sch_1):m_a_cpu1_sa_dq(27)';
NODE_NAME     U26 AE73
 '@T6G_MB_LIB.T6G(SCH_1):PAGE37_I167@PURE_QUANTA.GENOA_SP5(CHIPS)':
 'MAA_DATA27': CDS_PINID='MAA_DATA27';
NODE_NAME     J24 187
 '@T6G_MB_LIB.T6G(SCH_1):PAGE97_I22@PURE_QUANTA.SCONN288_DDR506112002KQ(CHIPS)':
 'DQ27_A': CDS_PINID='DQ27_A';
NET_NAME
'M_A_CPU1_SA_DQ<28>'
 '@T6G_MB_LIB.T6G(SCH_1):M_A_CPU1_SA_DQ'<28>:
 C_SIGNAL='@t6g_mb_lib.t6g(sch_1):m_a_cpu1_sa_dq(28)';
NODE_NAME     U26 AG74
 '@T6G_MB_LIB.T6G(SCH_1):PAGE37_I167@PURE_QUANTA.GENOA_SP5(CHIPS)':
 'MAA_DATA28': CDS_PINID='MAA_DATA28';
NODE_NAME     J24 47
 '@T6G_MB_LIB.T6G(SCH_1):PAGE97_I22@PURE_QUANTA.SCONN288_DDR506112002KQ(CHIPS)':
 'DQ28_A': CDS_PINID='DQ28_A';
NET_NAME
'M_A_CPU1_SA_DQ<29>'
 '@T6G_MB_LIB.T6G(SCH_1):M_A_CPU1_SA_DQ'<29>:
 C_SIGNAL='@t6g_mb_lib.t6g(sch_1):m_a_cpu1_sa_dq(29)';
NODE_NAME     U26 AH72
 '@T6G_MB_LIB.T6G(SCH_1):PAGE37_I167@PURE_QUANTA.GENOA_SP5(CHIPS)':
 'MAA_DATA29': CDS_PINID='MAA_DATA29';
NODE_NAME     J24 49
 '@T6G_MB_LIB.T6G(SCH_1):PAGE97_I22@PURE_QUANTA.SCONN288_DDR506112002KQ(CHIPS)':
 'DQ29_A': CDS_PINID='DQ29_A';
NET_NAME
'M_A_CPU1_SA_DQ<2>'
 '@T6G_MB_LIB.T6G(SCH_1):M_A_CPU1_SA_DQ'<2>:
 C_SIGNAL='@t6g_mb_lib.t6g(sch_1):m_a_cpu1_sa_dq(2)';
NODE_NAME     U26 F74
 '@T6G_MB_LIB.T6G(SCH_1):PAGE37_I167@PURE_QUANTA.GENOA_SP5(CHIPS)':
 'MAA_DATA2': CDS_PINID='MAA_DATA2';
NODE_NAME     J24 152
 '@T6G_MB_LIB.T6G(SCH_1):PAGE97_I22@PURE_QUANTA.SCONN288_DDR506112002KQ(CHIPS)':
 'DQ2_A': CDS_PINID='DQ2_A';
NET_NAME
'M_A_CPU1_SA_DQ<30>'
 '@T6G_MB_LIB.T6G(SCH_1):M_A_CPU1_SA_DQ'<30>:
 C_SIGNAL='@t6g_mb_lib.t6g(sch_1):m_a_cpu1_sa_dq(30)';
NODE_NAME     U26 AH74
 '@T6G_MB_LIB.T6G(SCH_1):PAGE37_I167@PURE_QUANTA.GENOA_SP5(CHIPS)':
 'MAA_DATA30': CDS_PINID='MAA_DATA30';
NODE_NAME     J24 192
 '@T6G_MB_LIB.T6G(SCH_1):PAGE97_I22@PURE_QUANTA.SCONN288_DDR506112002KQ(CHIPS)':
 'DQ30_A': CDS_PINID='DQ30_A';
NET_NAME
'M_A_CPU1_SA_DQ<31>'
 '@T6G_MB_LIB.T6G(SCH_1):M_A_CPU1_SA_DQ'<31>:
 C_SIGNAL='@t6g_mb_lib.t6g(sch_1):m_a_cpu1_sa_dq(31)';
NODE_NAME     U26 AJ73
 '@T6G_MB_LIB.T6G(SCH_1):PAGE37_I167@PURE_QUANTA.GENOA_SP5(CHIPS)':
 'MAA_DATA31': CDS_PINID='MAA_DATA31';
NODE_NAME     J24 194
 '@T6G_MB_LIB.T6G(SCH_1):PAGE97_I22@PURE_QUANTA.SCONN288_DDR506112002KQ(CHIPS)':
 'DQ31_A': CDS_PINID='DQ31_A';
NET_NAME
'M_A_CPU1_SA_DQ<3>'
 '@T6G_MB_LIB.T6G(SCH_1):M_A_CPU1_SA_DQ'<3>:
 C_SIGNAL='@t6g_mb_lib.t6g(sch_1):m_a_cpu1_sa_dq(3)';
NODE_NAME     U26 G73
 '@T6G_MB_LIB.T6G(SCH_1):PAGE37_I167@PURE_QUANTA.GENOA_SP5(CHIPS)':
 'MAA_DATA3': CDS_PINID='MAA_DATA3';
NODE_NAME     J24 154
 '@T6G_MB_LIB.T6G(SCH_1):PAGE97_I22@PURE_QUANTA.SCONN288_DDR506112002KQ(CHIPS)':
 'DQ3_A': CDS_PINID='DQ3_A';
NET_NAME
'M_A_CPU1_SA_DQ<4>'
 '@T6G_MB_LIB.T6G(SCH_1):M_A_CPU1_SA_DQ'<4>:
 C_SIGNAL='@t6g_mb_lib.t6g(sch_1):m_a_cpu1_sa_dq(4)';
NODE_NAME     U26 J74
 '@T6G_MB_LIB.T6G(SCH_1):PAGE37_I167@PURE_QUANTA.GENOA_SP5(CHIPS)':
 'MAA_DATA4': CDS_PINID='MAA_DATA4';
NODE_NAME     J24 14
 '@T6G_MB_LIB.T6G(SCH_1):PAGE97_I22@PURE_QUANTA.SCONN288_DDR506112002KQ(CHIPS)':
 'DQ4_A': CDS_PINID='DQ4_A';
NET_NAME
'M_A_CPU1_SA_DQ<5>'
 '@T6G_MB_LIB.T6G(SCH_1):M_A_CPU1_SA_DQ'<5>:
 C_SIGNAL='@t6g_mb_lib.t6g(sch_1):m_a_cpu1_sa_dq(5)';
NODE_NAME     U26 K72
 '@T6G_MB_LIB.T6G(SCH_1):PAGE37_I167@PURE_QUANTA.GENOA_SP5(CHIPS)':
 'MAA_DATA5': CDS_PINID='MAA_DATA5';
NODE_NAME     J24 16
 '@T6G_MB_LIB.T6G(SCH_1):PAGE97_I22@PURE_QUANTA.SCONN288_DDR506112002KQ(CHIPS)':
 'DQ5_A': CDS_PINID='DQ5_A';
NET_NAME
'M_A_CPU1_SA_DQ<6>'
 '@T6G_MB_LIB.T6G(SCH_1):M_A_CPU1_SA_DQ'<6>:
 C_SIGNAL='@t6g_mb_lib.t6g(sch_1):m_a_cpu1_sa_dq(6)';
NODE_NAME     U26 K74
 '@T6G_MB_LIB.T6G(SCH_1):PAGE37_I167@PURE_QUANTA.GENOA_SP5(CHIPS)':
 'MAA_DATA6': CDS_PINID='MAA_DATA6';
NODE_NAME     J24 159
 '@T6G_MB_LIB.T6G(SCH_1):PAGE97_I22@PURE_QUANTA.SCONN288_DDR506112002KQ(CHIPS)':
 'DQ6_A': CDS_PINID='DQ6_A';
NET_NAME
'M_A_CPU1_SA_DQ<7>'
 '@T6G_MB_LIB.T6G(SCH_1):M_A_CPU1_SA_DQ'<7>:
 C_SIGNAL='@t6g_mb_lib.t6g(sch_1):m_a_cpu1_sa_dq(7)';
NODE_NAME     U26 L73
 '@T6G_MB_LIB.T6G(SCH_1):PAGE37_I167@PURE_QUANTA.GENOA_SP5(CHIPS)':
 'MAA_DATA7': CDS_PINID='MAA_DATA7';
NODE_NAME     J24 161
 '@T6G_MB_LIB.T6G(SCH_1):PAGE97_I22@PURE_QUANTA.SCONN288_DDR506112002KQ(CHIPS)':
 'DQ7_A': CDS_PINID='DQ7_A';
NET_NAME
'M_A_CPU1_SA_DQ<8>'
 '@T6G_MB_LIB.T6G(SCH_1):M_A_CPU1_SA_DQ'<8>:
 C_SIGNAL='@t6g_mb_lib.t6g(sch_1):m_a_cpu1_sa_dq(8)';
NODE_NAME     U26 L74
 '@T6G_MB_LIB.T6G(SCH_1):PAGE37_I167@PURE_QUANTA.GENOA_SP5(CHIPS)':
 'MAA_DATA8': CDS_PINID='MAA_DATA8';
NODE_NAME     J24 18
 '@T6G_MB_LIB.T6G(SCH_1):PAGE97_I22@PURE_QUANTA.SCONN288_DDR506112002KQ(CHIPS)':
 'DQ8_A': CDS_PINID='DQ8_A';
NET_NAME
'M_A_CPU1_SA_DQ<9>'
 '@T6G_MB_LIB.T6G(SCH_1):M_A_CPU1_SA_DQ'<9>:
 C_SIGNAL='@t6g_mb_lib.t6g(sch_1):m_a_cpu1_sa_dq(9)';
NODE_NAME     U26 M72
 '@T6G_MB_LIB.T6G(SCH_1):PAGE37_I167@PURE_QUANTA.GENOA_SP5(CHIPS)':
 'MAA_DATA9': CDS_PINID='MAA_DATA9';
NODE_NAME     J24 20
 '@T6G_MB_LIB.T6G(SCH_1):PAGE97_I22@PURE_QUANTA.SCONN288_DDR506112002KQ(CHIPS)':
 'DQ9_A': CDS_PINID='DQ9_A';
NET_NAME
'M_A_CPU1_SA_DQS_DN<0>'
 '@T6G_MB_LIB.T6G(SCH_1):M_A_CPU1_SA_DQS_DN'<0>:
 C_SIGNAL='@t6g_mb_lib.t6g(sch_1):m_a_cpu1_sa_dqs_dn(0)';
NODE_NAME     U26 H74
 '@T6G_MB_LIB.T6G(SCH_1):PAGE37_I167@PURE_QUANTA.GENOA_SP5(CHIPS)':
 'MAA_DQS_L0': CDS_PINID='MAA_DQS_L0';
NODE_NAME     J24 12
 '@T6G_MB_LIB.T6G(SCH_1):PAGE97_I238@PURE_QUANTA.SCONN288_DDR506112002KQ(CHIPS)':
 'DQS0_A_C': CDS_PINID='DQS0_A_C';
NET_NAME
'M_A_CPU1_SA_DQS_DN<1>'
 '@T6G_MB_LIB.T6G(SCH_1):M_A_CPU1_SA_DQS_DN'<1>:
 C_SIGNAL='@t6g_mb_lib.t6g(sch_1):m_a_cpu1_sa_dqs_dn(1)';
NODE_NAME     U26 P74
 '@T6G_MB_LIB.T6G(SCH_1):PAGE37_I167@PURE_QUANTA.GENOA_SP5(CHIPS)':
 'MAA_DQS_L1': CDS_PINID='MAA_DQS_L1';
NODE_NAME     J24 23
 '@T6G_MB_LIB.T6G(SCH_1):PAGE97_I238@PURE_QUANTA.SCONN288_DDR506112002KQ(CHIPS)':
 'DQS1_A_C': CDS_PINID='DQS1_A_C';
NET_NAME
'M_A_CPU1_SA_DQS_DN<2>'
 '@T6G_MB_LIB.T6G(SCH_1):M_A_CPU1_SA_DQS_DN'<2>:
 C_SIGNAL='@t6g_mb_lib.t6g(sch_1):m_a_cpu1_sa_dqs_dn(2)';
NODE_NAME     U26 Y74
 '@T6G_MB_LIB.T6G(SCH_1):PAGE37_I167@PURE_QUANTA.GENOA_SP5(CHIPS)':
 'MAA_DQS_L2': CDS_PINID='MAA_DQS_L2';
NODE_NAME     J24 34
 '@T6G_MB_LIB.T6G(SCH_1):PAGE97_I238@PURE_QUANTA.SCONN288_DDR506112002KQ(CHIPS)':
 'DQS2_A_C': CDS_PINID='DQS2_A_C';
NET_NAME
'M_A_CPU1_SA_DQS_DN<3>'
 '@T6G_MB_LIB.T6G(SCH_1):M_A_CPU1_SA_DQS_DN'<3>:
 C_SIGNAL='@t6g_mb_lib.t6g(sch_1):m_a_cpu1_sa_dqs_dn(3)';
NODE_NAME     U26 AF74
 '@T6G_MB_LIB.T6G(SCH_1):PAGE37_I167@PURE_QUANTA.GENOA_SP5(CHIPS)':
 'MAA_DQS_L3': CDS_PINID='MAA_DQS_L3';
NODE_NAME     J24 45
 '@T6G_MB_LIB.T6G(SCH_1):PAGE97_I238@PURE_QUANTA.SCONN288_DDR506112002KQ(CHIPS)':
 'DQS3_A_C': CDS_PINID='DQS3_A_C';
NET_NAME
'M_A_CPU1_SA_DQS_DN<4>'
 '@T6G_MB_LIB.T6G(SCH_1):M_A_CPU1_SA_DQS_DN'<4>:
 C_SIGNAL='@t6g_mb_lib.t6g(sch_1):m_a_cpu1_sa_dqs_dn(4)';
NODE_NAME     U26 AM74
 '@T6G_MB_LIB.T6G(SCH_1):PAGE37_I167@PURE_QUANTA.GENOA_SP5(CHIPS)':
 'MAA_DQS_L4': CDS_PINID='MAA_DQS_L4';
NODE_NAME     J24 56
 '@T6G_MB_LIB.T6G(SCH_1):PAGE97_I238@PURE_QUANTA.SCONN288_DDR506112002KQ(CHIPS)':
 'DQS4_A_C': CDS_PINID='DQS4_A_C';
NET_NAME
'M_A_CPU1_SA_DQS_DN<5>'
 '@T6G_MB_LIB.T6G(SCH_1):M_A_CPU1_SA_DQS_DN'<5>:
 C_SIGNAL='@t6g_mb_lib.t6g(sch_1):m_a_cpu1_sa_dqs_dn(5)';
NODE_NAME     U26 H72
 '@T6G_MB_LIB.T6G(SCH_1):PAGE37_I167@PURE_QUANTA.GENOA_SP5(CHIPS)':
 'MAA_DQS_L5': CDS_PINID='MAA_DQS_L5';
NODE_NAME     J24 156
 '@T6G_MB_LIB.T6G(SCH_1):PAGE97_I238@PURE_QUANTA.SCONN288_DDR506112002KQ(CHIPS)':
 'DQS5_A_C||TDQS5_A_C||DQS5_A_T||TDQS5_A_T': CDS_PINID='\dqs5_a_c||tdqs5_a_c||dqs5_a_t||tdqs5_a_t\';
NET_NAME
'M_A_CPU1_SA_DQS_DN<6>'
 '@T6G_MB_LIB.T6G(SCH_1):M_A_CPU1_SA_DQS_DN'<6>:
 C_SIGNAL='@t6g_mb_lib.t6g(sch_1):m_a_cpu1_sa_dqs_dn(6)';
NODE_NAME     U26 P72
 '@T6G_MB_LIB.T6G(SCH_1):PAGE37_I167@PURE_QUANTA.GENOA_SP5(CHIPS)':
 'MAA_DQS_L6': CDS_PINID='MAA_DQS_L6';
NODE_NAME     J24 167
 '@T6G_MB_LIB.T6G(SCH_1):PAGE97_I238@PURE_QUANTA.SCONN288_DDR506112002KQ(CHIPS)':
 'DQS6_A_C||TDQS6_A_C||DQS6_A_T||TDQS6_A_T': CDS_PINID='\dqs6_a_c||tdqs6_a_c||dqs6_a_t||tdqs6_a_t\';
NET_NAME
'M_A_CPU1_SA_DQS_DN<7>'
 '@T6G_MB_LIB.T6G(SCH_1):M_A_CPU1_SA_DQS_DN'<7>:
 C_SIGNAL='@t6g_mb_lib.t6g(sch_1):m_a_cpu1_sa_dqs_dn(7)';
NODE_NAME     U26 Y72
 '@T6G_MB_LIB.T6G(SCH_1):PAGE37_I167@PURE_QUANTA.GENOA_SP5(CHIPS)':
 'MAA_DQS_L7': CDS_PINID='MAA_DQS_L7';
NODE_NAME     J24 178
 '@T6G_MB_LIB.T6G(SCH_1):PAGE97_I238@PURE_QUANTA.SCONN288_DDR506112002KQ(CHIPS)':
 'DQS7_A_C||TDQS7_A_C': CDS_PINID='\dqs7_a_c||tdqs7_a_c\';
NET_NAME
'M_A_CPU1_SA_DQS_DN<8>'
 '@T6G_MB_LIB.T6G(SCH_1):M_A_CPU1_SA_DQS_DN'<8>:
 C_SIGNAL='@t6g_mb_lib.t6g(sch_1):m_a_cpu1_sa_dqs_dn(8)';
NODE_NAME     U26 AF72
 '@T6G_MB_LIB.T6G(SCH_1):PAGE37_I167@PURE_QUANTA.GENOA_SP5(CHIPS)':
 'MAA_DQS_L8': CDS_PINID='MAA_DQS_L8';
NODE_NAME     J24 189
 '@T6G_MB_LIB.T6G(SCH_1):PAGE97_I238@PURE_QUANTA.SCONN288_DDR506112002KQ(CHIPS)':
 'DQS8_A_C||TDQS8_A_C': CDS_PINID='\dqs8_a_c||tdqs8_a_c\';
NET_NAME
'M_A_CPU1_SA_DQS_DN<9>'
 '@T6G_MB_LIB.T6G(SCH_1):M_A_CPU1_SA_DQS_DN'<9>:
 C_SIGNAL='@t6g_mb_lib.t6g(sch_1):m_a_cpu1_sa_dqs_dn(9)';
NODE_NAME     U26 AM72
 '@T6G_MB_LIB.T6G(SCH_1):PAGE37_I167@PURE_QUANTA.GENOA_SP5(CHIPS)':
 'MAA_DQS_L9': CDS_PINID='MAA_DQS_L9';
NODE_NAME     J24 200
 '@T6G_MB_LIB.T6G(SCH_1):PAGE97_I238@PURE_QUANTA.SCONN288_DDR506112002KQ(CHIPS)':
 'DQS9_A_C||TDQS9_A_C': CDS_PINID='\dqs9_a_c||tdqs9_a_c\';
NET_NAME
'M_A_CPU1_SA_DQS_DP<0>'
 '@T6G_MB_LIB.T6G(SCH_1):M_A_CPU1_SA_DQS_DP'<0>:
 C_SIGNAL='@t6g_mb_lib.t6g(sch_1):m_a_cpu1_sa_dqs_dp(0)';
NODE_NAME     U26 G74
 '@T6G_MB_LIB.T6G(SCH_1):PAGE37_I167@PURE_QUANTA.GENOA_SP5(CHIPS)':
 'MAA_DQS_H0': CDS_PINID='MAA_DQS_H0';
NODE_NAME     J24 11
 '@T6G_MB_LIB.T6G(SCH_1):PAGE97_I238@PURE_QUANTA.SCONN288_DDR506112002KQ(CHIPS)':
 'DQS0_A_T': CDS_PINID='DQS0_A_T';
NET_NAME
'M_A_CPU1_SA_DQS_DP<1>'
 '@T6G_MB_LIB.T6G(SCH_1):M_A_CPU1_SA_DQS_DP'<1>:
 C_SIGNAL='@t6g_mb_lib.t6g(sch_1):m_a_cpu1_sa_dqs_dp(1)';
NODE_NAME     U26 N74
 '@T6G_MB_LIB.T6G(SCH_1):PAGE37_I167@PURE_QUANTA.GENOA_SP5(CHIPS)':
 'MAA_DQS_H1': CDS_PINID='MAA_DQS_H1';
NODE_NAME     J24 22
 '@T6G_MB_LIB.T6G(SCH_1):PAGE97_I238@PURE_QUANTA.SCONN288_DDR506112002KQ(CHIPS)':
 'DQS1_A_T': CDS_PINID='DQS1_A_T';
NET_NAME
'M_A_CPU1_SA_DQS_DP<2>'
 '@T6G_MB_LIB.T6G(SCH_1):M_A_CPU1_SA_DQS_DP'<2>:
 C_SIGNAL='@t6g_mb_lib.t6g(sch_1):m_a_cpu1_sa_dqs_dp(2)';
NODE_NAME     U26 W74
 '@T6G_MB_LIB.T6G(SCH_1):PAGE37_I167@PURE_QUANTA.GENOA_SP5(CHIPS)':
 'MAA_DQS_H2': CDS_PINID='MAA_DQS_H2';
NODE_NAME     J24 33
 '@T6G_MB_LIB.T6G(SCH_1):PAGE97_I238@PURE_QUANTA.SCONN288_DDR506112002KQ(CHIPS)':
 'DQS2_A_T': CDS_PINID='DQS2_A_T';
NET_NAME
'M_A_CPU1_SA_DQS_DP<3>'
 '@T6G_MB_LIB.T6G(SCH_1):M_A_CPU1_SA_DQS_DP'<3>:
 C_SIGNAL='@t6g_mb_lib.t6g(sch_1):m_a_cpu1_sa_dqs_dp(3)';
NODE_NAME     U26 AE74
 '@T6G_MB_LIB.T6G(SCH_1):PAGE37_I167@PURE_QUANTA.GENOA_SP5(CHIPS)':
 'MAA_DQS_H3': CDS_PINID='MAA_DQS_H3';
NODE_NAME     J24 44
 '@T6G_MB_LIB.T6G(SCH_1):PAGE97_I238@PURE_QUANTA.SCONN288_DDR506112002KQ(CHIPS)':
 'DQS3_A_T': CDS_PINID='DQS3_A_T';
NET_NAME
'M_A_CPU1_SA_DQS_DP<4>'
 '@T6G_MB_LIB.T6G(SCH_1):M_A_CPU1_SA_DQS_DP'<4>:
 C_SIGNAL='@t6g_mb_lib.t6g(sch_1):m_a_cpu1_sa_dqs_dp(4)';
NODE_NAME     U26 AL74
 '@T6G_MB_LIB.T6G(SCH_1):PAGE37_I167@PURE_QUANTA.GENOA_SP5(CHIPS)':
 'MAA_DQS_H4': CDS_PINID='MAA_DQS_H4';
NODE_NAME     J24 55
 '@T6G_MB_LIB.T6G(SCH_1):PAGE97_I238@PURE_QUANTA.SCONN288_DDR506112002KQ(CHIPS)':
 'DQS4_A_T': CDS_PINID='DQS4_A_T';
NET_NAME
'M_A_CPU1_SA_DQS_DP<5>'
 '@T6G_MB_LIB.T6G(SCH_1):M_A_CPU1_SA_DQS_DP'<5>:
 C_SIGNAL='@t6g_mb_lib.t6g(sch_1):m_a_cpu1_sa_dqs_dp(5)';
NODE_NAME     U26 J73
 '@T6G_MB_LIB.T6G(SCH_1):PAGE37_I167@PURE_QUANTA.GENOA_SP5(CHIPS)':
 'MAA_DQS_H5': CDS_PINID='MAA_DQS_H5';
NODE_NAME     J24 157
 '@T6G_MB_LIB.T6G(SCH_1):PAGE97_I238@PURE_QUANTA.SCONN288_DDR506112002KQ(CHIPS)':
 'DQS5_A_T||TDQS5_A_T': CDS_PINID='\dqs5_a_t||tdqs5_a_t\';
NET_NAME
'M_A_CPU1_SA_DQS_DP<6>'
 '@T6G_MB_LIB.T6G(SCH_1):M_A_CPU1_SA_DQS_DP'<6>:
 C_SIGNAL='@t6g_mb_lib.t6g(sch_1):m_a_cpu1_sa_dqs_dp(6)';
NODE_NAME     U26 R73
 '@T6G_MB_LIB.T6G(SCH_1):PAGE37_I167@PURE_QUANTA.GENOA_SP5(CHIPS)':
 'MAA_DQS_H6': CDS_PINID='MAA_DQS_H6';
NODE_NAME     J24 168
 '@T6G_MB_LIB.T6G(SCH_1):PAGE97_I238@PURE_QUANTA.SCONN288_DDR506112002KQ(CHIPS)':
 'DQS6_A_T||TDQS6_A_T': CDS_PINID='\dqs6_a_t||tdqs6_a_t\';
NET_NAME
'M_A_CPU1_SA_DQS_DP<7>'
 '@T6G_MB_LIB.T6G(SCH_1):M_A_CPU1_SA_DQS_DP'<7>:
 C_SIGNAL='@t6g_mb_lib.t6g(sch_1):m_a_cpu1_sa_dqs_dp(7)';
NODE_NAME     U26 AA73
 '@T6G_MB_LIB.T6G(SCH_1):PAGE37_I167@PURE_QUANTA.GENOA_SP5(CHIPS)':
 'MAA_DQS_H7': CDS_PINID='MAA_DQS_H7';
NODE_NAME     J24 179
 '@T6G_MB_LIB.T6G(SCH_1):PAGE97_I238@PURE_QUANTA.SCONN288_DDR506112002KQ(CHIPS)':
 'DQS7_A_T||TDQS7_A_T': CDS_PINID='\dqs7_a_t||tdqs7_a_t\';
NET_NAME
'M_A_CPU1_SA_DQS_DP<8>'
 '@T6G_MB_LIB.T6G(SCH_1):M_A_CPU1_SA_DQS_DP'<8>:
 C_SIGNAL='@t6g_mb_lib.t6g(sch_1):m_a_cpu1_sa_dqs_dp(8)';
NODE_NAME     U26 AG73
 '@T6G_MB_LIB.T6G(SCH_1):PAGE37_I167@PURE_QUANTA.GENOA_SP5(CHIPS)':
 'MAA_DQS_H8': CDS_PINID='MAA_DQS_H8';
NODE_NAME     J24 190
 '@T6G_MB_LIB.T6G(SCH_1):PAGE97_I238@PURE_QUANTA.SCONN288_DDR506112002KQ(CHIPS)':
 'DQS8_A_T||TDQS8_A_T': CDS_PINID='\dqs8_a_t||tdqs8_a_t\';
NET_NAME
'M_A_CPU1_SA_DQS_DP<9>'
 '@T6G_MB_LIB.T6G(SCH_1):M_A_CPU1_SA_DQS_DP'<9>:
 C_SIGNAL='@t6g_mb_lib.t6g(sch_1):m_a_cpu1_sa_dqs_dp(9)';
NODE_NAME     U26 AN73
 '@T6G_MB_LIB.T6G(SCH_1):PAGE37_I167@PURE_QUANTA.GENOA_SP5(CHIPS)':
 'MAA_DQS_H9': CDS_PINID='MAA_DQS_H9';
NODE_NAME     J24 201
 '@T6G_MB_LIB.T6G(SCH_1):PAGE97_I238@PURE_QUANTA.SCONN288_DDR506112002KQ(CHIPS)':
 'DQS9_A_T||TDQS9_A_T': CDS_PINID='\dqs9_a_t||tdqs9_a_t\';
NET_NAME
'M_A_CPU1_SA_PAR'
 '@T6G_MB_LIB.T6G(SCH_1):M_A_CPU1_SA_PAR':
 C_SIGNAL='@t6g_mb_lib.t6g(sch_1):m_a_cpu1_sa_par';
NODE_NAME     U26 BC73
 '@T6G_MB_LIB.T6G(SCH_1):PAGE37_I167@PURE_QUANTA.GENOA_SP5(CHIPS)':
 'MAA_PAR': CDS_PINID='MAA_PAR';
NODE_NAME     J24 74
 '@T6G_MB_LIB.T6G(SCH_1):PAGE97_I22@PURE_QUANTA.SCONN288_DDR506112002KQ(CHIPS)':
 'PAR_A': CDS_PINID='PAR_A';
NET_NAME
'M_A_CPU1_SA_RSP<0>'
 '@T6G_MB_LIB.T6G(SCH_1):M_A_CPU1_SA_RSP'<0>:
 C_SIGNAL='@t6g_mb_lib.t6g(sch_1):m_a_cpu1_sa_rsp(0)';
NODE_NAME     U26 BN73
 '@T6G_MB_LIB.T6G(SCH_1):PAGE37_I167@PURE_QUANTA.GENOA_SP5(CHIPS)':
 'MAA0_RSP_L': CDS_PINID='MAA0_RSP_L';
NODE_NAME     J24 86
 '@T6G_MB_LIB.T6G(SCH_1):PAGE97_I22@PURE_QUANTA.SCONN288_DDR506112002KQ(CHIPS)':
 'LBD||RSP_A_N': CDS_PINID='\lbd||rsp_a_n\';
NET_NAME
'M_A_CPU1_SB_CA<0>'
 '@T6G_MB_LIB.T6G(SCH_1):M_A_CPU1_SB_CA'<0>:
 C_SIGNAL='@t6g_mb_lib.t6g(sch_1):m_a_cpu1_sb_ca(0)';
NODE_NAME     U26 BG73
 '@T6G_MB_LIB.T6G(SCH_1):PAGE37_I167@PURE_QUANTA.GENOA_SP5(CHIPS)':
 'MAB_CA0': CDS_PINID='MAB_CA0';
NODE_NAME     J24 76
 '@T6G_MB_LIB.T6G(SCH_1):PAGE97_I22@PURE_QUANTA.SCONN288_DDR506112002KQ(CHIPS)':
 'CA0_B': CDS_PINID='CA0_B';
NET_NAME
'M_A_CPU1_SB_CA<1>'
 '@T6G_MB_LIB.T6G(SCH_1):M_A_CPU1_SB_CA'<1>:
 C_SIGNAL='@t6g_mb_lib.t6g(sch_1):m_a_cpu1_sb_ca(1)';
NODE_NAME     U26 BH72
 '@T6G_MB_LIB.T6G(SCH_1):PAGE37_I167@PURE_QUANTA.GENOA_SP5(CHIPS)':
 'MAB_CA1': CDS_PINID='MAB_CA1';
NODE_NAME     J24 221
 '@T6G_MB_LIB.T6G(SCH_1):PAGE97_I22@PURE_QUANTA.SCONN288_DDR506112002KQ(CHIPS)':
 'CA1_B': CDS_PINID='CA1_B';
NET_NAME
'M_A_CPU1_SB_CA<2>'
 '@T6G_MB_LIB.T6G(SCH_1):M_A_CPU1_SB_CA'<2>:
 C_SIGNAL='@t6g_mb_lib.t6g(sch_1):m_a_cpu1_sb_ca(2)';
NODE_NAME     U26 BH74
 '@T6G_MB_LIB.T6G(SCH_1):PAGE37_I167@PURE_QUANTA.GENOA_SP5(CHIPS)':
 'MAB_CA2': CDS_PINID='MAB_CA2';
NODE_NAME     J24 78
 '@T6G_MB_LIB.T6G(SCH_1):PAGE97_I22@PURE_QUANTA.SCONN288_DDR506112002KQ(CHIPS)':
 'CA2_B': CDS_PINID='CA2_B';
NET_NAME
'M_A_CPU1_SB_CA<3>'
 '@T6G_MB_LIB.T6G(SCH_1):M_A_CPU1_SB_CA'<3>:
 C_SIGNAL='@t6g_mb_lib.t6g(sch_1):m_a_cpu1_sb_ca(3)';
NODE_NAME     U26 BJ74
 '@T6G_MB_LIB.T6G(SCH_1):PAGE37_I167@PURE_QUANTA.GENOA_SP5(CHIPS)':
 'MAB_CA3': CDS_PINID='MAB_CA3';
NODE_NAME     J24 223
 '@T6G_MB_LIB.T6G(SCH_1):PAGE97_I22@PURE_QUANTA.SCONN288_DDR506112002KQ(CHIPS)':
 'CA3_B': CDS_PINID='CA3_B';
NET_NAME
'M_A_CPU1_SB_CA<4>'
 '@T6G_MB_LIB.T6G(SCH_1):M_A_CPU1_SB_CA'<4>:
 C_SIGNAL='@t6g_mb_lib.t6g(sch_1):m_a_cpu1_sb_ca(4)';
NODE_NAME     U26 BJ73
 '@T6G_MB_LIB.T6G(SCH_1):PAGE37_I167@PURE_QUANTA.GENOA_SP5(CHIPS)':
 'MAB_CA4': CDS_PINID='MAB_CA4';
NODE_NAME     J24 80
 '@T6G_MB_LIB.T6G(SCH_1):PAGE97_I22@PURE_QUANTA.SCONN288_DDR506112002KQ(CHIPS)':
 'CA4_B': CDS_PINID='CA4_B';
NET_NAME
'M_A_CPU1_SB_CA<5>'
 '@T6G_MB_LIB.T6G(SCH_1):M_A_CPU1_SB_CA'<5>:
 C_SIGNAL='@t6g_mb_lib.t6g(sch_1):m_a_cpu1_sb_ca(5)';
NODE_NAME     U26 BK72
 '@T6G_MB_LIB.T6G(SCH_1):PAGE37_I167@PURE_QUANTA.GENOA_SP5(CHIPS)':
 'MAB_CA5': CDS_PINID='MAB_CA5';
NODE_NAME     J24 225
 '@T6G_MB_LIB.T6G(SCH_1):PAGE97_I22@PURE_QUANTA.SCONN288_DDR506112002KQ(CHIPS)':
 'CA5_B': CDS_PINID='CA5_B';
NET_NAME
'M_A_CPU1_SB_CA<6>'
 '@T6G_MB_LIB.T6G(SCH_1):M_A_CPU1_SB_CA'<6>:
 C_SIGNAL='@t6g_mb_lib.t6g(sch_1):m_a_cpu1_sb_ca(6)';
NODE_NAME     U26 BK74
 '@T6G_MB_LIB.T6G(SCH_1):PAGE37_I167@PURE_QUANTA.GENOA_SP5(CHIPS)':
 'MAB_CA6': CDS_PINID='MAB_CA6';
NODE_NAME     J24 82
 '@T6G_MB_LIB.T6G(SCH_1):PAGE97_I22@PURE_QUANTA.SCONN288_DDR506112002KQ(CHIPS)':
 'CA6_B': CDS_PINID='CA6_B';
NET_NAME
'M_A_CPU1_SB_CB<0>'
 '@T6G_MB_LIB.T6G(SCH_1):M_A_CPU1_SB_CB'<0>:
 C_SIGNAL='@t6g_mb_lib.t6g(sch_1):m_a_cpu1_sb_cb(0)';
NODE_NAME     U26 BY74
 '@T6G_MB_LIB.T6G(SCH_1):PAGE37_I167@PURE_QUANTA.GENOA_SP5(CHIPS)':
 'MAB_CHECK0': CDS_PINID='MAB_CHECK0';
NODE_NAME     J24 96
 '@T6G_MB_LIB.T6G(SCH_1):PAGE97_I22@PURE_QUANTA.SCONN288_DDR506112002KQ(CHIPS)':
 'CB0_B': CDS_PINID='CB0_B';
NET_NAME
'M_A_CPU1_SB_CB<1>'
 '@T6G_MB_LIB.T6G(SCH_1):M_A_CPU1_SB_CB'<1>:
 C_SIGNAL='@t6g_mb_lib.t6g(sch_1):m_a_cpu1_sb_cb(1)';
NODE_NAME     U26 CA73
 '@T6G_MB_LIB.T6G(SCH_1):PAGE37_I167@PURE_QUANTA.GENOA_SP5(CHIPS)':
 'MAB_CHECK1': CDS_PINID='MAB_CHECK1';
NODE_NAME     J24 98
 '@T6G_MB_LIB.T6G(SCH_1):PAGE97_I22@PURE_QUANTA.SCONN288_DDR506112002KQ(CHIPS)':
 'CB1_B': CDS_PINID='CB1_B';
NET_NAME
'M_A_CPU1_SB_CB<2>'
 '@T6G_MB_LIB.T6G(SCH_1):M_A_CPU1_SB_CB'<2>:
 C_SIGNAL='@t6g_mb_lib.t6g(sch_1):m_a_cpu1_sb_cb(2)';
NODE_NAME     U26 CA74
 '@T6G_MB_LIB.T6G(SCH_1):PAGE37_I167@PURE_QUANTA.GENOA_SP5(CHIPS)':
 'MAB_CHECK2': CDS_PINID='MAB_CHECK2';
NODE_NAME     J24 241
 '@T6G_MB_LIB.T6G(SCH_1):PAGE97_I22@PURE_QUANTA.SCONN288_DDR506112002KQ(CHIPS)':
 'CB2_B': CDS_PINID='CB2_B';
NET_NAME
'M_A_CPU1_SB_CB<3>'
 '@T6G_MB_LIB.T6G(SCH_1):M_A_CPU1_SB_CB'<3>:
 C_SIGNAL='@t6g_mb_lib.t6g(sch_1):m_a_cpu1_sb_cb(3)';
NODE_NAME     U26 CB72
 '@T6G_MB_LIB.T6G(SCH_1):PAGE37_I167@PURE_QUANTA.GENOA_SP5(CHIPS)':
 'MAB_CHECK3': CDS_PINID='MAB_CHECK3';
NODE_NAME     J24 243
 '@T6G_MB_LIB.T6G(SCH_1):PAGE97_I22@PURE_QUANTA.SCONN288_DDR506112002KQ(CHIPS)':
 'CB3_B': CDS_PINID='CB3_B';
NET_NAME
'M_A_CPU1_SB_CB<4>'
 '@T6G_MB_LIB.T6G(SCH_1):M_A_CPU1_SB_CB'<4>:
 C_SIGNAL='@t6g_mb_lib.t6g(sch_1):m_a_cpu1_sb_cb(4)';
NODE_NAME     U26 BT74
 '@T6G_MB_LIB.T6G(SCH_1):PAGE37_I167@PURE_QUANTA.GENOA_SP5(CHIPS)':
 'MAB_CHECK4': CDS_PINID='MAB_CHECK4';
NODE_NAME     J24 89
 '@T6G_MB_LIB.T6G(SCH_1):PAGE97_I22@PURE_QUANTA.SCONN288_DDR506112002KQ(CHIPS)':
 'CB4_B': CDS_PINID='CB4_B';
NET_NAME
'M_A_CPU1_SB_CB<5>'
 '@T6G_MB_LIB.T6G(SCH_1):M_A_CPU1_SB_CB'<5>:
 C_SIGNAL='@t6g_mb_lib.t6g(sch_1):m_a_cpu1_sb_cb(5)';
NODE_NAME     U26 BU73
 '@T6G_MB_LIB.T6G(SCH_1):PAGE37_I167@PURE_QUANTA.GENOA_SP5(CHIPS)':
 'MAB_CHECK5': CDS_PINID='MAB_CHECK5';
NODE_NAME     J24 91
 '@T6G_MB_LIB.T6G(SCH_1):PAGE97_I22@PURE_QUANTA.SCONN288_DDR506112002KQ(CHIPS)':
 'CB5_B': CDS_PINID='CB5_B';
NET_NAME
'M_A_CPU1_SB_CB<6>'
 '@T6G_MB_LIB.T6G(SCH_1):M_A_CPU1_SB_CB'<6>:
 C_SIGNAL='@t6g_mb_lib.t6g(sch_1):m_a_cpu1_sb_cb(6)';
NODE_NAME     U26 BU74
 '@T6G_MB_LIB.T6G(SCH_1):PAGE37_I167@PURE_QUANTA.GENOA_SP5(CHIPS)':
 'MAB_CHECK6': CDS_PINID='MAB_CHECK6';
NODE_NAME     J24 234
 '@T6G_MB_LIB.T6G(SCH_1):PAGE97_I22@PURE_QUANTA.SCONN288_DDR506112002KQ(CHIPS)':
 'CB6_B': CDS_PINID='CB6_B';
NET_NAME
'M_A_CPU1_SB_CB<7>'
 '@T6G_MB_LIB.T6G(SCH_1):M_A_CPU1_SB_CB'<7>:
 C_SIGNAL='@t6g_mb_lib.t6g(sch_1):m_a_cpu1_sb_cb(7)';
NODE_NAME     U26 BV72
 '@T6G_MB_LIB.T6G(SCH_1):PAGE37_I167@PURE_QUANTA.GENOA_SP5(CHIPS)':
 'MAB_CHECK7': CDS_PINID='MAB_CHECK7';
NODE_NAME     J24 236
 '@T6G_MB_LIB.T6G(SCH_1):PAGE97_I22@PURE_QUANTA.SCONN288_DDR506112002KQ(CHIPS)':
 'CB7_B': CDS_PINID='CB7_B';
NET_NAME
'M_A_CPU1_SB_CS_N<0>'
 '@T6G_MB_LIB.T6G(SCH_1):M_A_CPU1_SB_CS_N'<0>:
 C_SIGNAL='@t6g_mb_lib.t6g(sch_1):m_a_cpu1_sb_cs_n(0)';
NODE_NAME     U26 BM72
 '@T6G_MB_LIB.T6G(SCH_1):PAGE37_I167@PURE_QUANTA.GENOA_SP5(CHIPS)':
 'MAB0_CS_L0': CDS_PINID='MAB0_CS_L0';
NODE_NAME     J24 84
 '@T6G_MB_LIB.T6G(SCH_1):PAGE97_I22@PURE_QUANTA.SCONN288_DDR506112002KQ(CHIPS)':
 'CS0_B_N': CDS_PINID='CS0_B_N';
NET_NAME
'M_A_CPU1_SB_CS_N<1>'
 '@T6G_MB_LIB.T6G(SCH_1):M_A_CPU1_SB_CS_N'<1>:
 C_SIGNAL='@t6g_mb_lib.t6g(sch_1):m_a_cpu1_sb_cs_n(1)';
NODE_NAME     U26 BN74
 '@T6G_MB_LIB.T6G(SCH_1):PAGE37_I167@PURE_QUANTA.GENOA_SP5(CHIPS)':
 'MAB0_CS_L1': CDS_PINID='MAB0_CS_L1';
NODE_NAME     J24 229
 '@T6G_MB_LIB.T6G(SCH_1):PAGE97_I22@PURE_QUANTA.SCONN288_DDR506112002KQ(CHIPS)':
 'CS1_B_N': CDS_PINID='CS1_B_N';
NET_NAME
'M_A_CPU1_SB_DQ<0>'
 '@T6G_MB_LIB.T6G(SCH_1):M_A_CPU1_SB_DQ'<0>:
 C_SIGNAL='@t6g_mb_lib.t6g(sch_1):m_a_cpu1_sb_dq(0)';
NODE_NAME     U26 CB74
 '@T6G_MB_LIB.T6G(SCH_1):PAGE37_I167@PURE_QUANTA.GENOA_SP5(CHIPS)':
 'MAB_DATA0': CDS_PINID='MAB_DATA0';
NODE_NAME     J24 100
 '@T6G_MB_LIB.T6G(SCH_1):PAGE97_I22@PURE_QUANTA.SCONN288_DDR506112002KQ(CHIPS)':
 'DQ0_B': CDS_PINID='DQ0_B';
NET_NAME
'M_A_CPU1_SB_DQ<10>'
 '@T6G_MB_LIB.T6G(SCH_1):M_A_CPU1_SB_DQ'<10>:
 C_SIGNAL='@t6g_mb_lib.t6g(sch_1):m_a_cpu1_sb_dq(10)';
NODE_NAME     U26 CJ74
 '@T6G_MB_LIB.T6G(SCH_1):PAGE37_I167@PURE_QUANTA.GENOA_SP5(CHIPS)':
 'MAB_DATA10': CDS_PINID='MAB_DATA10';
NODE_NAME     J24 256
 '@T6G_MB_LIB.T6G(SCH_1):PAGE97_I22@PURE_QUANTA.SCONN288_DDR506112002KQ(CHIPS)':
 'DQ10_B': CDS_PINID='DQ10_B';
NET_NAME
'M_A_CPU1_SB_DQ<11>'
 '@T6G_MB_LIB.T6G(SCH_1):M_A_CPU1_SB_DQ'<11>:
 C_SIGNAL='@t6g_mb_lib.t6g(sch_1):m_a_cpu1_sb_dq(11)';
NODE_NAME     U26 CK72
 '@T6G_MB_LIB.T6G(SCH_1):PAGE37_I167@PURE_QUANTA.GENOA_SP5(CHIPS)':
 'MAB_DATA11': CDS_PINID='MAB_DATA11';
NODE_NAME     J24 258
 '@T6G_MB_LIB.T6G(SCH_1):PAGE97_I22@PURE_QUANTA.SCONN288_DDR506112002KQ(CHIPS)':
 'DQ11_B': CDS_PINID='DQ11_B';
NET_NAME
'M_A_CPU1_SB_DQ<12>'
 '@T6G_MB_LIB.T6G(SCH_1):M_A_CPU1_SB_DQ'<12>:
 C_SIGNAL='@t6g_mb_lib.t6g(sch_1):m_a_cpu1_sb_dq(12)';
NODE_NAME     U26 CM74
 '@T6G_MB_LIB.T6G(SCH_1):PAGE37_I167@PURE_QUANTA.GENOA_SP5(CHIPS)':
 'MAB_DATA12': CDS_PINID='MAB_DATA12';
NODE_NAME     J24 118
 '@T6G_MB_LIB.T6G(SCH_1):PAGE97_I22@PURE_QUANTA.SCONN288_DDR506112002KQ(CHIPS)':
 'DQ12_B': CDS_PINID='DQ12_B';
NET_NAME
'M_A_CPU1_SB_DQ<13>'
 '@T6G_MB_LIB.T6G(SCH_1):M_A_CPU1_SB_DQ'<13>:
 C_SIGNAL='@t6g_mb_lib.t6g(sch_1):m_a_cpu1_sb_dq(13)';
NODE_NAME     U26 CN73
 '@T6G_MB_LIB.T6G(SCH_1):PAGE37_I167@PURE_QUANTA.GENOA_SP5(CHIPS)':
 'MAB_DATA13': CDS_PINID='MAB_DATA13';
NODE_NAME     J24 120
 '@T6G_MB_LIB.T6G(SCH_1):PAGE97_I22@PURE_QUANTA.SCONN288_DDR506112002KQ(CHIPS)':
 'DQ13_B': CDS_PINID='DQ13_B';
NET_NAME
'M_A_CPU1_SB_DQ<14>'
 '@T6G_MB_LIB.T6G(SCH_1):M_A_CPU1_SB_DQ'<14>:
 C_SIGNAL='@t6g_mb_lib.t6g(sch_1):m_a_cpu1_sb_dq(14)';
NODE_NAME     U26 CN74
 '@T6G_MB_LIB.T6G(SCH_1):PAGE37_I167@PURE_QUANTA.GENOA_SP5(CHIPS)':
 'MAB_DATA14': CDS_PINID='MAB_DATA14';
NODE_NAME     J24 263
 '@T6G_MB_LIB.T6G(SCH_1):PAGE97_I22@PURE_QUANTA.SCONN288_DDR506112002KQ(CHIPS)':
 'DQ14_B': CDS_PINID='DQ14_B';
NET_NAME
'M_A_CPU1_SB_DQ<15>'
 '@T6G_MB_LIB.T6G(SCH_1):M_A_CPU1_SB_DQ'<15>:
 C_SIGNAL='@t6g_mb_lib.t6g(sch_1):m_a_cpu1_sb_dq(15)';
NODE_NAME     U26 CP72
 '@T6G_MB_LIB.T6G(SCH_1):PAGE37_I167@PURE_QUANTA.GENOA_SP5(CHIPS)':
 'MAB_DATA15': CDS_PINID='MAB_DATA15';
NODE_NAME     J24 265
 '@T6G_MB_LIB.T6G(SCH_1):PAGE97_I22@PURE_QUANTA.SCONN288_DDR506112002KQ(CHIPS)':
 'DQ15_B': CDS_PINID='DQ15_B';
NET_NAME
'M_A_CPU1_SB_DQ<16>'
 '@T6G_MB_LIB.T6G(SCH_1):M_A_CPU1_SB_DQ'<16>:
 C_SIGNAL='@t6g_mb_lib.t6g(sch_1):m_a_cpu1_sb_dq(16)';
NODE_NAME     U26 CP74
 '@T6G_MB_LIB.T6G(SCH_1):PAGE37_I167@PURE_QUANTA.GENOA_SP5(CHIPS)':
 'MAB_DATA16': CDS_PINID='MAB_DATA16';
NODE_NAME     J24 122
 '@T6G_MB_LIB.T6G(SCH_1):PAGE97_I22@PURE_QUANTA.SCONN288_DDR506112002KQ(CHIPS)':
 'DQ16_B': CDS_PINID='DQ16_B';
NET_NAME
'M_A_CPU1_SB_DQ<17>'
 '@T6G_MB_LIB.T6G(SCH_1):M_A_CPU1_SB_DQ'<17>:
 C_SIGNAL='@t6g_mb_lib.t6g(sch_1):m_a_cpu1_sb_dq(17)';
NODE_NAME     U26 CR73
 '@T6G_MB_LIB.T6G(SCH_1):PAGE37_I167@PURE_QUANTA.GENOA_SP5(CHIPS)':
 'MAB_DATA17': CDS_PINID='MAB_DATA17';
NODE_NAME     J24 124
 '@T6G_MB_LIB.T6G(SCH_1):PAGE97_I22@PURE_QUANTA.SCONN288_DDR506112002KQ(CHIPS)':
 'DQ17_B': CDS_PINID='DQ17_B';
NET_NAME
'M_A_CPU1_SB_DQ<18>'
 '@T6G_MB_LIB.T6G(SCH_1):M_A_CPU1_SB_DQ'<18>:
 C_SIGNAL='@t6g_mb_lib.t6g(sch_1):m_a_cpu1_sb_dq(18)';
NODE_NAME     U26 CR74
 '@T6G_MB_LIB.T6G(SCH_1):PAGE37_I167@PURE_QUANTA.GENOA_SP5(CHIPS)':
 'MAB_DATA18': CDS_PINID='MAB_DATA18';
NODE_NAME     J24 267
 '@T6G_MB_LIB.T6G(SCH_1):PAGE97_I22@PURE_QUANTA.SCONN288_DDR506112002KQ(CHIPS)':
 'DQ18_B': CDS_PINID='DQ18_B';
NET_NAME
'M_A_CPU1_SB_DQ<19>'
 '@T6G_MB_LIB.T6G(SCH_1):M_A_CPU1_SB_DQ'<19>:
 C_SIGNAL='@t6g_mb_lib.t6g(sch_1):m_a_cpu1_sb_dq(19)';
NODE_NAME     U26 CT72
 '@T6G_MB_LIB.T6G(SCH_1):PAGE37_I167@PURE_QUANTA.GENOA_SP5(CHIPS)':
 'MAB_DATA19': CDS_PINID='MAB_DATA19';
NODE_NAME     J24 269
 '@T6G_MB_LIB.T6G(SCH_1):PAGE97_I22@PURE_QUANTA.SCONN288_DDR506112002KQ(CHIPS)':
 'DQ19_B': CDS_PINID='DQ19_B';
NET_NAME
'M_A_CPU1_SB_DQ<1>'
 '@T6G_MB_LIB.T6G(SCH_1):M_A_CPU1_SB_DQ'<1>:
 C_SIGNAL='@t6g_mb_lib.t6g(sch_1):m_a_cpu1_sb_dq(1)';
NODE_NAME     U26 CC73
 '@T6G_MB_LIB.T6G(SCH_1):PAGE37_I167@PURE_QUANTA.GENOA_SP5(CHIPS)':
 'MAB_DATA1': CDS_PINID='MAB_DATA1';
NODE_NAME     J24 102
 '@T6G_MB_LIB.T6G(SCH_1):PAGE97_I22@PURE_QUANTA.SCONN288_DDR506112002KQ(CHIPS)':
 'DQ1_B': CDS_PINID='DQ1_B';
NET_NAME
'M_A_CPU1_SB_DQ<20>'
 '@T6G_MB_LIB.T6G(SCH_1):M_A_CPU1_SB_DQ'<20>:
 C_SIGNAL='@t6g_mb_lib.t6g(sch_1):m_a_cpu1_sb_dq(20)';
NODE_NAME     U26 CV74
 '@T6G_MB_LIB.T6G(SCH_1):PAGE37_I167@PURE_QUANTA.GENOA_SP5(CHIPS)':
 'MAB_DATA20': CDS_PINID='MAB_DATA20';
NODE_NAME     J24 129
 '@T6G_MB_LIB.T6G(SCH_1):PAGE97_I22@PURE_QUANTA.SCONN288_DDR506112002KQ(CHIPS)':
 'DQ20_B': CDS_PINID='DQ20_B';
NET_NAME
'M_A_CPU1_SB_DQ<21>'
 '@T6G_MB_LIB.T6G(SCH_1):M_A_CPU1_SB_DQ'<21>:
 C_SIGNAL='@t6g_mb_lib.t6g(sch_1):m_a_cpu1_sb_dq(21)';
NODE_NAME     U26 CW73
 '@T6G_MB_LIB.T6G(SCH_1):PAGE37_I167@PURE_QUANTA.GENOA_SP5(CHIPS)':
 'MAB_DATA21': CDS_PINID='MAB_DATA21';
NODE_NAME     J24 131
 '@T6G_MB_LIB.T6G(SCH_1):PAGE97_I22@PURE_QUANTA.SCONN288_DDR506112002KQ(CHIPS)':
 'DQ21_B': CDS_PINID='DQ21_B';
NET_NAME
'M_A_CPU1_SB_DQ<22>'
 '@T6G_MB_LIB.T6G(SCH_1):M_A_CPU1_SB_DQ'<22>:
 C_SIGNAL='@t6g_mb_lib.t6g(sch_1):m_a_cpu1_sb_dq(22)';
NODE_NAME     U26 CW74
 '@T6G_MB_LIB.T6G(SCH_1):PAGE37_I167@PURE_QUANTA.GENOA_SP5(CHIPS)':
 'MAB_DATA22': CDS_PINID='MAB_DATA22';
NODE_NAME     J24 274
 '@T6G_MB_LIB.T6G(SCH_1):PAGE97_I22@PURE_QUANTA.SCONN288_DDR506112002KQ(CHIPS)':
 'DQ22_B': CDS_PINID='DQ22_B';
NET_NAME
'M_A_CPU1_SB_DQ<23>'
 '@T6G_MB_LIB.T6G(SCH_1):M_A_CPU1_SB_DQ'<23>:
 C_SIGNAL='@t6g_mb_lib.t6g(sch_1):m_a_cpu1_sb_dq(23)';
NODE_NAME     U26 CY72
 '@T6G_MB_LIB.T6G(SCH_1):PAGE37_I167@PURE_QUANTA.GENOA_SP5(CHIPS)':
 'MAB_DATA23': CDS_PINID='MAB_DATA23';
NODE_NAME     J24 276
 '@T6G_MB_LIB.T6G(SCH_1):PAGE97_I22@PURE_QUANTA.SCONN288_DDR506112002KQ(CHIPS)':
 'DQ23_B': CDS_PINID='DQ23_B';
NET_NAME
'M_A_CPU1_SB_DQ<24>'
 '@T6G_MB_LIB.T6G(SCH_1):M_A_CPU1_SB_DQ'<24>:
 C_SIGNAL='@t6g_mb_lib.t6g(sch_1):m_a_cpu1_sb_dq(24)';
NODE_NAME     U26 CY74
 '@T6G_MB_LIB.T6G(SCH_1):PAGE37_I167@PURE_QUANTA.GENOA_SP5(CHIPS)':
 'MAB_DATA24': CDS_PINID='MAB_DATA24';
NODE_NAME     J24 133
 '@T6G_MB_LIB.T6G(SCH_1):PAGE97_I22@PURE_QUANTA.SCONN288_DDR506112002KQ(CHIPS)':
 'DQ24_B': CDS_PINID='DQ24_B';
NET_NAME
'M_A_CPU1_SB_DQ<25>'
 '@T6G_MB_LIB.T6G(SCH_1):M_A_CPU1_SB_DQ'<25>:
 C_SIGNAL='@t6g_mb_lib.t6g(sch_1):m_a_cpu1_sb_dq(25)';
NODE_NAME     U26 DA73
 '@T6G_MB_LIB.T6G(SCH_1):PAGE37_I167@PURE_QUANTA.GENOA_SP5(CHIPS)':
 'MAB_DATA25': CDS_PINID='MAB_DATA25';
NODE_NAME     J24 135
 '@T6G_MB_LIB.T6G(SCH_1):PAGE97_I22@PURE_QUANTA.SCONN288_DDR506112002KQ(CHIPS)':
 'DQ25_B': CDS_PINID='DQ25_B';
NET_NAME
'M_A_CPU1_SB_DQ<26>'
 '@T6G_MB_LIB.T6G(SCH_1):M_A_CPU1_SB_DQ'<26>:
 C_SIGNAL='@t6g_mb_lib.t6g(sch_1):m_a_cpu1_sb_dq(26)';
NODE_NAME     U26 DA74
 '@T6G_MB_LIB.T6G(SCH_1):PAGE37_I167@PURE_QUANTA.GENOA_SP5(CHIPS)':
 'MAB_DATA26': CDS_PINID='MAB_DATA26';
NODE_NAME     J24 278
 '@T6G_MB_LIB.T6G(SCH_1):PAGE97_I22@PURE_QUANTA.SCONN288_DDR506112002KQ(CHIPS)':
 'DQ26_B': CDS_PINID='DQ26_B';
NET_NAME
'M_A_CPU1_SB_DQ<27>'
 '@T6G_MB_LIB.T6G(SCH_1):M_A_CPU1_SB_DQ'<27>:
 C_SIGNAL='@t6g_mb_lib.t6g(sch_1):m_a_cpu1_sb_dq(27)';
NODE_NAME     U26 DB72
 '@T6G_MB_LIB.T6G(SCH_1):PAGE37_I167@PURE_QUANTA.GENOA_SP5(CHIPS)':
 'MAB_DATA27': CDS_PINID='MAB_DATA27';
NODE_NAME     J24 280
 '@T6G_MB_LIB.T6G(SCH_1):PAGE97_I22@PURE_QUANTA.SCONN288_DDR506112002KQ(CHIPS)':
 'DQ27_B': CDS_PINID='DQ27_B';
NET_NAME
'M_A_CPU1_SB_DQ<28>'
 '@T6G_MB_LIB.T6G(SCH_1):M_A_CPU1_SB_DQ'<28>:
 C_SIGNAL='@t6g_mb_lib.t6g(sch_1):m_a_cpu1_sb_dq(28)';
NODE_NAME     U26 DD74
 '@T6G_MB_LIB.T6G(SCH_1):PAGE37_I167@PURE_QUANTA.GENOA_SP5(CHIPS)':
 'MAB_DATA28': CDS_PINID='MAB_DATA28';
NODE_NAME     J24 140
 '@T6G_MB_LIB.T6G(SCH_1):PAGE97_I22@PURE_QUANTA.SCONN288_DDR506112002KQ(CHIPS)':
 'DQ28_B': CDS_PINID='DQ28_B';
NET_NAME
'M_A_CPU1_SB_DQ<29>'
 '@T6G_MB_LIB.T6G(SCH_1):M_A_CPU1_SB_DQ'<29>:
 C_SIGNAL='@t6g_mb_lib.t6g(sch_1):m_a_cpu1_sb_dq(29)';
NODE_NAME     U26 DE73
 '@T6G_MB_LIB.T6G(SCH_1):PAGE37_I167@PURE_QUANTA.GENOA_SP5(CHIPS)':
 'MAB_DATA29': CDS_PINID='MAB_DATA29';
NODE_NAME     J24 142
 '@T6G_MB_LIB.T6G(SCH_1):PAGE97_I22@PURE_QUANTA.SCONN288_DDR506112002KQ(CHIPS)':
 'DQ29_B': CDS_PINID='DQ29_B';
NET_NAME
'M_A_CPU1_SB_DQ<2>'
 '@T6G_MB_LIB.T6G(SCH_1):M_A_CPU1_SB_DQ'<2>:
 C_SIGNAL='@t6g_mb_lib.t6g(sch_1):m_a_cpu1_sb_dq(2)';
NODE_NAME     U26 CC74
 '@T6G_MB_LIB.T6G(SCH_1):PAGE37_I167@PURE_QUANTA.GENOA_SP5(CHIPS)':
 'MAB_DATA2': CDS_PINID='MAB_DATA2';
NODE_NAME     J24 245
 '@T6G_MB_LIB.T6G(SCH_1):PAGE97_I22@PURE_QUANTA.SCONN288_DDR506112002KQ(CHIPS)':
 'DQ2_B': CDS_PINID='DQ2_B';
NET_NAME
'M_A_CPU1_SB_DQ<30>'
 '@T6G_MB_LIB.T6G(SCH_1):M_A_CPU1_SB_DQ'<30>:
 C_SIGNAL='@t6g_mb_lib.t6g(sch_1):m_a_cpu1_sb_dq(30)';
NODE_NAME     U26 DE74
 '@T6G_MB_LIB.T6G(SCH_1):PAGE37_I167@PURE_QUANTA.GENOA_SP5(CHIPS)':
 'MAB_DATA30': CDS_PINID='MAB_DATA30';
NODE_NAME     J24 285
 '@T6G_MB_LIB.T6G(SCH_1):PAGE97_I22@PURE_QUANTA.SCONN288_DDR506112002KQ(CHIPS)':
 'DQ30_B': CDS_PINID='DQ30_B';
NET_NAME
'M_A_CPU1_SB_DQ<31>'
 '@T6G_MB_LIB.T6G(SCH_1):M_A_CPU1_SB_DQ'<31>:
 C_SIGNAL='@t6g_mb_lib.t6g(sch_1):m_a_cpu1_sb_dq(31)';
NODE_NAME     U26 DF74
 '@T6G_MB_LIB.T6G(SCH_1):PAGE37_I167@PURE_QUANTA.GENOA_SP5(CHIPS)':
 'MAB_DATA31': CDS_PINID='MAB_DATA31';
NODE_NAME     J24 287
 '@T6G_MB_LIB.T6G(SCH_1):PAGE97_I22@PURE_QUANTA.SCONN288_DDR506112002KQ(CHIPS)':
 'DQ31_B': CDS_PINID='DQ31_B';
NET_NAME
'M_A_CPU1_SB_DQ<3>'
 '@T6G_MB_LIB.T6G(SCH_1):M_A_CPU1_SB_DQ'<3>:
 C_SIGNAL='@t6g_mb_lib.t6g(sch_1):m_a_cpu1_sb_dq(3)';
NODE_NAME     U26 CD72
 '@T6G_MB_LIB.T6G(SCH_1):PAGE37_I167@PURE_QUANTA.GENOA_SP5(CHIPS)':
 'MAB_DATA3': CDS_PINID='MAB_DATA3';
NODE_NAME     J24 247
 '@T6G_MB_LIB.T6G(SCH_1):PAGE97_I22@PURE_QUANTA.SCONN288_DDR506112002KQ(CHIPS)':
 'DQ3_B': CDS_PINID='DQ3_B';
NET_NAME
'M_A_CPU1_SB_DQ<4>'
 '@T6G_MB_LIB.T6G(SCH_1):M_A_CPU1_SB_DQ'<4>:
 C_SIGNAL='@t6g_mb_lib.t6g(sch_1):m_a_cpu1_sb_dq(4)';
NODE_NAME     U26 CF74
 '@T6G_MB_LIB.T6G(SCH_1):PAGE37_I167@PURE_QUANTA.GENOA_SP5(CHIPS)':
 'MAB_DATA4': CDS_PINID='MAB_DATA4';
NODE_NAME     J24 107
 '@T6G_MB_LIB.T6G(SCH_1):PAGE97_I22@PURE_QUANTA.SCONN288_DDR506112002KQ(CHIPS)':
 'DQ4_B': CDS_PINID='DQ4_B';
NET_NAME
'M_A_CPU1_SB_DQ<5>'
 '@T6G_MB_LIB.T6G(SCH_1):M_A_CPU1_SB_DQ'<5>:
 C_SIGNAL='@t6g_mb_lib.t6g(sch_1):m_a_cpu1_sb_dq(5)';
NODE_NAME     U26 CG73
 '@T6G_MB_LIB.T6G(SCH_1):PAGE37_I167@PURE_QUANTA.GENOA_SP5(CHIPS)':
 'MAB_DATA5': CDS_PINID='MAB_DATA5';
NODE_NAME     J24 109
 '@T6G_MB_LIB.T6G(SCH_1):PAGE97_I22@PURE_QUANTA.SCONN288_DDR506112002KQ(CHIPS)':
 'DQ5_B': CDS_PINID='DQ5_B';
NET_NAME
'M_A_CPU1_SB_DQ<6>'
 '@T6G_MB_LIB.T6G(SCH_1):M_A_CPU1_SB_DQ'<6>:
 C_SIGNAL='@t6g_mb_lib.t6g(sch_1):m_a_cpu1_sb_dq(6)';
NODE_NAME     U26 CG74
 '@T6G_MB_LIB.T6G(SCH_1):PAGE37_I167@PURE_QUANTA.GENOA_SP5(CHIPS)':
 'MAB_DATA6': CDS_PINID='MAB_DATA6';
NODE_NAME     J24 252
 '@T6G_MB_LIB.T6G(SCH_1):PAGE97_I22@PURE_QUANTA.SCONN288_DDR506112002KQ(CHIPS)':
 'DQ6_B': CDS_PINID='DQ6_B';
NET_NAME
'M_A_CPU1_SB_DQ<7>'
 '@T6G_MB_LIB.T6G(SCH_1):M_A_CPU1_SB_DQ'<7>:
 C_SIGNAL='@t6g_mb_lib.t6g(sch_1):m_a_cpu1_sb_dq(7)';
NODE_NAME     U26 CH72
 '@T6G_MB_LIB.T6G(SCH_1):PAGE37_I167@PURE_QUANTA.GENOA_SP5(CHIPS)':
 'MAB_DATA7': CDS_PINID='MAB_DATA7';
NODE_NAME     J24 254
 '@T6G_MB_LIB.T6G(SCH_1):PAGE97_I22@PURE_QUANTA.SCONN288_DDR506112002KQ(CHIPS)':
 'DQ7_B': CDS_PINID='DQ7_B';
NET_NAME
'M_A_CPU1_SB_DQ<8>'
 '@T6G_MB_LIB.T6G(SCH_1):M_A_CPU1_SB_DQ'<8>:
 C_SIGNAL='@t6g_mb_lib.t6g(sch_1):m_a_cpu1_sb_dq(8)';
NODE_NAME     U26 CH74
 '@T6G_MB_LIB.T6G(SCH_1):PAGE37_I167@PURE_QUANTA.GENOA_SP5(CHIPS)':
 'MAB_DATA8': CDS_PINID='MAB_DATA8';
NODE_NAME     J24 111
 '@T6G_MB_LIB.T6G(SCH_1):PAGE97_I22@PURE_QUANTA.SCONN288_DDR506112002KQ(CHIPS)':
 'DQ8_B': CDS_PINID='DQ8_B';
NET_NAME
'M_A_CPU1_SB_DQ<9>'
 '@T6G_MB_LIB.T6G(SCH_1):M_A_CPU1_SB_DQ'<9>:
 C_SIGNAL='@t6g_mb_lib.t6g(sch_1):m_a_cpu1_sb_dq(9)';
NODE_NAME     U26 CJ73
 '@T6G_MB_LIB.T6G(SCH_1):PAGE37_I167@PURE_QUANTA.GENOA_SP5(CHIPS)':
 'MAB_DATA9': CDS_PINID='MAB_DATA9';
NODE_NAME     J24 113
 '@T6G_MB_LIB.T6G(SCH_1):PAGE97_I22@PURE_QUANTA.SCONN288_DDR506112002KQ(CHIPS)':
 'DQ9_B': CDS_PINID='DQ9_B';
NET_NAME
'M_A_CPU1_SB_DQS_DN<0>'
 '@T6G_MB_LIB.T6G(SCH_1):M_A_CPU1_SB_DQS_DN'<0>:
 C_SIGNAL='@t6g_mb_lib.t6g(sch_1):m_a_cpu1_sb_dqs_dn(0)';
NODE_NAME     U26 CE74
 '@T6G_MB_LIB.T6G(SCH_1):PAGE37_I167@PURE_QUANTA.GENOA_SP5(CHIPS)':
 'MAB_DQS_L0': CDS_PINID='MAB_DQS_L0';
NODE_NAME     J24 105
 '@T6G_MB_LIB.T6G(SCH_1):PAGE97_I238@PURE_QUANTA.SCONN288_DDR506112002KQ(CHIPS)':
 'DQS0_B_C': CDS_PINID='DQS0_B_C';
NET_NAME
'M_A_CPU1_SB_DQS_DN<1>'
 '@T6G_MB_LIB.T6G(SCH_1):M_A_CPU1_SB_DQS_DN'<1>:
 C_SIGNAL='@t6g_mb_lib.t6g(sch_1):m_a_cpu1_sb_dqs_dn(1)';
NODE_NAME     U26 CL74
 '@T6G_MB_LIB.T6G(SCH_1):PAGE37_I167@PURE_QUANTA.GENOA_SP5(CHIPS)':
 'MAB_DQS_L1': CDS_PINID='MAB_DQS_L1';
NODE_NAME     J24 116
 '@T6G_MB_LIB.T6G(SCH_1):PAGE97_I238@PURE_QUANTA.SCONN288_DDR506112002KQ(CHIPS)':
 'DQS1_B_C': CDS_PINID='DQS1_B_C';
NET_NAME
'M_A_CPU1_SB_DQS_DN<2>'
 '@T6G_MB_LIB.T6G(SCH_1):M_A_CPU1_SB_DQS_DN'<2>:
 C_SIGNAL='@t6g_mb_lib.t6g(sch_1):m_a_cpu1_sb_dqs_dn(2)';
NODE_NAME     U26 CU74
 '@T6G_MB_LIB.T6G(SCH_1):PAGE37_I167@PURE_QUANTA.GENOA_SP5(CHIPS)':
 'MAB_DQS_L2': CDS_PINID='MAB_DQS_L2';
NODE_NAME     J24 127
 '@T6G_MB_LIB.T6G(SCH_1):PAGE97_I238@PURE_QUANTA.SCONN288_DDR506112002KQ(CHIPS)':
 'DQS2_B_C': CDS_PINID='DQS2_B_C';
NET_NAME
'M_A_CPU1_SB_DQS_DN<3>'
 '@T6G_MB_LIB.T6G(SCH_1):M_A_CPU1_SB_DQS_DN'<3>:
 C_SIGNAL='@t6g_mb_lib.t6g(sch_1):m_a_cpu1_sb_dqs_dn(3)';
NODE_NAME     U26 DC74
 '@T6G_MB_LIB.T6G(SCH_1):PAGE37_I167@PURE_QUANTA.GENOA_SP5(CHIPS)':
 'MAB_DQS_L3': CDS_PINID='MAB_DQS_L3';
NODE_NAME     J24 138
 '@T6G_MB_LIB.T6G(SCH_1):PAGE97_I238@PURE_QUANTA.SCONN288_DDR506112002KQ(CHIPS)':
 'DQS3_B_C': CDS_PINID='DQS3_B_C';
NET_NAME
'M_A_CPU1_SB_DQS_DN<4>'
 '@T6G_MB_LIB.T6G(SCH_1):M_A_CPU1_SB_DQS_DN'<4>:
 C_SIGNAL='@t6g_mb_lib.t6g(sch_1):m_a_cpu1_sb_dqs_dn(4)';
NODE_NAME     U26 BW73
 '@T6G_MB_LIB.T6G(SCH_1):PAGE37_I167@PURE_QUANTA.GENOA_SP5(CHIPS)':
 'MAB_DQS_L4': CDS_PINID='MAB_DQS_L4';
NODE_NAME     J24 238
 '@T6G_MB_LIB.T6G(SCH_1):PAGE97_I238@PURE_QUANTA.SCONN288_DDR506112002KQ(CHIPS)':
 'DQS4_B_C': CDS_PINID='DQS4_B_C';
NET_NAME
'M_A_CPU1_SB_DQS_DN<5>'
 '@T6G_MB_LIB.T6G(SCH_1):M_A_CPU1_SB_DQS_DN'<5>:
 C_SIGNAL='@t6g_mb_lib.t6g(sch_1):m_a_cpu1_sb_dqs_dn(5)';
NODE_NAME     U26 CE73
 '@T6G_MB_LIB.T6G(SCH_1):PAGE37_I167@PURE_QUANTA.GENOA_SP5(CHIPS)':
 'MAB_DQS_L5': CDS_PINID='MAB_DQS_L5';
NODE_NAME     J24 249
 '@T6G_MB_LIB.T6G(SCH_1):PAGE97_I238@PURE_QUANTA.SCONN288_DDR506112002KQ(CHIPS)':
 'DQS5_B_C||TDQS5_B_C': CDS_PINID='\dqs5_b_c||tdqs5_b_c\';
NET_NAME
'M_A_CPU1_SB_DQS_DN<6>'
 '@T6G_MB_LIB.T6G(SCH_1):M_A_CPU1_SB_DQS_DN'<6>:
 C_SIGNAL='@t6g_mb_lib.t6g(sch_1):m_a_cpu1_sb_dqs_dn(6)';
NODE_NAME     U26 CL73
 '@T6G_MB_LIB.T6G(SCH_1):PAGE37_I167@PURE_QUANTA.GENOA_SP5(CHIPS)':
 'MAB_DQS_L6': CDS_PINID='MAB_DQS_L6';
NODE_NAME     J24 260
 '@T6G_MB_LIB.T6G(SCH_1):PAGE97_I238@PURE_QUANTA.SCONN288_DDR506112002KQ(CHIPS)':
 'DQS6_B_C||TDQS6_B_C': CDS_PINID='\dqs6_b_c||tdqs6_b_c\';
NET_NAME
'M_A_CPU1_SB_DQS_DN<7>'
 '@T6G_MB_LIB.T6G(SCH_1):M_A_CPU1_SB_DQS_DN'<7>:
 C_SIGNAL='@t6g_mb_lib.t6g(sch_1):m_a_cpu1_sb_dqs_dn(7)';
NODE_NAME     U26 CU73
 '@T6G_MB_LIB.T6G(SCH_1):PAGE37_I167@PURE_QUANTA.GENOA_SP5(CHIPS)':
 'MAB_DQS_L7': CDS_PINID='MAB_DQS_L7';
NODE_NAME     J24 271
 '@T6G_MB_LIB.T6G(SCH_1):PAGE97_I238@PURE_QUANTA.SCONN288_DDR506112002KQ(CHIPS)':
 'DQS7_B_C||TDQS7_B_C': CDS_PINID='\dqs7_b_c||tdqs7_b_c\';
NET_NAME
'M_A_CPU1_SB_DQS_DN<8>'
 '@T6G_MB_LIB.T6G(SCH_1):M_A_CPU1_SB_DQS_DN'<8>:
 C_SIGNAL='@t6g_mb_lib.t6g(sch_1):m_a_cpu1_sb_dqs_dn(8)';
NODE_NAME     U26 DC73
 '@T6G_MB_LIB.T6G(SCH_1):PAGE37_I167@PURE_QUANTA.GENOA_SP5(CHIPS)':
 'MAB_DQS_L8': CDS_PINID='MAB_DQS_L8';
NODE_NAME     J24 282
 '@T6G_MB_LIB.T6G(SCH_1):PAGE97_I238@PURE_QUANTA.SCONN288_DDR506112002KQ(CHIPS)':
 'DQS8_B_C||TDQS8_B_C': CDS_PINID='\dqs8_b_c||tdqs8_b_c\';
NET_NAME
'M_A_CPU1_SB_DQS_DN<9>'
 '@T6G_MB_LIB.T6G(SCH_1):M_A_CPU1_SB_DQS_DN'<9>:
 C_SIGNAL='@t6g_mb_lib.t6g(sch_1):m_a_cpu1_sb_dqs_dn(9)';
NODE_NAME     U26 BW74
 '@T6G_MB_LIB.T6G(SCH_1):PAGE37_I167@PURE_QUANTA.GENOA_SP5(CHIPS)':
 'MAB_DQS_L9': CDS_PINID='MAB_DQS_L9';
NODE_NAME     J24 94
 '@T6G_MB_LIB.T6G(SCH_1):PAGE97_I238@PURE_QUANTA.SCONN288_DDR506112002KQ(CHIPS)':
 'DQS9_B_C||TDQS9_B_C': CDS_PINID='\dqs9_b_c||tdqs9_b_c\';
NET_NAME
'M_A_CPU1_SB_DQS_DP<0>'
 '@T6G_MB_LIB.T6G(SCH_1):M_A_CPU1_SB_DQS_DP'<0>:
 C_SIGNAL='@t6g_mb_lib.t6g(sch_1):m_a_cpu1_sb_dqs_dp(0)';
NODE_NAME     U26 CD74
 '@T6G_MB_LIB.T6G(SCH_1):PAGE37_I167@PURE_QUANTA.GENOA_SP5(CHIPS)':
 'MAB_DQS_H0': CDS_PINID='MAB_DQS_H0';
NODE_NAME     J24 104
 '@T6G_MB_LIB.T6G(SCH_1):PAGE97_I238@PURE_QUANTA.SCONN288_DDR506112002KQ(CHIPS)':
 'DQS0_B_T': CDS_PINID='DQS0_B_T';
NET_NAME
'M_A_CPU1_SB_DQS_DP<1>'
 '@T6G_MB_LIB.T6G(SCH_1):M_A_CPU1_SB_DQS_DP'<1>:
 C_SIGNAL='@t6g_mb_lib.t6g(sch_1):m_a_cpu1_sb_dqs_dp(1)';
NODE_NAME     U26 CK74
 '@T6G_MB_LIB.T6G(SCH_1):PAGE37_I167@PURE_QUANTA.GENOA_SP5(CHIPS)':
 'MAB_DQS_H1': CDS_PINID='MAB_DQS_H1';
NODE_NAME     J24 115
 '@T6G_MB_LIB.T6G(SCH_1):PAGE97_I238@PURE_QUANTA.SCONN288_DDR506112002KQ(CHIPS)':
 'DQS1_B_T': CDS_PINID='DQS1_B_T';
NET_NAME
'M_A_CPU1_SB_DQS_DP<2>'
 '@T6G_MB_LIB.T6G(SCH_1):M_A_CPU1_SB_DQS_DP'<2>:
 C_SIGNAL='@t6g_mb_lib.t6g(sch_1):m_a_cpu1_sb_dqs_dp(2)';
NODE_NAME     U26 CT74
 '@T6G_MB_LIB.T6G(SCH_1):PAGE37_I167@PURE_QUANTA.GENOA_SP5(CHIPS)':
 'MAB_DQS_H2': CDS_PINID='MAB_DQS_H2';
NODE_NAME     J24 126
 '@T6G_MB_LIB.T6G(SCH_1):PAGE97_I238@PURE_QUANTA.SCONN288_DDR506112002KQ(CHIPS)':
 'DQS2_B_T': CDS_PINID='DQS2_B_T';
NET_NAME
'M_A_CPU1_SB_DQS_DP<3>'
 '@T6G_MB_LIB.T6G(SCH_1):M_A_CPU1_SB_DQS_DP'<3>:
 C_SIGNAL='@t6g_mb_lib.t6g(sch_1):m_a_cpu1_sb_dqs_dp(3)';
NODE_NAME     U26 DB74
 '@T6G_MB_LIB.T6G(SCH_1):PAGE37_I167@PURE_QUANTA.GENOA_SP5(CHIPS)':
 'MAB_DQS_H3': CDS_PINID='MAB_DQS_H3';
NODE_NAME     J24 137
 '@T6G_MB_LIB.T6G(SCH_1):PAGE97_I238@PURE_QUANTA.SCONN288_DDR506112002KQ(CHIPS)':
 'DQS3_B_T': CDS_PINID='DQS3_B_T';
NET_NAME
'M_A_CPU1_SB_DQS_DP<4>'
 '@T6G_MB_LIB.T6G(SCH_1):M_A_CPU1_SB_DQS_DP'<4>:
 C_SIGNAL='@t6g_mb_lib.t6g(sch_1):m_a_cpu1_sb_dqs_dp(4)';
NODE_NAME     U26 BY72
 '@T6G_MB_LIB.T6G(SCH_1):PAGE37_I167@PURE_QUANTA.GENOA_SP5(CHIPS)':
 'MAB_DQS_H4': CDS_PINID='MAB_DQS_H4';
NODE_NAME     J24 239
 '@T6G_MB_LIB.T6G(SCH_1):PAGE97_I238@PURE_QUANTA.SCONN288_DDR506112002KQ(CHIPS)':
 'DQS4_B_T': CDS_PINID='DQS4_B_T';
NET_NAME
'M_A_CPU1_SB_DQS_DP<5>'
 '@T6G_MB_LIB.T6G(SCH_1):M_A_CPU1_SB_DQS_DP'<5>:
 C_SIGNAL='@t6g_mb_lib.t6g(sch_1):m_a_cpu1_sb_dqs_dp(5)';
NODE_NAME     U26 CF72
 '@T6G_MB_LIB.T6G(SCH_1):PAGE37_I167@PURE_QUANTA.GENOA_SP5(CHIPS)':
 'MAB_DQS_H5': CDS_PINID='MAB_DQS_H5';
NODE_NAME     J24 250
 '@T6G_MB_LIB.T6G(SCH_1):PAGE97_I238@PURE_QUANTA.SCONN288_DDR506112002KQ(CHIPS)':
 'DQS5_B_T||TDQS5_B_T': CDS_PINID='\dqs5_b_t||tdqs5_b_t\';
NET_NAME
'M_A_CPU1_SB_DQS_DP<6>'
 '@T6G_MB_LIB.T6G(SCH_1):M_A_CPU1_SB_DQS_DP'<6>:
 C_SIGNAL='@t6g_mb_lib.t6g(sch_1):m_a_cpu1_sb_dqs_dp(6)';
NODE_NAME     U26 CM72
 '@T6G_MB_LIB.T6G(SCH_1):PAGE37_I167@PURE_QUANTA.GENOA_SP5(CHIPS)':
 'MAB_DQS_H6': CDS_PINID='MAB_DQS_H6';
NODE_NAME     J24 261
 '@T6G_MB_LIB.T6G(SCH_1):PAGE97_I238@PURE_QUANTA.SCONN288_DDR506112002KQ(CHIPS)':
 'DQS6_B_T||TDQS6_B_T': CDS_PINID='\dqs6_b_t||tdqs6_b_t\';
NET_NAME
'M_A_CPU1_SB_DQS_DP<7>'
 '@T6G_MB_LIB.T6G(SCH_1):M_A_CPU1_SB_DQS_DP'<7>:
 C_SIGNAL='@t6g_mb_lib.t6g(sch_1):m_a_cpu1_sb_dqs_dp(7)';
NODE_NAME     U26 CV72
 '@T6G_MB_LIB.T6G(SCH_1):PAGE37_I167@PURE_QUANTA.GENOA_SP5(CHIPS)':
 'MAB_DQS_H7': CDS_PINID='MAB_DQS_H7';
NODE_NAME     J24 272
 '@T6G_MB_LIB.T6G(SCH_1):PAGE97_I238@PURE_QUANTA.SCONN288_DDR506112002KQ(CHIPS)':
 'DQS7_B_T||TDQS7_B_T': CDS_PINID='\dqs7_b_t||tdqs7_b_t\';
NET_NAME
'M_A_CPU1_SB_DQS_DP<8>'
 '@T6G_MB_LIB.T6G(SCH_1):M_A_CPU1_SB_DQS_DP'<8>:
 C_SIGNAL='@t6g_mb_lib.t6g(sch_1):m_a_cpu1_sb_dqs_dp(8)';
NODE_NAME     U26 DD72
 '@T6G_MB_LIB.T6G(SCH_1):PAGE37_I167@PURE_QUANTA.GENOA_SP5(CHIPS)':
 'MAB_DQS_H8': CDS_PINID='MAB_DQS_H8';
NODE_NAME     J24 283
 '@T6G_MB_LIB.T6G(SCH_1):PAGE97_I238@PURE_QUANTA.SCONN288_DDR506112002KQ(CHIPS)':
 'DQS8_B_T||TDQS8_B_T': CDS_PINID='\dqs8_b_t||tdqs8_b_t\';
NET_NAME
'M_A_CPU1_SB_DQS_DP<9>'
 '@T6G_MB_LIB.T6G(SCH_1):M_A_CPU1_SB_DQS_DP'<9>:
 C_SIGNAL='@t6g_mb_lib.t6g(sch_1):m_a_cpu1_sb_dqs_dp(9)';
NODE_NAME     U26 BV74
 '@T6G_MB_LIB.T6G(SCH_1):PAGE37_I167@PURE_QUANTA.GENOA_SP5(CHIPS)':
 'MAB_DQS_H9': CDS_PINID='MAB_DQS_H9';
NODE_NAME     J24 93
 '@T6G_MB_LIB.T6G(SCH_1):PAGE97_I238@PURE_QUANTA.SCONN288_DDR506112002KQ(CHIPS)':
 'DQS9_B_T||TDQS9_B_T||DBI4_B_N': CDS_PINID='\dqs9_b_t||tdqs9_b_t||dbi4_b_n\';
NET_NAME
'M_A_CPU1_SB_PAR'
 '@T6G_MB_LIB.T6G(SCH_1):M_A_CPU1_SB_PAR':
 C_SIGNAL='@t6g_mb_lib.t6g(sch_1):m_a_cpu1_sb_par';
NODE_NAME     U26 BL74
 '@T6G_MB_LIB.T6G(SCH_1):PAGE37_I167@PURE_QUANTA.GENOA_SP5(CHIPS)':
 'MAB_PAR': CDS_PINID='MAB_PAR';
NODE_NAME     J24 227
 '@T6G_MB_LIB.T6G(SCH_1):PAGE97_I22@PURE_QUANTA.SCONN288_DDR506112002KQ(CHIPS)':
 'PAR_B': CDS_PINID='PAR_B';
NET_NAME
'M_A_CPU1_SB_RSP<0>'
 '@T6G_MB_LIB.T6G(SCH_1):M_A_CPU1_SB_RSP'<0>:
 C_SIGNAL='@t6g_mb_lib.t6g(sch_1):m_a_cpu1_sb_rsp(0)';
NODE_NAME     U26 BP74
 '@T6G_MB_LIB.T6G(SCH_1):PAGE37_I167@PURE_QUANTA.GENOA_SP5(CHIPS)':
 'MAB0_RSP_L': CDS_PINID='MAB0_RSP_L';
NODE_NAME     J24 87
 '@T6G_MB_LIB.T6G(SCH_1):PAGE97_I22@PURE_QUANTA.SCONN288_DDR506112002KQ(CHIPS)':
 'LBS||RSP_B_N': CDS_PINID='\lbs||rsp_b_n\';
NET_NAME
'M_B_CPU0_ALERT_N'
 '@T6G_MB_LIB.T6G(SCH_1):M_B_CPU0_ALERT_N':
 C_SIGNAL='@t6g_mb_lib.t6g(sch_1):m_b_cpu0_alert_n';
NODE_NAME     R376 1
 '@T6G_MB_LIB.T6G(SCH_1):PAGE11_I327@PURE_QUANTA.Q_RES(CHIPS)':
 'A': CDS_PINID='A';
NODE_NAME     J15 62
 '@T6G_MB_LIB.T6G(SCH_1):PAGE86_I350@PURE_QUANTA.SCONN288_DDR506112002KQ(CHIPS)':
 'ALERT_N': CDS_PINID='ALERT_N';
NET_NAME
'M_B_CPU0_ALERT_R_N'
 '@T6G_MB_LIB.T6G(SCH_1):M_B_CPU0_ALERT_R_N':
 C_SIGNAL='@t6g_mb_lib.t6g(sch_1):m_b_cpu0_alert_r_n';
NODE_NAME     U25 AT62
 '@T6G_MB_LIB.T6G(SCH_1):PAGE11_I171@PURE_QUANTA.GENOA_SP5(CHIPS)':
 'MB_ALERT_L': CDS_PINID='MB_ALERT_L';
NODE_NAME     R376 2
 '@T6G_MB_LIB.T6G(SCH_1):PAGE11_I327@PURE_QUANTA.Q_RES(CHIPS)':
 'B': CDS_PINID='B';
NET_NAME
'M_B_CPU0_CLK_DN<0>'
 '@T6G_MB_LIB.T6G(SCH_1):M_B_CPU0_CLK_DN'<0>:
 C_SIGNAL='@t6g_mb_lib.t6g(sch_1):m_b_cpu0_clk_dn(0)';
NODE_NAME     U25 BD63
 '@T6G_MB_LIB.T6G(SCH_1):PAGE11_I171@PURE_QUANTA.GENOA_SP5(CHIPS)':
 'MB0_CLK_L': CDS_PINID='MB0_CLK_L';
NODE_NAME     J15 218
 '@T6G_MB_LIB.T6G(SCH_1):PAGE86_I350@PURE_QUANTA.SCONN288_DDR506112002KQ(CHIPS)':
 'CK_C': CDS_PINID='CK_C';
NET_NAME
'M_B_CPU0_CLK_DP<0>'
 '@T6G_MB_LIB.T6G(SCH_1):M_B_CPU0_CLK_DP'<0>:
 C_SIGNAL='@t6g_mb_lib.t6g(sch_1):m_b_cpu0_clk_dp(0)';
NODE_NAME     U25 BC64
 '@T6G_MB_LIB.T6G(SCH_1):PAGE11_I171@PURE_QUANTA.GENOA_SP5(CHIPS)':
 'MB0_CLK_H': CDS_PINID='MB0_CLK_H';
NODE_NAME     J15 217
 '@T6G_MB_LIB.T6G(SCH_1):PAGE86_I350@PURE_QUANTA.SCONN288_DDR506112002KQ(CHIPS)':
 'CK_T': CDS_PINID='CK_T';
NET_NAME
'M_B_CPU0_RESET_N'
 '@T6G_MB_LIB.T6G(SCH_1):M_B_CPU0_RESET_N':
 C_SIGNAL='@t6g_mb_lib.t6g(sch_1):m_b_cpu0_reset_n';
NODE_NAME     U25 AU62
 '@T6G_MB_LIB.T6G(SCH_1):PAGE11_I171@PURE_QUANTA.GENOA_SP5(CHIPS)':
 'MB_RESET_L': CDS_PINID='MB_RESET_L';
NODE_NAME     J15 207
 '@T6G_MB_LIB.T6G(SCH_1):PAGE86_I350@PURE_QUANTA.SCONN288_DDR506112002KQ(CHIPS)':
 'RESET_N': CDS_PINID='RESET_N';
NET_NAME
'M_B_CPU0_SA_CA<0>'
 '@T6G_MB_LIB.T6G(SCH_1):M_B_CPU0_SA_CA'<0>:
 C_SIGNAL='@t6g_mb_lib.t6g(sch_1):m_b_cpu0_sa_ca(0)';
NODE_NAME     U25 AW64
 '@T6G_MB_LIB.T6G(SCH_1):PAGE11_I171@PURE_QUANTA.GENOA_SP5(CHIPS)':
 'MBA_CA0': CDS_PINID='MBA_CA0';
NODE_NAME     J15 66
 '@T6G_MB_LIB.T6G(SCH_1):PAGE86_I350@PURE_QUANTA.SCONN288_DDR506112002KQ(CHIPS)':
 'CA0_A': CDS_PINID='CA0_A';
NET_NAME
'M_B_CPU0_SA_CA<1>'
 '@T6G_MB_LIB.T6G(SCH_1):M_B_CPU0_SA_CA'<1>:
 C_SIGNAL='@t6g_mb_lib.t6g(sch_1):m_b_cpu0_sa_ca(1)';
NODE_NAME     U25 AY63
 '@T6G_MB_LIB.T6G(SCH_1):PAGE11_I171@PURE_QUANTA.GENOA_SP5(CHIPS)':
 'MBA_CA1': CDS_PINID='MBA_CA1';
NODE_NAME     J15 211
 '@T6G_MB_LIB.T6G(SCH_1):PAGE86_I350@PURE_QUANTA.SCONN288_DDR506112002KQ(CHIPS)':
 'CA1_A': CDS_PINID='CA1_A';
NET_NAME
'M_B_CPU0_SA_CA<2>'
 '@T6G_MB_LIB.T6G(SCH_1):M_B_CPU0_SA_CA'<2>:
 C_SIGNAL='@t6g_mb_lib.t6g(sch_1):m_b_cpu0_sa_ca(2)';
NODE_NAME     U25 AY62
 '@T6G_MB_LIB.T6G(SCH_1):PAGE11_I171@PURE_QUANTA.GENOA_SP5(CHIPS)':
 'MBA_CA2': CDS_PINID='MBA_CA2';
NODE_NAME     J15 68
 '@T6G_MB_LIB.T6G(SCH_1):PAGE86_I350@PURE_QUANTA.SCONN288_DDR506112002KQ(CHIPS)':
 'CA2_A': CDS_PINID='CA2_A';
NET_NAME
'M_B_CPU0_SA_CA<3>'
 '@T6G_MB_LIB.T6G(SCH_1):M_B_CPU0_SA_CA'<3>:
 C_SIGNAL='@t6g_mb_lib.t6g(sch_1):m_b_cpu0_sa_ca(3)';
NODE_NAME     U25 BA62
 '@T6G_MB_LIB.T6G(SCH_1):PAGE11_I171@PURE_QUANTA.GENOA_SP5(CHIPS)':
 'MBA_CA3': CDS_PINID='MBA_CA3';
NODE_NAME     J15 213
 '@T6G_MB_LIB.T6G(SCH_1):PAGE86_I350@PURE_QUANTA.SCONN288_DDR506112002KQ(CHIPS)':
 'CA3_A': CDS_PINID='CA3_A';
NET_NAME
'M_B_CPU0_SA_CA<4>'
 '@T6G_MB_LIB.T6G(SCH_1):M_B_CPU0_SA_CA'<4>:
 C_SIGNAL='@t6g_mb_lib.t6g(sch_1):m_b_cpu0_sa_ca(4)';
NODE_NAME     U25 BA64
 '@T6G_MB_LIB.T6G(SCH_1):PAGE11_I171@PURE_QUANTA.GENOA_SP5(CHIPS)':
 'MBA_CA4': CDS_PINID='MBA_CA4';
NODE_NAME     J15 70
 '@T6G_MB_LIB.T6G(SCH_1):PAGE86_I350@PURE_QUANTA.SCONN288_DDR506112002KQ(CHIPS)':
 'CA4_A': CDS_PINID='CA4_A';
NET_NAME
'M_B_CPU0_SA_CA<5>'
 '@T6G_MB_LIB.T6G(SCH_1):M_B_CPU0_SA_CA'<5>:
 C_SIGNAL='@t6g_mb_lib.t6g(sch_1):m_b_cpu0_sa_ca(5)';
NODE_NAME     U25 BB63
 '@T6G_MB_LIB.T6G(SCH_1):PAGE11_I171@PURE_QUANTA.GENOA_SP5(CHIPS)':
 'MBA_CA5': CDS_PINID='MBA_CA5';
NODE_NAME     J15 215
 '@T6G_MB_LIB.T6G(SCH_1):PAGE86_I350@PURE_QUANTA.SCONN288_DDR506112002KQ(CHIPS)':
 'CA5_A': CDS_PINID='CA5_A';
NET_NAME
'M_B_CPU0_SA_CA<6>'
 '@T6G_MB_LIB.T6G(SCH_1):M_B_CPU0_SA_CA'<6>:
 C_SIGNAL='@t6g_mb_lib.t6g(sch_1):m_b_cpu0_sa_ca(6)';
NODE_NAME     U25 BB62
 '@T6G_MB_LIB.T6G(SCH_1):PAGE11_I171@PURE_QUANTA.GENOA_SP5(CHIPS)':
 'MBA_CA6': CDS_PINID='MBA_CA6';
NODE_NAME     J15 72
 '@T6G_MB_LIB.T6G(SCH_1):PAGE86_I350@PURE_QUANTA.SCONN288_DDR506112002KQ(CHIPS)':
 'CA6_A': CDS_PINID='CA6_A';
NET_NAME
'M_B_CPU0_SA_CB<0>'
 '@T6G_MB_LIB.T6G(SCH_1):M_B_CPU0_SA_CB'<0>:
 C_SIGNAL='@t6g_mb_lib.t6g(sch_1):m_b_cpu0_sa_cb(0)';
NODE_NAME     U25 AJ64
 '@T6G_MB_LIB.T6G(SCH_1):PAGE11_I171@PURE_QUANTA.GENOA_SP5(CHIPS)':
 'MBA_CHECK0': CDS_PINID='MBA_CHECK0';
NODE_NAME     J15 51
 '@T6G_MB_LIB.T6G(SCH_1):PAGE86_I350@PURE_QUANTA.SCONN288_DDR506112002KQ(CHIPS)':
 'CB0_A': CDS_PINID='CB0_A';
NET_NAME
'M_B_CPU0_SA_CB<1>'
 '@T6G_MB_LIB.T6G(SCH_1):M_B_CPU0_SA_CB'<1>:
 C_SIGNAL='@t6g_mb_lib.t6g(sch_1):m_b_cpu0_sa_cb(1)';
NODE_NAME     U25 AK62
 '@T6G_MB_LIB.T6G(SCH_1):PAGE11_I171@PURE_QUANTA.GENOA_SP5(CHIPS)':
 'MBA_CHECK1': CDS_PINID='MBA_CHECK1';
NODE_NAME     J15 53
 '@T6G_MB_LIB.T6G(SCH_1):PAGE86_I350@PURE_QUANTA.SCONN288_DDR506112002KQ(CHIPS)':
 'CB1_A': CDS_PINID='CB1_A';
NET_NAME
'M_B_CPU0_SA_CB<2>'
 '@T6G_MB_LIB.T6G(SCH_1):M_B_CPU0_SA_CB'<2>:
 C_SIGNAL='@t6g_mb_lib.t6g(sch_1):m_b_cpu0_sa_cb(2)';
NODE_NAME     U25 AK63
 '@T6G_MB_LIB.T6G(SCH_1):PAGE11_I171@PURE_QUANTA.GENOA_SP5(CHIPS)':
 'MBA_CHECK2': CDS_PINID='MBA_CHECK2';
NODE_NAME     J15 196
 '@T6G_MB_LIB.T6G(SCH_1):PAGE86_I350@PURE_QUANTA.SCONN288_DDR506112002KQ(CHIPS)':
 'CB2_A': CDS_PINID='CB2_A';
NET_NAME
'M_B_CPU0_SA_CB<3>'
 '@T6G_MB_LIB.T6G(SCH_1):M_B_CPU0_SA_CB'<3>:
 C_SIGNAL='@t6g_mb_lib.t6g(sch_1):m_b_cpu0_sa_cb(3)';
NODE_NAME     U25 AL62
 '@T6G_MB_LIB.T6G(SCH_1):PAGE11_I171@PURE_QUANTA.GENOA_SP5(CHIPS)':
 'MBA_CHECK3': CDS_PINID='MBA_CHECK3';
NODE_NAME     J15 198
 '@T6G_MB_LIB.T6G(SCH_1):PAGE86_I350@PURE_QUANTA.SCONN288_DDR506112002KQ(CHIPS)':
 'CB3_A': CDS_PINID='CB3_A';
NET_NAME
'M_B_CPU0_SA_CB<4>'
 '@T6G_MB_LIB.T6G(SCH_1):M_B_CPU0_SA_CB'<4>:
 C_SIGNAL='@t6g_mb_lib.t6g(sch_1):m_b_cpu0_sa_cb(4)';
NODE_NAME     U25 AN64
 '@T6G_MB_LIB.T6G(SCH_1):PAGE11_I171@PURE_QUANTA.GENOA_SP5(CHIPS)':
 'MBA_CHECK4': CDS_PINID='MBA_CHECK4';
NODE_NAME     J15 58
 '@T6G_MB_LIB.T6G(SCH_1):PAGE86_I350@PURE_QUANTA.SCONN288_DDR506112002KQ(CHIPS)':
 'CB4_A': CDS_PINID='CB4_A';
NET_NAME
'M_B_CPU0_SA_CB<5>'
 '@T6G_MB_LIB.T6G(SCH_1):M_B_CPU0_SA_CB'<5>:
 C_SIGNAL='@t6g_mb_lib.t6g(sch_1):m_b_cpu0_sa_cb(5)';
NODE_NAME     U25 AP62
 '@T6G_MB_LIB.T6G(SCH_1):PAGE11_I171@PURE_QUANTA.GENOA_SP5(CHIPS)':
 'MBA_CHECK5': CDS_PINID='MBA_CHECK5';
NODE_NAME     J15 60
 '@T6G_MB_LIB.T6G(SCH_1):PAGE86_I350@PURE_QUANTA.SCONN288_DDR506112002KQ(CHIPS)':
 'CB5_A': CDS_PINID='CB5_A';
NET_NAME
'M_B_CPU0_SA_CB<6>'
 '@T6G_MB_LIB.T6G(SCH_1):M_B_CPU0_SA_CB'<6>:
 C_SIGNAL='@t6g_mb_lib.t6g(sch_1):m_b_cpu0_sa_cb(6)';
NODE_NAME     U25 AP63
 '@T6G_MB_LIB.T6G(SCH_1):PAGE11_I171@PURE_QUANTA.GENOA_SP5(CHIPS)':
 'MBA_CHECK6': CDS_PINID='MBA_CHECK6';
NODE_NAME     J15 203
 '@T6G_MB_LIB.T6G(SCH_1):PAGE86_I350@PURE_QUANTA.SCONN288_DDR506112002KQ(CHIPS)':
 'CB6_A': CDS_PINID='CB6_A';
NET_NAME
'M_B_CPU0_SA_CB<7>'
 '@T6G_MB_LIB.T6G(SCH_1):M_B_CPU0_SA_CB'<7>:
 C_SIGNAL='@t6g_mb_lib.t6g(sch_1):m_b_cpu0_sa_cb(7)';
NODE_NAME     U25 AR62
 '@T6G_MB_LIB.T6G(SCH_1):PAGE11_I171@PURE_QUANTA.GENOA_SP5(CHIPS)':
 'MBA_CHECK7': CDS_PINID='MBA_CHECK7';
NODE_NAME     J15 205
 '@T6G_MB_LIB.T6G(SCH_1):PAGE86_I350@PURE_QUANTA.SCONN288_DDR506112002KQ(CHIPS)':
 'CB7_A': CDS_PINID='CB7_A';
NET_NAME
'M_B_CPU0_SA_CS_N<0>'
 '@T6G_MB_LIB.T6G(SCH_1):M_B_CPU0_SA_CS_N'<0>:
 C_SIGNAL='@t6g_mb_lib.t6g(sch_1):m_b_cpu0_sa_cs_n(0)';
NODE_NAME     U25 AV63
 '@T6G_MB_LIB.T6G(SCH_1):PAGE11_I171@PURE_QUANTA.GENOA_SP5(CHIPS)':
 'MBA0_CS_L0': CDS_PINID='MBA0_CS_L0';
NODE_NAME     J15 64
 '@T6G_MB_LIB.T6G(SCH_1):PAGE86_I350@PURE_QUANTA.SCONN288_DDR506112002KQ(CHIPS)':
 'CS0_A_N': CDS_PINID='CS0_A_N';
NET_NAME
'M_B_CPU0_SA_CS_N<1>'
 '@T6G_MB_LIB.T6G(SCH_1):M_B_CPU0_SA_CS_N'<1>:
 C_SIGNAL='@t6g_mb_lib.t6g(sch_1):m_b_cpu0_sa_cs_n(1)';
NODE_NAME     U25 AW62
 '@T6G_MB_LIB.T6G(SCH_1):PAGE11_I171@PURE_QUANTA.GENOA_SP5(CHIPS)':
 'MBA0_CS_L1': CDS_PINID='MBA0_CS_L1';
NODE_NAME     J15 209
 '@T6G_MB_LIB.T6G(SCH_1):PAGE86_I350@PURE_QUANTA.SCONN288_DDR506112002KQ(CHIPS)':
 'CS1_A_N': CDS_PINID='CS1_A_N';
NET_NAME
'M_B_CPU0_SA_DQ<0>'
 '@T6G_MB_LIB.T6G(SCH_1):M_B_CPU0_SA_DQ'<0>:
 C_SIGNAL='@t6g_mb_lib.t6g(sch_1):m_b_cpu0_sa_dq(0)';
NODE_NAME     U25 E64
 '@T6G_MB_LIB.T6G(SCH_1):PAGE11_I171@PURE_QUANTA.GENOA_SP5(CHIPS)':
 'MBA_DATA0': CDS_PINID='MBA_DATA0';
NODE_NAME     J15 7
 '@T6G_MB_LIB.T6G(SCH_1):PAGE86_I350@PURE_QUANTA.SCONN288_DDR506112002KQ(CHIPS)':
 'DQ0_A': CDS_PINID='DQ0_A';
NET_NAME
'M_B_CPU0_SA_DQ<10>'
 '@T6G_MB_LIB.T6G(SCH_1):M_B_CPU0_SA_DQ'<10>:
 C_SIGNAL='@t6g_mb_lib.t6g(sch_1):m_b_cpu0_sa_dq(10)';
NODE_NAME     U25 M63
 '@T6G_MB_LIB.T6G(SCH_1):PAGE11_I171@PURE_QUANTA.GENOA_SP5(CHIPS)':
 'MBA_DATA10': CDS_PINID='MBA_DATA10';
NODE_NAME     J15 163
 '@T6G_MB_LIB.T6G(SCH_1):PAGE86_I350@PURE_QUANTA.SCONN288_DDR506112002KQ(CHIPS)':
 'DQ10_A': CDS_PINID='DQ10_A';
NET_NAME
'M_B_CPU0_SA_DQ<11>'
 '@T6G_MB_LIB.T6G(SCH_1):M_B_CPU0_SA_DQ'<11>:
 C_SIGNAL='@t6g_mb_lib.t6g(sch_1):m_b_cpu0_sa_dq(11)';
NODE_NAME     U25 N62
 '@T6G_MB_LIB.T6G(SCH_1):PAGE11_I171@PURE_QUANTA.GENOA_SP5(CHIPS)':
 'MBA_DATA11': CDS_PINID='MBA_DATA11';
NODE_NAME     J15 165
 '@T6G_MB_LIB.T6G(SCH_1):PAGE86_I350@PURE_QUANTA.SCONN288_DDR506112002KQ(CHIPS)':
 'DQ11_A': CDS_PINID='DQ11_A';
NET_NAME
'M_B_CPU0_SA_DQ<12>'
 '@T6G_MB_LIB.T6G(SCH_1):M_B_CPU0_SA_DQ'<12>:
 C_SIGNAL='@t6g_mb_lib.t6g(sch_1):m_b_cpu0_sa_dq(12)';
NODE_NAME     U25 R64
 '@T6G_MB_LIB.T6G(SCH_1):PAGE11_I171@PURE_QUANTA.GENOA_SP5(CHIPS)':
 'MBA_DATA12': CDS_PINID='MBA_DATA12';
NODE_NAME     J15 25
 '@T6G_MB_LIB.T6G(SCH_1):PAGE86_I350@PURE_QUANTA.SCONN288_DDR506112002KQ(CHIPS)':
 'DQ12_A': CDS_PINID='DQ12_A';
NET_NAME
'M_B_CPU0_SA_DQ<13>'
 '@T6G_MB_LIB.T6G(SCH_1):M_B_CPU0_SA_DQ'<13>:
 C_SIGNAL='@t6g_mb_lib.t6g(sch_1):m_b_cpu0_sa_dq(13)';
NODE_NAME     U25 T62
 '@T6G_MB_LIB.T6G(SCH_1):PAGE11_I171@PURE_QUANTA.GENOA_SP5(CHIPS)':
 'MBA_DATA13': CDS_PINID='MBA_DATA13';
NODE_NAME     J15 27
 '@T6G_MB_LIB.T6G(SCH_1):PAGE86_I350@PURE_QUANTA.SCONN288_DDR506112002KQ(CHIPS)':
 'DQ13_A': CDS_PINID='DQ13_A';
NET_NAME
'M_B_CPU0_SA_DQ<14>'
 '@T6G_MB_LIB.T6G(SCH_1):M_B_CPU0_SA_DQ'<14>:
 C_SIGNAL='@t6g_mb_lib.t6g(sch_1):m_b_cpu0_sa_dq(14)';
NODE_NAME     U25 T63
 '@T6G_MB_LIB.T6G(SCH_1):PAGE11_I171@PURE_QUANTA.GENOA_SP5(CHIPS)':
 'MBA_DATA14': CDS_PINID='MBA_DATA14';
NODE_NAME     J15 170
 '@T6G_MB_LIB.T6G(SCH_1):PAGE86_I350@PURE_QUANTA.SCONN288_DDR506112002KQ(CHIPS)':
 'DQ14_A': CDS_PINID='DQ14_A';
NET_NAME
'M_B_CPU0_SA_DQ<15>'
 '@T6G_MB_LIB.T6G(SCH_1):M_B_CPU0_SA_DQ'<15>:
 C_SIGNAL='@t6g_mb_lib.t6g(sch_1):m_b_cpu0_sa_dq(15)';
NODE_NAME     U25 U62
 '@T6G_MB_LIB.T6G(SCH_1):PAGE11_I171@PURE_QUANTA.GENOA_SP5(CHIPS)':
 'MBA_DATA15': CDS_PINID='MBA_DATA15';
NODE_NAME     J15 172
 '@T6G_MB_LIB.T6G(SCH_1):PAGE86_I350@PURE_QUANTA.SCONN288_DDR506112002KQ(CHIPS)':
 'DQ15_A': CDS_PINID='DQ15_A';
NET_NAME
'M_B_CPU0_SA_DQ<16>'
 '@T6G_MB_LIB.T6G(SCH_1):M_B_CPU0_SA_DQ'<16>:
 C_SIGNAL='@t6g_mb_lib.t6g(sch_1):m_b_cpu0_sa_dq(16)';
NODE_NAME     U25 U64
 '@T6G_MB_LIB.T6G(SCH_1):PAGE11_I171@PURE_QUANTA.GENOA_SP5(CHIPS)':
 'MBA_DATA16': CDS_PINID='MBA_DATA16';
NODE_NAME     J15 29
 '@T6G_MB_LIB.T6G(SCH_1):PAGE86_I350@PURE_QUANTA.SCONN288_DDR506112002KQ(CHIPS)':
 'DQ16_A': CDS_PINID='DQ16_A';
NET_NAME
'M_B_CPU0_SA_DQ<17>'
 '@T6G_MB_LIB.T6G(SCH_1):M_B_CPU0_SA_DQ'<17>:
 C_SIGNAL='@t6g_mb_lib.t6g(sch_1):m_b_cpu0_sa_dq(17)';
NODE_NAME     U25 V62
 '@T6G_MB_LIB.T6G(SCH_1):PAGE11_I171@PURE_QUANTA.GENOA_SP5(CHIPS)':
 'MBA_DATA17': CDS_PINID='MBA_DATA17';
NODE_NAME     J15 31
 '@T6G_MB_LIB.T6G(SCH_1):PAGE86_I350@PURE_QUANTA.SCONN288_DDR506112002KQ(CHIPS)':
 'DQ17_A': CDS_PINID='DQ17_A';
NET_NAME
'M_B_CPU0_SA_DQ<18>'
 '@T6G_MB_LIB.T6G(SCH_1):M_B_CPU0_SA_DQ'<18>:
 C_SIGNAL='@t6g_mb_lib.t6g(sch_1):m_b_cpu0_sa_dq(18)';
NODE_NAME     U25 V63
 '@T6G_MB_LIB.T6G(SCH_1):PAGE11_I171@PURE_QUANTA.GENOA_SP5(CHIPS)':
 'MBA_DATA18': CDS_PINID='MBA_DATA18';
NODE_NAME     J15 174
 '@T6G_MB_LIB.T6G(SCH_1):PAGE86_I350@PURE_QUANTA.SCONN288_DDR506112002KQ(CHIPS)':
 'DQ18_A': CDS_PINID='DQ18_A';
NET_NAME
'M_B_CPU0_SA_DQ<19>'
 '@T6G_MB_LIB.T6G(SCH_1):M_B_CPU0_SA_DQ'<19>:
 C_SIGNAL='@t6g_mb_lib.t6g(sch_1):m_b_cpu0_sa_dq(19)';
NODE_NAME     U25 W62
 '@T6G_MB_LIB.T6G(SCH_1):PAGE11_I171@PURE_QUANTA.GENOA_SP5(CHIPS)':
 'MBA_DATA19': CDS_PINID='MBA_DATA19';
NODE_NAME     J15 176
 '@T6G_MB_LIB.T6G(SCH_1):PAGE86_I350@PURE_QUANTA.SCONN288_DDR506112002KQ(CHIPS)':
 'DQ19_A': CDS_PINID='DQ19_A';
NET_NAME
'M_B_CPU0_SA_DQ<1>'
 '@T6G_MB_LIB.T6G(SCH_1):M_B_CPU0_SA_DQ'<1>:
 C_SIGNAL='@t6g_mb_lib.t6g(sch_1):m_b_cpu0_sa_dq(1)';
NODE_NAME     U25 F62
 '@T6G_MB_LIB.T6G(SCH_1):PAGE11_I171@PURE_QUANTA.GENOA_SP5(CHIPS)':
 'MBA_DATA1': CDS_PINID='MBA_DATA1';
NODE_NAME     J15 9
 '@T6G_MB_LIB.T6G(SCH_1):PAGE86_I350@PURE_QUANTA.SCONN288_DDR506112002KQ(CHIPS)':
 'DQ1_A': CDS_PINID='DQ1_A';
NET_NAME
'M_B_CPU0_SA_DQ<20>'
 '@T6G_MB_LIB.T6G(SCH_1):M_B_CPU0_SA_DQ'<20>:
 C_SIGNAL='@t6g_mb_lib.t6g(sch_1):m_b_cpu0_sa_dq(20)';
NODE_NAME     U25 AA64
 '@T6G_MB_LIB.T6G(SCH_1):PAGE11_I171@PURE_QUANTA.GENOA_SP5(CHIPS)':
 'MBA_DATA20': CDS_PINID='MBA_DATA20';
NODE_NAME     J15 36
 '@T6G_MB_LIB.T6G(SCH_1):PAGE86_I350@PURE_QUANTA.SCONN288_DDR506112002KQ(CHIPS)':
 'DQ20_A': CDS_PINID='DQ20_A';
NET_NAME
'M_B_CPU0_SA_DQ<21>'
 '@T6G_MB_LIB.T6G(SCH_1):M_B_CPU0_SA_DQ'<21>:
 C_SIGNAL='@t6g_mb_lib.t6g(sch_1):m_b_cpu0_sa_dq(21)';
NODE_NAME     U25 AB62
 '@T6G_MB_LIB.T6G(SCH_1):PAGE11_I171@PURE_QUANTA.GENOA_SP5(CHIPS)':
 'MBA_DATA21': CDS_PINID='MBA_DATA21';
NODE_NAME     J15 38
 '@T6G_MB_LIB.T6G(SCH_1):PAGE86_I350@PURE_QUANTA.SCONN288_DDR506112002KQ(CHIPS)':
 'DQ21_A': CDS_PINID='DQ21_A';
NET_NAME
'M_B_CPU0_SA_DQ<22>'
 '@T6G_MB_LIB.T6G(SCH_1):M_B_CPU0_SA_DQ'<22>:
 C_SIGNAL='@t6g_mb_lib.t6g(sch_1):m_b_cpu0_sa_dq(22)';
NODE_NAME     U25 AB63
 '@T6G_MB_LIB.T6G(SCH_1):PAGE11_I171@PURE_QUANTA.GENOA_SP5(CHIPS)':
 'MBA_DATA22': CDS_PINID='MBA_DATA22';
NODE_NAME     J15 181
 '@T6G_MB_LIB.T6G(SCH_1):PAGE86_I350@PURE_QUANTA.SCONN288_DDR506112002KQ(CHIPS)':
 'DQ22_A': CDS_PINID='DQ22_A';
NET_NAME
'M_B_CPU0_SA_DQ<23>'
 '@T6G_MB_LIB.T6G(SCH_1):M_B_CPU0_SA_DQ'<23>:
 C_SIGNAL='@t6g_mb_lib.t6g(sch_1):m_b_cpu0_sa_dq(23)';
NODE_NAME     U25 AC62
 '@T6G_MB_LIB.T6G(SCH_1):PAGE11_I171@PURE_QUANTA.GENOA_SP5(CHIPS)':
 'MBA_DATA23': CDS_PINID='MBA_DATA23';
NODE_NAME     J15 183
 '@T6G_MB_LIB.T6G(SCH_1):PAGE86_I350@PURE_QUANTA.SCONN288_DDR506112002KQ(CHIPS)':
 'DQ23_A': CDS_PINID='DQ23_A';
NET_NAME
'M_B_CPU0_SA_DQ<24>'
 '@T6G_MB_LIB.T6G(SCH_1):M_B_CPU0_SA_DQ'<24>:
 C_SIGNAL='@t6g_mb_lib.t6g(sch_1):m_b_cpu0_sa_dq(24)';
NODE_NAME     U25 AC64
 '@T6G_MB_LIB.T6G(SCH_1):PAGE11_I171@PURE_QUANTA.GENOA_SP5(CHIPS)':
 'MBA_DATA24': CDS_PINID='MBA_DATA24';
NODE_NAME     J15 40
 '@T6G_MB_LIB.T6G(SCH_1):PAGE86_I350@PURE_QUANTA.SCONN288_DDR506112002KQ(CHIPS)':
 'DQ24_A': CDS_PINID='DQ24_A';
NET_NAME
'M_B_CPU0_SA_DQ<25>'
 '@T6G_MB_LIB.T6G(SCH_1):M_B_CPU0_SA_DQ'<25>:
 C_SIGNAL='@t6g_mb_lib.t6g(sch_1):m_b_cpu0_sa_dq(25)';
NODE_NAME     U25 AD62
 '@T6G_MB_LIB.T6G(SCH_1):PAGE11_I171@PURE_QUANTA.GENOA_SP5(CHIPS)':
 'MBA_DATA25': CDS_PINID='MBA_DATA25';
NODE_NAME     J15 42
 '@T6G_MB_LIB.T6G(SCH_1):PAGE86_I350@PURE_QUANTA.SCONN288_DDR506112002KQ(CHIPS)':
 'DQ25_A': CDS_PINID='DQ25_A';
NET_NAME
'M_B_CPU0_SA_DQ<26>'
 '@T6G_MB_LIB.T6G(SCH_1):M_B_CPU0_SA_DQ'<26>:
 C_SIGNAL='@t6g_mb_lib.t6g(sch_1):m_b_cpu0_sa_dq(26)';
NODE_NAME     U25 AD63
 '@T6G_MB_LIB.T6G(SCH_1):PAGE11_I171@PURE_QUANTA.GENOA_SP5(CHIPS)':
 'MBA_DATA26': CDS_PINID='MBA_DATA26';
NODE_NAME     J15 185
 '@T6G_MB_LIB.T6G(SCH_1):PAGE86_I350@PURE_QUANTA.SCONN288_DDR506112002KQ(CHIPS)':
 'DQ26_A': CDS_PINID='DQ26_A';
NET_NAME
'M_B_CPU0_SA_DQ<27>'
 '@T6G_MB_LIB.T6G(SCH_1):M_B_CPU0_SA_DQ'<27>:
 C_SIGNAL='@t6g_mb_lib.t6g(sch_1):m_b_cpu0_sa_dq(27)';
NODE_NAME     U25 AE62
 '@T6G_MB_LIB.T6G(SCH_1):PAGE11_I171@PURE_QUANTA.GENOA_SP5(CHIPS)':
 'MBA_DATA27': CDS_PINID='MBA_DATA27';
NODE_NAME     J15 187
 '@T6G_MB_LIB.T6G(SCH_1):PAGE86_I350@PURE_QUANTA.SCONN288_DDR506112002KQ(CHIPS)':
 'DQ27_A': CDS_PINID='DQ27_A';
NET_NAME
'M_B_CPU0_SA_DQ<28>'
 '@T6G_MB_LIB.T6G(SCH_1):M_B_CPU0_SA_DQ'<28>:
 C_SIGNAL='@t6g_mb_lib.t6g(sch_1):m_b_cpu0_sa_dq(28)';
NODE_NAME     U25 AG64
 '@T6G_MB_LIB.T6G(SCH_1):PAGE11_I171@PURE_QUANTA.GENOA_SP5(CHIPS)':
 'MBA_DATA28': CDS_PINID='MBA_DATA28';
NODE_NAME     J15 47
 '@T6G_MB_LIB.T6G(SCH_1):PAGE86_I350@PURE_QUANTA.SCONN288_DDR506112002KQ(CHIPS)':
 'DQ28_A': CDS_PINID='DQ28_A';
NET_NAME
'M_B_CPU0_SA_DQ<29>'
 '@T6G_MB_LIB.T6G(SCH_1):M_B_CPU0_SA_DQ'<29>:
 C_SIGNAL='@t6g_mb_lib.t6g(sch_1):m_b_cpu0_sa_dq(29)';
NODE_NAME     U25 AH62
 '@T6G_MB_LIB.T6G(SCH_1):PAGE11_I171@PURE_QUANTA.GENOA_SP5(CHIPS)':
 'MBA_DATA29': CDS_PINID='MBA_DATA29';
NODE_NAME     J15 49
 '@T6G_MB_LIB.T6G(SCH_1):PAGE86_I350@PURE_QUANTA.SCONN288_DDR506112002KQ(CHIPS)':
 'DQ29_A': CDS_PINID='DQ29_A';
NET_NAME
'M_B_CPU0_SA_DQ<2>'
 '@T6G_MB_LIB.T6G(SCH_1):M_B_CPU0_SA_DQ'<2>:
 C_SIGNAL='@t6g_mb_lib.t6g(sch_1):m_b_cpu0_sa_dq(2)';
NODE_NAME     U25 F63
 '@T6G_MB_LIB.T6G(SCH_1):PAGE11_I171@PURE_QUANTA.GENOA_SP5(CHIPS)':
 'MBA_DATA2': CDS_PINID='MBA_DATA2';
NODE_NAME     J15 152
 '@T6G_MB_LIB.T6G(SCH_1):PAGE86_I350@PURE_QUANTA.SCONN288_DDR506112002KQ(CHIPS)':
 'DQ2_A': CDS_PINID='DQ2_A';
NET_NAME
'M_B_CPU0_SA_DQ<30>'
 '@T6G_MB_LIB.T6G(SCH_1):M_B_CPU0_SA_DQ'<30>:
 C_SIGNAL='@t6g_mb_lib.t6g(sch_1):m_b_cpu0_sa_dq(30)';
NODE_NAME     U25 AH63
 '@T6G_MB_LIB.T6G(SCH_1):PAGE11_I171@PURE_QUANTA.GENOA_SP5(CHIPS)':
 'MBA_DATA30': CDS_PINID='MBA_DATA30';
NODE_NAME     J15 192
 '@T6G_MB_LIB.T6G(SCH_1):PAGE86_I350@PURE_QUANTA.SCONN288_DDR506112002KQ(CHIPS)':
 'DQ30_A': CDS_PINID='DQ30_A';
NET_NAME
'M_B_CPU0_SA_DQ<31>'
 '@T6G_MB_LIB.T6G(SCH_1):M_B_CPU0_SA_DQ'<31>:
 C_SIGNAL='@t6g_mb_lib.t6g(sch_1):m_b_cpu0_sa_dq(31)';
NODE_NAME     U25 AJ62
 '@T6G_MB_LIB.T6G(SCH_1):PAGE11_I171@PURE_QUANTA.GENOA_SP5(CHIPS)':
 'MBA_DATA31': CDS_PINID='MBA_DATA31';
NODE_NAME     J15 194
 '@T6G_MB_LIB.T6G(SCH_1):PAGE86_I350@PURE_QUANTA.SCONN288_DDR506112002KQ(CHIPS)':
 'DQ31_A': CDS_PINID='DQ31_A';
NET_NAME
'M_B_CPU0_SA_DQ<3>'
 '@T6G_MB_LIB.T6G(SCH_1):M_B_CPU0_SA_DQ'<3>:
 C_SIGNAL='@t6g_mb_lib.t6g(sch_1):m_b_cpu0_sa_dq(3)';
NODE_NAME     U25 G62
 '@T6G_MB_LIB.T6G(SCH_1):PAGE11_I171@PURE_QUANTA.GENOA_SP5(CHIPS)':
 'MBA_DATA3': CDS_PINID='MBA_DATA3';
NODE_NAME     J15 154
 '@T6G_MB_LIB.T6G(SCH_1):PAGE86_I350@PURE_QUANTA.SCONN288_DDR506112002KQ(CHIPS)':
 'DQ3_A': CDS_PINID='DQ3_A';
NET_NAME
'M_B_CPU0_SA_DQ<4>'
 '@T6G_MB_LIB.T6G(SCH_1):M_B_CPU0_SA_DQ'<4>:
 C_SIGNAL='@t6g_mb_lib.t6g(sch_1):m_b_cpu0_sa_dq(4)';
NODE_NAME     U25 J64
 '@T6G_MB_LIB.T6G(SCH_1):PAGE11_I171@PURE_QUANTA.GENOA_SP5(CHIPS)':
 'MBA_DATA4': CDS_PINID='MBA_DATA4';
NODE_NAME     J15 14
 '@T6G_MB_LIB.T6G(SCH_1):PAGE86_I350@PURE_QUANTA.SCONN288_DDR506112002KQ(CHIPS)':
 'DQ4_A': CDS_PINID='DQ4_A';
NET_NAME
'M_B_CPU0_SA_DQ<5>'
 '@T6G_MB_LIB.T6G(SCH_1):M_B_CPU0_SA_DQ'<5>:
 C_SIGNAL='@t6g_mb_lib.t6g(sch_1):m_b_cpu0_sa_dq(5)';
NODE_NAME     U25 K62
 '@T6G_MB_LIB.T6G(SCH_1):PAGE11_I171@PURE_QUANTA.GENOA_SP5(CHIPS)':
 'MBA_DATA5': CDS_PINID='MBA_DATA5';
NODE_NAME     J15 16
 '@T6G_MB_LIB.T6G(SCH_1):PAGE86_I350@PURE_QUANTA.SCONN288_DDR506112002KQ(CHIPS)':
 'DQ5_A': CDS_PINID='DQ5_A';
NET_NAME
'M_B_CPU0_SA_DQ<6>'
 '@T6G_MB_LIB.T6G(SCH_1):M_B_CPU0_SA_DQ'<6>:
 C_SIGNAL='@t6g_mb_lib.t6g(sch_1):m_b_cpu0_sa_dq(6)';
NODE_NAME     U25 K63
 '@T6G_MB_LIB.T6G(SCH_1):PAGE11_I171@PURE_QUANTA.GENOA_SP5(CHIPS)':
 'MBA_DATA6': CDS_PINID='MBA_DATA6';
NODE_NAME     J15 159
 '@T6G_MB_LIB.T6G(SCH_1):PAGE86_I350@PURE_QUANTA.SCONN288_DDR506112002KQ(CHIPS)':
 'DQ6_A': CDS_PINID='DQ6_A';
NET_NAME
'M_B_CPU0_SA_DQ<7>'
 '@T6G_MB_LIB.T6G(SCH_1):M_B_CPU0_SA_DQ'<7>:
 C_SIGNAL='@t6g_mb_lib.t6g(sch_1):m_b_cpu0_sa_dq(7)';
NODE_NAME     U25 L62
 '@T6G_MB_LIB.T6G(SCH_1):PAGE11_I171@PURE_QUANTA.GENOA_SP5(CHIPS)':
 'MBA_DATA7': CDS_PINID='MBA_DATA7';
NODE_NAME     J15 161
 '@T6G_MB_LIB.T6G(SCH_1):PAGE86_I350@PURE_QUANTA.SCONN288_DDR506112002KQ(CHIPS)':
 'DQ7_A': CDS_PINID='DQ7_A';
NET_NAME
'M_B_CPU0_SA_DQ<8>'
 '@T6G_MB_LIB.T6G(SCH_1):M_B_CPU0_SA_DQ'<8>:
 C_SIGNAL='@t6g_mb_lib.t6g(sch_1):m_b_cpu0_sa_dq(8)';
NODE_NAME     U25 L64
 '@T6G_MB_LIB.T6G(SCH_1):PAGE11_I171@PURE_QUANTA.GENOA_SP5(CHIPS)':
 'MBA_DATA8': CDS_PINID='MBA_DATA8';
NODE_NAME     J15 18
 '@T6G_MB_LIB.T6G(SCH_1):PAGE86_I350@PURE_QUANTA.SCONN288_DDR506112002KQ(CHIPS)':
 'DQ8_A': CDS_PINID='DQ8_A';
NET_NAME
'M_B_CPU0_SA_DQ<9>'
 '@T6G_MB_LIB.T6G(SCH_1):M_B_CPU0_SA_DQ'<9>:
 C_SIGNAL='@t6g_mb_lib.t6g(sch_1):m_b_cpu0_sa_dq(9)';
NODE_NAME     U25 M62
 '@T6G_MB_LIB.T6G(SCH_1):PAGE11_I171@PURE_QUANTA.GENOA_SP5(CHIPS)':
 'MBA_DATA9': CDS_PINID='MBA_DATA9';
NODE_NAME     J15 20
 '@T6G_MB_LIB.T6G(SCH_1):PAGE86_I350@PURE_QUANTA.SCONN288_DDR506112002KQ(CHIPS)':
 'DQ9_A': CDS_PINID='DQ9_A';
NET_NAME
'M_B_CPU0_SA_DQS_DN<0>'
 '@T6G_MB_LIB.T6G(SCH_1):M_B_CPU0_SA_DQS_DN'<0>:
 C_SIGNAL='@t6g_mb_lib.t6g(sch_1):m_b_cpu0_sa_dqs_dn(0)';
NODE_NAME     U25 H63
 '@T6G_MB_LIB.T6G(SCH_1):PAGE11_I171@PURE_QUANTA.GENOA_SP5(CHIPS)':
 'MBA_DQS_L0': CDS_PINID='MBA_DQS_L0';
NODE_NAME     J15 12
 '@T6G_MB_LIB.T6G(SCH_1):PAGE86_I367@PURE_QUANTA.SCONN288_DDR506112002KQ(CHIPS)':
 'DQS0_A_C': CDS_PINID='DQS0_A_C';
NET_NAME
'M_B_CPU0_SA_DQS_DN<1>'
 '@T6G_MB_LIB.T6G(SCH_1):M_B_CPU0_SA_DQS_DN'<1>:
 C_SIGNAL='@t6g_mb_lib.t6g(sch_1):m_b_cpu0_sa_dqs_dn(1)';
NODE_NAME     U25 P63
 '@T6G_MB_LIB.T6G(SCH_1):PAGE11_I171@PURE_QUANTA.GENOA_SP5(CHIPS)':
 'MBA_DQS_L1': CDS_PINID='MBA_DQS_L1';
NODE_NAME     J15 23
 '@T6G_MB_LIB.T6G(SCH_1):PAGE86_I367@PURE_QUANTA.SCONN288_DDR506112002KQ(CHIPS)':
 'DQS1_A_C': CDS_PINID='DQS1_A_C';
NET_NAME
'M_B_CPU0_SA_DQS_DN<2>'
 '@T6G_MB_LIB.T6G(SCH_1):M_B_CPU0_SA_DQS_DN'<2>:
 C_SIGNAL='@t6g_mb_lib.t6g(sch_1):m_b_cpu0_sa_dqs_dn(2)';
NODE_NAME     U25 Y63
 '@T6G_MB_LIB.T6G(SCH_1):PAGE11_I171@PURE_QUANTA.GENOA_SP5(CHIPS)':
 'MBA_DQS_L2': CDS_PINID='MBA_DQS_L2';
NODE_NAME     J15 34
 '@T6G_MB_LIB.T6G(SCH_1):PAGE86_I367@PURE_QUANTA.SCONN288_DDR506112002KQ(CHIPS)':
 'DQS2_A_C': CDS_PINID='DQS2_A_C';
NET_NAME
'M_B_CPU0_SA_DQS_DN<3>'
 '@T6G_MB_LIB.T6G(SCH_1):M_B_CPU0_SA_DQS_DN'<3>:
 C_SIGNAL='@t6g_mb_lib.t6g(sch_1):m_b_cpu0_sa_dqs_dn(3)';
NODE_NAME     U25 AF63
 '@T6G_MB_LIB.T6G(SCH_1):PAGE11_I171@PURE_QUANTA.GENOA_SP5(CHIPS)':
 'MBA_DQS_L3': CDS_PINID='MBA_DQS_L3';
NODE_NAME     J15 45
 '@T6G_MB_LIB.T6G(SCH_1):PAGE86_I367@PURE_QUANTA.SCONN288_DDR506112002KQ(CHIPS)':
 'DQS3_A_C': CDS_PINID='DQS3_A_C';
NET_NAME
'M_B_CPU0_SA_DQS_DN<4>'
 '@T6G_MB_LIB.T6G(SCH_1):M_B_CPU0_SA_DQS_DN'<4>:
 C_SIGNAL='@t6g_mb_lib.t6g(sch_1):m_b_cpu0_sa_dqs_dn(4)';
NODE_NAME     U25 AM63
 '@T6G_MB_LIB.T6G(SCH_1):PAGE11_I171@PURE_QUANTA.GENOA_SP5(CHIPS)':
 'MBA_DQS_L4': CDS_PINID='MBA_DQS_L4';
NODE_NAME     J15 56
 '@T6G_MB_LIB.T6G(SCH_1):PAGE86_I367@PURE_QUANTA.SCONN288_DDR506112002KQ(CHIPS)':
 'DQS4_A_C': CDS_PINID='DQS4_A_C';
NET_NAME
'M_B_CPU0_SA_DQS_DN<5>'
 '@T6G_MB_LIB.T6G(SCH_1):M_B_CPU0_SA_DQS_DN'<5>:
 C_SIGNAL='@t6g_mb_lib.t6g(sch_1):m_b_cpu0_sa_dqs_dn(5)';
NODE_NAME     U25 H62
 '@T6G_MB_LIB.T6G(SCH_1):PAGE11_I171@PURE_QUANTA.GENOA_SP5(CHIPS)':
 'MBA_DQS_L5': CDS_PINID='MBA_DQS_L5';
NODE_NAME     J15 156
 '@T6G_MB_LIB.T6G(SCH_1):PAGE86_I367@PURE_QUANTA.SCONN288_DDR506112002KQ(CHIPS)':
 'DQS5_A_C||TDQS5_A_C||DQS5_A_T||TDQS5_A_T': CDS_PINID='\dqs5_a_c||tdqs5_a_c||dqs5_a_t||tdqs5_a_t\';
NET_NAME
'M_B_CPU0_SA_DQS_DN<6>'
 '@T6G_MB_LIB.T6G(SCH_1):M_B_CPU0_SA_DQS_DN'<6>:
 C_SIGNAL='@t6g_mb_lib.t6g(sch_1):m_b_cpu0_sa_dqs_dn(6)';
NODE_NAME     U25 P62
 '@T6G_MB_LIB.T6G(SCH_1):PAGE11_I171@PURE_QUANTA.GENOA_SP5(CHIPS)':
 'MBA_DQS_L6': CDS_PINID='MBA_DQS_L6';
NODE_NAME     J15 167
 '@T6G_MB_LIB.T6G(SCH_1):PAGE86_I367@PURE_QUANTA.SCONN288_DDR506112002KQ(CHIPS)':
 'DQS6_A_C||TDQS6_A_C||DQS6_A_T||TDQS6_A_T': CDS_PINID='\dqs6_a_c||tdqs6_a_c||dqs6_a_t||tdqs6_a_t\';
NET_NAME
'M_B_CPU0_SA_DQS_DN<7>'
 '@T6G_MB_LIB.T6G(SCH_1):M_B_CPU0_SA_DQS_DN'<7>:
 C_SIGNAL='@t6g_mb_lib.t6g(sch_1):m_b_cpu0_sa_dqs_dn(7)';
NODE_NAME     U25 Y62
 '@T6G_MB_LIB.T6G(SCH_1):PAGE11_I171@PURE_QUANTA.GENOA_SP5(CHIPS)':
 'MBA_DQS_L7': CDS_PINID='MBA_DQS_L7';
NODE_NAME     J15 178
 '@T6G_MB_LIB.T6G(SCH_1):PAGE86_I367@PURE_QUANTA.SCONN288_DDR506112002KQ(CHIPS)':
 'DQS7_A_C||TDQS7_A_C': CDS_PINID='\dqs7_a_c||tdqs7_a_c\';
NET_NAME
'M_B_CPU0_SA_DQS_DN<8>'
 '@T6G_MB_LIB.T6G(SCH_1):M_B_CPU0_SA_DQS_DN'<8>:
 C_SIGNAL='@t6g_mb_lib.t6g(sch_1):m_b_cpu0_sa_dqs_dn(8)';
NODE_NAME     U25 AF62
 '@T6G_MB_LIB.T6G(SCH_1):PAGE11_I171@PURE_QUANTA.GENOA_SP5(CHIPS)':
 'MBA_DQS_L8': CDS_PINID='MBA_DQS_L8';
NODE_NAME     J15 189
 '@T6G_MB_LIB.T6G(SCH_1):PAGE86_I367@PURE_QUANTA.SCONN288_DDR506112002KQ(CHIPS)':
 'DQS8_A_C||TDQS8_A_C': CDS_PINID='\dqs8_a_c||tdqs8_a_c\';
NET_NAME
'M_B_CPU0_SA_DQS_DN<9>'
 '@T6G_MB_LIB.T6G(SCH_1):M_B_CPU0_SA_DQS_DN'<9>:
 C_SIGNAL='@t6g_mb_lib.t6g(sch_1):m_b_cpu0_sa_dqs_dn(9)';
NODE_NAME     U25 AM62
 '@T6G_MB_LIB.T6G(SCH_1):PAGE11_I171@PURE_QUANTA.GENOA_SP5(CHIPS)':
 'MBA_DQS_L9': CDS_PINID='MBA_DQS_L9';
NODE_NAME     J15 200
 '@T6G_MB_LIB.T6G(SCH_1):PAGE86_I367@PURE_QUANTA.SCONN288_DDR506112002KQ(CHIPS)':
 'DQS9_A_C||TDQS9_A_C': CDS_PINID='\dqs9_a_c||tdqs9_a_c\';
NET_NAME
'M_B_CPU0_SA_DQS_DP<0>'
 '@T6G_MB_LIB.T6G(SCH_1):M_B_CPU0_SA_DQS_DP'<0>:
 C_SIGNAL='@t6g_mb_lib.t6g(sch_1):m_b_cpu0_sa_dqs_dp(0)';
NODE_NAME     U25 G64
 '@T6G_MB_LIB.T6G(SCH_1):PAGE11_I171@PURE_QUANTA.GENOA_SP5(CHIPS)':
 'MBA_DQS_H0': CDS_PINID='MBA_DQS_H0';
NODE_NAME     J15 11
 '@T6G_MB_LIB.T6G(SCH_1):PAGE86_I367@PURE_QUANTA.SCONN288_DDR506112002KQ(CHIPS)':
 'DQS0_A_T': CDS_PINID='DQS0_A_T';
NET_NAME
'M_B_CPU0_SA_DQS_DP<1>'
 '@T6G_MB_LIB.T6G(SCH_1):M_B_CPU0_SA_DQS_DP'<1>:
 C_SIGNAL='@t6g_mb_lib.t6g(sch_1):m_b_cpu0_sa_dqs_dp(1)';
NODE_NAME     U25 N64
 '@T6G_MB_LIB.T6G(SCH_1):PAGE11_I171@PURE_QUANTA.GENOA_SP5(CHIPS)':
 'MBA_DQS_H1': CDS_PINID='MBA_DQS_H1';
NODE_NAME     J15 22
 '@T6G_MB_LIB.T6G(SCH_1):PAGE86_I367@PURE_QUANTA.SCONN288_DDR506112002KQ(CHIPS)':
 'DQS1_A_T': CDS_PINID='DQS1_A_T';
NET_NAME
'M_B_CPU0_SA_DQS_DP<2>'
 '@T6G_MB_LIB.T6G(SCH_1):M_B_CPU0_SA_DQS_DP'<2>:
 C_SIGNAL='@t6g_mb_lib.t6g(sch_1):m_b_cpu0_sa_dqs_dp(2)';
NODE_NAME     U25 W64
 '@T6G_MB_LIB.T6G(SCH_1):PAGE11_I171@PURE_QUANTA.GENOA_SP5(CHIPS)':
 'MBA_DQS_H2': CDS_PINID='MBA_DQS_H2';
NODE_NAME     J15 33
 '@T6G_MB_LIB.T6G(SCH_1):PAGE86_I367@PURE_QUANTA.SCONN288_DDR506112002KQ(CHIPS)':
 'DQS2_A_T': CDS_PINID='DQS2_A_T';
NET_NAME
'M_B_CPU0_SA_DQS_DP<3>'
 '@T6G_MB_LIB.T6G(SCH_1):M_B_CPU0_SA_DQS_DP'<3>:
 C_SIGNAL='@t6g_mb_lib.t6g(sch_1):m_b_cpu0_sa_dqs_dp(3)';
NODE_NAME     U25 AE64
 '@T6G_MB_LIB.T6G(SCH_1):PAGE11_I171@PURE_QUANTA.GENOA_SP5(CHIPS)':
 'MBA_DQS_H3': CDS_PINID='MBA_DQS_H3';
NODE_NAME     J15 44
 '@T6G_MB_LIB.T6G(SCH_1):PAGE86_I367@PURE_QUANTA.SCONN288_DDR506112002KQ(CHIPS)':
 'DQS3_A_T': CDS_PINID='DQS3_A_T';
NET_NAME
'M_B_CPU0_SA_DQS_DP<4>'
 '@T6G_MB_LIB.T6G(SCH_1):M_B_CPU0_SA_DQS_DP'<4>:
 C_SIGNAL='@t6g_mb_lib.t6g(sch_1):m_b_cpu0_sa_dqs_dp(4)';
NODE_NAME     U25 AL64
 '@T6G_MB_LIB.T6G(SCH_1):PAGE11_I171@PURE_QUANTA.GENOA_SP5(CHIPS)':
 'MBA_DQS_H4': CDS_PINID='MBA_DQS_H4';
NODE_NAME     J15 55
 '@T6G_MB_LIB.T6G(SCH_1):PAGE86_I367@PURE_QUANTA.SCONN288_DDR506112002KQ(CHIPS)':
 'DQS4_A_T': CDS_PINID='DQS4_A_T';
NET_NAME
'M_B_CPU0_SA_DQS_DP<5>'
 '@T6G_MB_LIB.T6G(SCH_1):M_B_CPU0_SA_DQS_DP'<5>:
 C_SIGNAL='@t6g_mb_lib.t6g(sch_1):m_b_cpu0_sa_dqs_dp(5)';
NODE_NAME     U25 J62
 '@T6G_MB_LIB.T6G(SCH_1):PAGE11_I171@PURE_QUANTA.GENOA_SP5(CHIPS)':
 'MBA_DQS_H5': CDS_PINID='MBA_DQS_H5';
NODE_NAME     J15 157
 '@T6G_MB_LIB.T6G(SCH_1):PAGE86_I367@PURE_QUANTA.SCONN288_DDR506112002KQ(CHIPS)':
 'DQS5_A_T||TDQS5_A_T': CDS_PINID='\dqs5_a_t||tdqs5_a_t\';
NET_NAME
'M_B_CPU0_SA_DQS_DP<6>'
 '@T6G_MB_LIB.T6G(SCH_1):M_B_CPU0_SA_DQS_DP'<6>:
 C_SIGNAL='@t6g_mb_lib.t6g(sch_1):m_b_cpu0_sa_dqs_dp(6)';
NODE_NAME     U25 R62
 '@T6G_MB_LIB.T6G(SCH_1):PAGE11_I171@PURE_QUANTA.GENOA_SP5(CHIPS)':
 'MBA_DQS_H6': CDS_PINID='MBA_DQS_H6';
NODE_NAME     J15 168
 '@T6G_MB_LIB.T6G(SCH_1):PAGE86_I367@PURE_QUANTA.SCONN288_DDR506112002KQ(CHIPS)':
 'DQS6_A_T||TDQS6_A_T': CDS_PINID='\dqs6_a_t||tdqs6_a_t\';
NET_NAME
'M_B_CPU0_SA_DQS_DP<7>'
 '@T6G_MB_LIB.T6G(SCH_1):M_B_CPU0_SA_DQS_DP'<7>:
 C_SIGNAL='@t6g_mb_lib.t6g(sch_1):m_b_cpu0_sa_dqs_dp(7)';
NODE_NAME     U25 AA62
 '@T6G_MB_LIB.T6G(SCH_1):PAGE11_I171@PURE_QUANTA.GENOA_SP5(CHIPS)':
 'MBA_DQS_H7': CDS_PINID='MBA_DQS_H7';
NODE_NAME     J15 179
 '@T6G_MB_LIB.T6G(SCH_1):PAGE86_I367@PURE_QUANTA.SCONN288_DDR506112002KQ(CHIPS)':
 'DQS7_A_T||TDQS7_A_T': CDS_PINID='\dqs7_a_t||tdqs7_a_t\';
NET_NAME
'M_B_CPU0_SA_DQS_DP<8>'
 '@T6G_MB_LIB.T6G(SCH_1):M_B_CPU0_SA_DQS_DP'<8>:
 C_SIGNAL='@t6g_mb_lib.t6g(sch_1):m_b_cpu0_sa_dqs_dp(8)';
NODE_NAME     U25 AG62
 '@T6G_MB_LIB.T6G(SCH_1):PAGE11_I171@PURE_QUANTA.GENOA_SP5(CHIPS)':
 'MBA_DQS_H8': CDS_PINID='MBA_DQS_H8';
NODE_NAME     J15 190
 '@T6G_MB_LIB.T6G(SCH_1):PAGE86_I367@PURE_QUANTA.SCONN288_DDR506112002KQ(CHIPS)':
 'DQS8_A_T||TDQS8_A_T': CDS_PINID='\dqs8_a_t||tdqs8_a_t\';
NET_NAME
'M_B_CPU0_SA_DQS_DP<9>'
 '@T6G_MB_LIB.T6G(SCH_1):M_B_CPU0_SA_DQS_DP'<9>:
 C_SIGNAL='@t6g_mb_lib.t6g(sch_1):m_b_cpu0_sa_dqs_dp(9)';
NODE_NAME     U25 AN62
 '@T6G_MB_LIB.T6G(SCH_1):PAGE11_I171@PURE_QUANTA.GENOA_SP5(CHIPS)':
 'MBA_DQS_H9': CDS_PINID='MBA_DQS_H9';
NODE_NAME     J15 201
 '@T6G_MB_LIB.T6G(SCH_1):PAGE86_I367@PURE_QUANTA.SCONN288_DDR506112002KQ(CHIPS)':
 'DQS9_A_T||TDQS9_A_T': CDS_PINID='\dqs9_a_t||tdqs9_a_t\';
NET_NAME
'M_B_CPU0_SA_PAR'
 '@T6G_MB_LIB.T6G(SCH_1):M_B_CPU0_SA_PAR':
 C_SIGNAL='@t6g_mb_lib.t6g(sch_1):m_b_cpu0_sa_par';
NODE_NAME     U25 BC62
 '@T6G_MB_LIB.T6G(SCH_1):PAGE11_I171@PURE_QUANTA.GENOA_SP5(CHIPS)':
 'MBA_PAR': CDS_PINID='MBA_PAR';
NODE_NAME     J15 74
 '@T6G_MB_LIB.T6G(SCH_1):PAGE86_I350@PURE_QUANTA.SCONN288_DDR506112002KQ(CHIPS)':
 'PAR_A': CDS_PINID='PAR_A';
NET_NAME
'M_B_CPU0_SA_RSP<0>'
 '@T6G_MB_LIB.T6G(SCH_1):M_B_CPU0_SA_RSP'<0>:
 C_SIGNAL='@t6g_mb_lib.t6g(sch_1):m_b_cpu0_sa_rsp(0)';
NODE_NAME     U25 BN62
 '@T6G_MB_LIB.T6G(SCH_1):PAGE11_I171@PURE_QUANTA.GENOA_SP5(CHIPS)':
 'MBA0_RSP_L': CDS_PINID='MBA0_RSP_L';
NODE_NAME     J15 86
 '@T6G_MB_LIB.T6G(SCH_1):PAGE86_I350@PURE_QUANTA.SCONN288_DDR506112002KQ(CHIPS)':
 'LBD||RSP_A_N': CDS_PINID='\lbd||rsp_a_n\';
NET_NAME
'M_B_CPU0_SB_CA<0>'
 '@T6G_MB_LIB.T6G(SCH_1):M_B_CPU0_SB_CA'<0>:
 C_SIGNAL='@t6g_mb_lib.t6g(sch_1):m_b_cpu0_sb_ca(0)';
NODE_NAME     U25 BG62
 '@T6G_MB_LIB.T6G(SCH_1):PAGE11_I171@PURE_QUANTA.GENOA_SP5(CHIPS)':
 'MBB_CA0': CDS_PINID='MBB_CA0';
NODE_NAME     J15 76
 '@T6G_MB_LIB.T6G(SCH_1):PAGE86_I350@PURE_QUANTA.SCONN288_DDR506112002KQ(CHIPS)':
 'CA0_B': CDS_PINID='CA0_B';
NET_NAME
'M_B_CPU0_SB_CA<1>'
 '@T6G_MB_LIB.T6G(SCH_1):M_B_CPU0_SB_CA'<1>:
 C_SIGNAL='@t6g_mb_lib.t6g(sch_1):m_b_cpu0_sb_ca(1)';
NODE_NAME     U25 BH62
 '@T6G_MB_LIB.T6G(SCH_1):PAGE11_I171@PURE_QUANTA.GENOA_SP5(CHIPS)':
 'MBB_CA1': CDS_PINID='MBB_CA1';
NODE_NAME     J15 221
 '@T6G_MB_LIB.T6G(SCH_1):PAGE86_I350@PURE_QUANTA.SCONN288_DDR506112002KQ(CHIPS)':
 'CA1_B': CDS_PINID='CA1_B';
NET_NAME
'M_B_CPU0_SB_CA<2>'
 '@T6G_MB_LIB.T6G(SCH_1):M_B_CPU0_SB_CA'<2>:
 C_SIGNAL='@t6g_mb_lib.t6g(sch_1):m_b_cpu0_sb_ca(2)';
NODE_NAME     U25 BH63
 '@T6G_MB_LIB.T6G(SCH_1):PAGE11_I171@PURE_QUANTA.GENOA_SP5(CHIPS)':
 'MBB_CA2': CDS_PINID='MBB_CA2';
NODE_NAME     J15 78
 '@T6G_MB_LIB.T6G(SCH_1):PAGE86_I350@PURE_QUANTA.SCONN288_DDR506112002KQ(CHIPS)':
 'CA2_B': CDS_PINID='CA2_B';
NET_NAME
'M_B_CPU0_SB_CA<3>'
 '@T6G_MB_LIB.T6G(SCH_1):M_B_CPU0_SB_CA'<3>:
 C_SIGNAL='@t6g_mb_lib.t6g(sch_1):m_b_cpu0_sb_ca(3)';
NODE_NAME     U25 BJ64
 '@T6G_MB_LIB.T6G(SCH_1):PAGE11_I171@PURE_QUANTA.GENOA_SP5(CHIPS)':
 'MBB_CA3': CDS_PINID='MBB_CA3';
NODE_NAME     J15 223
 '@T6G_MB_LIB.T6G(SCH_1):PAGE86_I350@PURE_QUANTA.SCONN288_DDR506112002KQ(CHIPS)':
 'CA3_B': CDS_PINID='CA3_B';
NET_NAME
'M_B_CPU0_SB_CA<4>'
 '@T6G_MB_LIB.T6G(SCH_1):M_B_CPU0_SB_CA'<4>:
 C_SIGNAL='@t6g_mb_lib.t6g(sch_1):m_b_cpu0_sb_ca(4)';
NODE_NAME     U25 BJ62
 '@T6G_MB_LIB.T6G(SCH_1):PAGE11_I171@PURE_QUANTA.GENOA_SP5(CHIPS)':
 'MBB_CA4': CDS_PINID='MBB_CA4';
NODE_NAME     J15 80
 '@T6G_MB_LIB.T6G(SCH_1):PAGE86_I350@PURE_QUANTA.SCONN288_DDR506112002KQ(CHIPS)':
 'CA4_B': CDS_PINID='CA4_B';
NET_NAME
'M_B_CPU0_SB_CA<5>'
 '@T6G_MB_LIB.T6G(SCH_1):M_B_CPU0_SB_CA'<5>:
 C_SIGNAL='@t6g_mb_lib.t6g(sch_1):m_b_cpu0_sb_ca(5)';
NODE_NAME     U25 BK62
 '@T6G_MB_LIB.T6G(SCH_1):PAGE11_I171@PURE_QUANTA.GENOA_SP5(CHIPS)':
 'MBB_CA5': CDS_PINID='MBB_CA5';
NODE_NAME     J15 225
 '@T6G_MB_LIB.T6G(SCH_1):PAGE86_I350@PURE_QUANTA.SCONN288_DDR506112002KQ(CHIPS)':
 'CA5_B': CDS_PINID='CA5_B';
NET_NAME
'M_B_CPU0_SB_CA<6>'
 '@T6G_MB_LIB.T6G(SCH_1):M_B_CPU0_SB_CA'<6>:
 C_SIGNAL='@t6g_mb_lib.t6g(sch_1):m_b_cpu0_sb_ca(6)';
NODE_NAME     U25 BK63
 '@T6G_MB_LIB.T6G(SCH_1):PAGE11_I171@PURE_QUANTA.GENOA_SP5(CHIPS)':
 'MBB_CA6': CDS_PINID='MBB_CA6';
NODE_NAME     J15 82
 '@T6G_MB_LIB.T6G(SCH_1):PAGE86_I350@PURE_QUANTA.SCONN288_DDR506112002KQ(CHIPS)':
 'CA6_B': CDS_PINID='CA6_B';
NET_NAME
'M_B_CPU0_SB_CB<0>'
 '@T6G_MB_LIB.T6G(SCH_1):M_B_CPU0_SB_CB'<0>:
 C_SIGNAL='@t6g_mb_lib.t6g(sch_1):m_b_cpu0_sb_cb(0)';
NODE_NAME     U25 BY63
 '@T6G_MB_LIB.T6G(SCH_1):PAGE11_I171@PURE_QUANTA.GENOA_SP5(CHIPS)':
 'MBB_CHECK0': CDS_PINID='MBB_CHECK0';
NODE_NAME     J15 96
 '@T6G_MB_LIB.T6G(SCH_1):PAGE86_I350@PURE_QUANTA.SCONN288_DDR506112002KQ(CHIPS)':
 'CB0_B': CDS_PINID='CB0_B';
NET_NAME
'M_B_CPU0_SB_CB<1>'
 '@T6G_MB_LIB.T6G(SCH_1):M_B_CPU0_SB_CB'<1>:
 C_SIGNAL='@t6g_mb_lib.t6g(sch_1):m_b_cpu0_sb_cb(1)';
NODE_NAME     U25 CA62
 '@T6G_MB_LIB.T6G(SCH_1):PAGE11_I171@PURE_QUANTA.GENOA_SP5(CHIPS)':
 'MBB_CHECK1': CDS_PINID='MBB_CHECK1';
NODE_NAME     J15 98
 '@T6G_MB_LIB.T6G(SCH_1):PAGE86_I350@PURE_QUANTA.SCONN288_DDR506112002KQ(CHIPS)':
 'CB1_B': CDS_PINID='CB1_B';
NET_NAME
'M_B_CPU0_SB_CB<2>'
 '@T6G_MB_LIB.T6G(SCH_1):M_B_CPU0_SB_CB'<2>:
 C_SIGNAL='@t6g_mb_lib.t6g(sch_1):m_b_cpu0_sb_cb(2)';
NODE_NAME     U25 CA64
 '@T6G_MB_LIB.T6G(SCH_1):PAGE11_I171@PURE_QUANTA.GENOA_SP5(CHIPS)':
 'MBB_CHECK2': CDS_PINID='MBB_CHECK2';
NODE_NAME     J15 241
 '@T6G_MB_LIB.T6G(SCH_1):PAGE86_I350@PURE_QUANTA.SCONN288_DDR506112002KQ(CHIPS)':
 'CB2_B': CDS_PINID='CB2_B';
NET_NAME
'M_B_CPU0_SB_CB<3>'
 '@T6G_MB_LIB.T6G(SCH_1):M_B_CPU0_SB_CB'<3>:
 C_SIGNAL='@t6g_mb_lib.t6g(sch_1):m_b_cpu0_sb_cb(3)';
NODE_NAME     U25 CB62
 '@T6G_MB_LIB.T6G(SCH_1):PAGE11_I171@PURE_QUANTA.GENOA_SP5(CHIPS)':
 'MBB_CHECK3': CDS_PINID='MBB_CHECK3';
NODE_NAME     J15 243
 '@T6G_MB_LIB.T6G(SCH_1):PAGE86_I350@PURE_QUANTA.SCONN288_DDR506112002KQ(CHIPS)':
 'CB3_B': CDS_PINID='CB3_B';
NET_NAME
'M_B_CPU0_SB_CB<4>'
 '@T6G_MB_LIB.T6G(SCH_1):M_B_CPU0_SB_CB'<4>:
 C_SIGNAL='@t6g_mb_lib.t6g(sch_1):m_b_cpu0_sb_cb(4)';
NODE_NAME     U25 BT63
 '@T6G_MB_LIB.T6G(SCH_1):PAGE11_I171@PURE_QUANTA.GENOA_SP5(CHIPS)':
 'MBB_CHECK4': CDS_PINID='MBB_CHECK4';
NODE_NAME     J15 89
 '@T6G_MB_LIB.T6G(SCH_1):PAGE86_I350@PURE_QUANTA.SCONN288_DDR506112002KQ(CHIPS)':
 'CB4_B': CDS_PINID='CB4_B';
NET_NAME
'M_B_CPU0_SB_CB<5>'
 '@T6G_MB_LIB.T6G(SCH_1):M_B_CPU0_SB_CB'<5>:
 C_SIGNAL='@t6g_mb_lib.t6g(sch_1):m_b_cpu0_sb_cb(5)';
NODE_NAME     U25 BU62
 '@T6G_MB_LIB.T6G(SCH_1):PAGE11_I171@PURE_QUANTA.GENOA_SP5(CHIPS)':
 'MBB_CHECK5': CDS_PINID='MBB_CHECK5';
NODE_NAME     J15 91
 '@T6G_MB_LIB.T6G(SCH_1):PAGE86_I350@PURE_QUANTA.SCONN288_DDR506112002KQ(CHIPS)':
 'CB5_B': CDS_PINID='CB5_B';
NET_NAME
'M_B_CPU0_SB_CB<6>'
 '@T6G_MB_LIB.T6G(SCH_1):M_B_CPU0_SB_CB'<6>:
 C_SIGNAL='@t6g_mb_lib.t6g(sch_1):m_b_cpu0_sb_cb(6)';
NODE_NAME     U25 BU64
 '@T6G_MB_LIB.T6G(SCH_1):PAGE11_I171@PURE_QUANTA.GENOA_SP5(CHIPS)':
 'MBB_CHECK6': CDS_PINID='MBB_CHECK6';
NODE_NAME     J15 234
 '@T6G_MB_LIB.T6G(SCH_1):PAGE86_I350@PURE_QUANTA.SCONN288_DDR506112002KQ(CHIPS)':
 'CB6_B': CDS_PINID='CB6_B';
NET_NAME
'M_B_CPU0_SB_CB<7>'
 '@T6G_MB_LIB.T6G(SCH_1):M_B_CPU0_SB_CB'<7>:
 C_SIGNAL='@t6g_mb_lib.t6g(sch_1):m_b_cpu0_sb_cb(7)';
NODE_NAME     U25 BV62
 '@T6G_MB_LIB.T6G(SCH_1):PAGE11_I171@PURE_QUANTA.GENOA_SP5(CHIPS)':
 'MBB_CHECK7': CDS_PINID='MBB_CHECK7';
NODE_NAME     J15 236
 '@T6G_MB_LIB.T6G(SCH_1):PAGE86_I350@PURE_QUANTA.SCONN288_DDR506112002KQ(CHIPS)':
 'CB7_B': CDS_PINID='CB7_B';
NET_NAME
'M_B_CPU0_SB_CS_N<0>'
 '@T6G_MB_LIB.T6G(SCH_1):M_B_CPU0_SB_CS_N'<0>:
 C_SIGNAL='@t6g_mb_lib.t6g(sch_1):m_b_cpu0_sb_cs_n(0)';
NODE_NAME     U25 BM62
 '@T6G_MB_LIB.T6G(SCH_1):PAGE11_I171@PURE_QUANTA.GENOA_SP5(CHIPS)':
 'MBB0_CS_L0': CDS_PINID='MBB0_CS_L0';
NODE_NAME     J15 84
 '@T6G_MB_LIB.T6G(SCH_1):PAGE86_I350@PURE_QUANTA.SCONN288_DDR506112002KQ(CHIPS)':
 'CS0_B_N': CDS_PINID='CS0_B_N';
NET_NAME
'M_B_CPU0_SB_CS_N<1>'
 '@T6G_MB_LIB.T6G(SCH_1):M_B_CPU0_SB_CS_N'<1>:
 C_SIGNAL='@t6g_mb_lib.t6g(sch_1):m_b_cpu0_sb_cs_n(1)';
NODE_NAME     U25 BN64
 '@T6G_MB_LIB.T6G(SCH_1):PAGE11_I171@PURE_QUANTA.GENOA_SP5(CHIPS)':
 'MBB0_CS_L1': CDS_PINID='MBB0_CS_L1';
NODE_NAME     J15 229
 '@T6G_MB_LIB.T6G(SCH_1):PAGE86_I350@PURE_QUANTA.SCONN288_DDR506112002KQ(CHIPS)':
 'CS1_B_N': CDS_PINID='CS1_B_N';
NET_NAME
'M_B_CPU0_SB_DQ<0>'
 '@T6G_MB_LIB.T6G(SCH_1):M_B_CPU0_SB_DQ'<0>:
 C_SIGNAL='@t6g_mb_lib.t6g(sch_1):m_b_cpu0_sb_dq(0)';
NODE_NAME     U25 CB63
 '@T6G_MB_LIB.T6G(SCH_1):PAGE11_I171@PURE_QUANTA.GENOA_SP5(CHIPS)':
 'MBB_DATA0': CDS_PINID='MBB_DATA0';
NODE_NAME     J15 100
 '@T6G_MB_LIB.T6G(SCH_1):PAGE86_I350@PURE_QUANTA.SCONN288_DDR506112002KQ(CHIPS)':
 'DQ0_B': CDS_PINID='DQ0_B';
NET_NAME
'M_B_CPU0_SB_DQ<10>'
 '@T6G_MB_LIB.T6G(SCH_1):M_B_CPU0_SB_DQ'<10>:
 C_SIGNAL='@t6g_mb_lib.t6g(sch_1):m_b_cpu0_sb_dq(10)';
NODE_NAME     U25 CJ64
 '@T6G_MB_LIB.T6G(SCH_1):PAGE11_I171@PURE_QUANTA.GENOA_SP5(CHIPS)':
 'MBB_DATA10': CDS_PINID='MBB_DATA10';
NODE_NAME     J15 256
 '@T6G_MB_LIB.T6G(SCH_1):PAGE86_I350@PURE_QUANTA.SCONN288_DDR506112002KQ(CHIPS)':
 'DQ10_B': CDS_PINID='DQ10_B';
NET_NAME
'M_B_CPU0_SB_DQ<11>'
 '@T6G_MB_LIB.T6G(SCH_1):M_B_CPU0_SB_DQ'<11>:
 C_SIGNAL='@t6g_mb_lib.t6g(sch_1):m_b_cpu0_sb_dq(11)';
NODE_NAME     U25 CK62
 '@T6G_MB_LIB.T6G(SCH_1):PAGE11_I171@PURE_QUANTA.GENOA_SP5(CHIPS)':
 'MBB_DATA11': CDS_PINID='MBB_DATA11';
NODE_NAME     J15 258
 '@T6G_MB_LIB.T6G(SCH_1):PAGE86_I350@PURE_QUANTA.SCONN288_DDR506112002KQ(CHIPS)':
 'DQ11_B': CDS_PINID='DQ11_B';
NET_NAME
'M_B_CPU0_SB_DQ<12>'
 '@T6G_MB_LIB.T6G(SCH_1):M_B_CPU0_SB_DQ'<12>:
 C_SIGNAL='@t6g_mb_lib.t6g(sch_1):m_b_cpu0_sb_dq(12)';
NODE_NAME     U25 CM63
 '@T6G_MB_LIB.T6G(SCH_1):PAGE11_I171@PURE_QUANTA.GENOA_SP5(CHIPS)':
 'MBB_DATA12': CDS_PINID='MBB_DATA12';
NODE_NAME     J15 118
 '@T6G_MB_LIB.T6G(SCH_1):PAGE86_I350@PURE_QUANTA.SCONN288_DDR506112002KQ(CHIPS)':
 'DQ12_B': CDS_PINID='DQ12_B';
NET_NAME
'M_B_CPU0_SB_DQ<13>'
 '@T6G_MB_LIB.T6G(SCH_1):M_B_CPU0_SB_DQ'<13>:
 C_SIGNAL='@t6g_mb_lib.t6g(sch_1):m_b_cpu0_sb_dq(13)';
NODE_NAME     U25 CN62
 '@T6G_MB_LIB.T6G(SCH_1):PAGE11_I171@PURE_QUANTA.GENOA_SP5(CHIPS)':
 'MBB_DATA13': CDS_PINID='MBB_DATA13';
NODE_NAME     J15 120
 '@T6G_MB_LIB.T6G(SCH_1):PAGE86_I350@PURE_QUANTA.SCONN288_DDR506112002KQ(CHIPS)':
 'DQ13_B': CDS_PINID='DQ13_B';
NET_NAME
'M_B_CPU0_SB_DQ<14>'
 '@T6G_MB_LIB.T6G(SCH_1):M_B_CPU0_SB_DQ'<14>:
 C_SIGNAL='@t6g_mb_lib.t6g(sch_1):m_b_cpu0_sb_dq(14)';
NODE_NAME     U25 CN64
 '@T6G_MB_LIB.T6G(SCH_1):PAGE11_I171@PURE_QUANTA.GENOA_SP5(CHIPS)':
 'MBB_DATA14': CDS_PINID='MBB_DATA14';
NODE_NAME     J15 263
 '@T6G_MB_LIB.T6G(SCH_1):PAGE86_I350@PURE_QUANTA.SCONN288_DDR506112002KQ(CHIPS)':
 'DQ14_B': CDS_PINID='DQ14_B';
NET_NAME
'M_B_CPU0_SB_DQ<15>'
 '@T6G_MB_LIB.T6G(SCH_1):M_B_CPU0_SB_DQ'<15>:
 C_SIGNAL='@t6g_mb_lib.t6g(sch_1):m_b_cpu0_sb_dq(15)';
NODE_NAME     U25 CP62
 '@T6G_MB_LIB.T6G(SCH_1):PAGE11_I171@PURE_QUANTA.GENOA_SP5(CHIPS)':
 'MBB_DATA15': CDS_PINID='MBB_DATA15';
NODE_NAME     J15 265
 '@T6G_MB_LIB.T6G(SCH_1):PAGE86_I350@PURE_QUANTA.SCONN288_DDR506112002KQ(CHIPS)':
 'DQ15_B': CDS_PINID='DQ15_B';
NET_NAME
'M_B_CPU0_SB_DQ<16>'
 '@T6G_MB_LIB.T6G(SCH_1):M_B_CPU0_SB_DQ'<16>:
 C_SIGNAL='@t6g_mb_lib.t6g(sch_1):m_b_cpu0_sb_dq(16)';
NODE_NAME     U25 CP63
 '@T6G_MB_LIB.T6G(SCH_1):PAGE11_I171@PURE_QUANTA.GENOA_SP5(CHIPS)':
 'MBB_DATA16': CDS_PINID='MBB_DATA16';
NODE_NAME     J15 122
 '@T6G_MB_LIB.T6G(SCH_1):PAGE86_I350@PURE_QUANTA.SCONN288_DDR506112002KQ(CHIPS)':
 'DQ16_B': CDS_PINID='DQ16_B';
NET_NAME
'M_B_CPU0_SB_DQ<17>'
 '@T6G_MB_LIB.T6G(SCH_1):M_B_CPU0_SB_DQ'<17>:
 C_SIGNAL='@t6g_mb_lib.t6g(sch_1):m_b_cpu0_sb_dq(17)';
NODE_NAME     U25 CR62
 '@T6G_MB_LIB.T6G(SCH_1):PAGE11_I171@PURE_QUANTA.GENOA_SP5(CHIPS)':
 'MBB_DATA17': CDS_PINID='MBB_DATA17';
NODE_NAME     J15 124
 '@T6G_MB_LIB.T6G(SCH_1):PAGE86_I350@PURE_QUANTA.SCONN288_DDR506112002KQ(CHIPS)':
 'DQ17_B': CDS_PINID='DQ17_B';
NET_NAME
'M_B_CPU0_SB_DQ<18>'
 '@T6G_MB_LIB.T6G(SCH_1):M_B_CPU0_SB_DQ'<18>:
 C_SIGNAL='@t6g_mb_lib.t6g(sch_1):m_b_cpu0_sb_dq(18)';
NODE_NAME     U25 CR64
 '@T6G_MB_LIB.T6G(SCH_1):PAGE11_I171@PURE_QUANTA.GENOA_SP5(CHIPS)':
 'MBB_DATA18': CDS_PINID='MBB_DATA18';
NODE_NAME     J15 267
 '@T6G_MB_LIB.T6G(SCH_1):PAGE86_I350@PURE_QUANTA.SCONN288_DDR506112002KQ(CHIPS)':
 'DQ18_B': CDS_PINID='DQ18_B';
NET_NAME
'M_B_CPU0_SB_DQ<19>'
 '@T6G_MB_LIB.T6G(SCH_1):M_B_CPU0_SB_DQ'<19>:
 C_SIGNAL='@t6g_mb_lib.t6g(sch_1):m_b_cpu0_sb_dq(19)';
NODE_NAME     U25 CT62
 '@T6G_MB_LIB.T6G(SCH_1):PAGE11_I171@PURE_QUANTA.GENOA_SP5(CHIPS)':
 'MBB_DATA19': CDS_PINID='MBB_DATA19';
NODE_NAME     J15 269
 '@T6G_MB_LIB.T6G(SCH_1):PAGE86_I350@PURE_QUANTA.SCONN288_DDR506112002KQ(CHIPS)':
 'DQ19_B': CDS_PINID='DQ19_B';
NET_NAME
'M_B_CPU0_SB_DQ<1>'
 '@T6G_MB_LIB.T6G(SCH_1):M_B_CPU0_SB_DQ'<1>:
 C_SIGNAL='@t6g_mb_lib.t6g(sch_1):m_b_cpu0_sb_dq(1)';
NODE_NAME     U25 CC62
 '@T6G_MB_LIB.T6G(SCH_1):PAGE11_I171@PURE_QUANTA.GENOA_SP5(CHIPS)':
 'MBB_DATA1': CDS_PINID='MBB_DATA1';
NODE_NAME     J15 102
 '@T6G_MB_LIB.T6G(SCH_1):PAGE86_I350@PURE_QUANTA.SCONN288_DDR506112002KQ(CHIPS)':
 'DQ1_B': CDS_PINID='DQ1_B';
NET_NAME
'M_B_CPU0_SB_DQ<20>'
 '@T6G_MB_LIB.T6G(SCH_1):M_B_CPU0_SB_DQ'<20>:
 C_SIGNAL='@t6g_mb_lib.t6g(sch_1):m_b_cpu0_sb_dq(20)';
NODE_NAME     U25 CV63
 '@T6G_MB_LIB.T6G(SCH_1):PAGE11_I171@PURE_QUANTA.GENOA_SP5(CHIPS)':
 'MBB_DATA20': CDS_PINID='MBB_DATA20';
NODE_NAME     J15 129
 '@T6G_MB_LIB.T6G(SCH_1):PAGE86_I350@PURE_QUANTA.SCONN288_DDR506112002KQ(CHIPS)':
 'DQ20_B': CDS_PINID='DQ20_B';
NET_NAME
'M_B_CPU0_SB_DQ<21>'
 '@T6G_MB_LIB.T6G(SCH_1):M_B_CPU0_SB_DQ'<21>:
 C_SIGNAL='@t6g_mb_lib.t6g(sch_1):m_b_cpu0_sb_dq(21)';
NODE_NAME     U25 CW62
 '@T6G_MB_LIB.T6G(SCH_1):PAGE11_I171@PURE_QUANTA.GENOA_SP5(CHIPS)':
 'MBB_DATA21': CDS_PINID='MBB_DATA21';
NODE_NAME     J15 131
 '@T6G_MB_LIB.T6G(SCH_1):PAGE86_I350@PURE_QUANTA.SCONN288_DDR506112002KQ(CHIPS)':
 'DQ21_B': CDS_PINID='DQ21_B';
NET_NAME
'M_B_CPU0_SB_DQ<22>'
 '@T6G_MB_LIB.T6G(SCH_1):M_B_CPU0_SB_DQ'<22>:
 C_SIGNAL='@t6g_mb_lib.t6g(sch_1):m_b_cpu0_sb_dq(22)';
NODE_NAME     U25 CW64
 '@T6G_MB_LIB.T6G(SCH_1):PAGE11_I171@PURE_QUANTA.GENOA_SP5(CHIPS)':
 'MBB_DATA22': CDS_PINID='MBB_DATA22';
NODE_NAME     J15 274
 '@T6G_MB_LIB.T6G(SCH_1):PAGE86_I350@PURE_QUANTA.SCONN288_DDR506112002KQ(CHIPS)':
 'DQ22_B': CDS_PINID='DQ22_B';
NET_NAME
'M_B_CPU0_SB_DQ<23>'
 '@T6G_MB_LIB.T6G(SCH_1):M_B_CPU0_SB_DQ'<23>:
 C_SIGNAL='@t6g_mb_lib.t6g(sch_1):m_b_cpu0_sb_dq(23)';
NODE_NAME     U25 CY62
 '@T6G_MB_LIB.T6G(SCH_1):PAGE11_I171@PURE_QUANTA.GENOA_SP5(CHIPS)':
 'MBB_DATA23': CDS_PINID='MBB_DATA23';
NODE_NAME     J15 276
 '@T6G_MB_LIB.T6G(SCH_1):PAGE86_I350@PURE_QUANTA.SCONN288_DDR506112002KQ(CHIPS)':
 'DQ23_B': CDS_PINID='DQ23_B';
NET_NAME
'M_B_CPU0_SB_DQ<24>'
 '@T6G_MB_LIB.T6G(SCH_1):M_B_CPU0_SB_DQ'<24>:
 C_SIGNAL='@t6g_mb_lib.t6g(sch_1):m_b_cpu0_sb_dq(24)';
NODE_NAME     U25 CY63
 '@T6G_MB_LIB.T6G(SCH_1):PAGE11_I171@PURE_QUANTA.GENOA_SP5(CHIPS)':
 'MBB_DATA24': CDS_PINID='MBB_DATA24';
NODE_NAME     J15 133
 '@T6G_MB_LIB.T6G(SCH_1):PAGE86_I350@PURE_QUANTA.SCONN288_DDR506112002KQ(CHIPS)':
 'DQ24_B': CDS_PINID='DQ24_B';
NET_NAME
'M_B_CPU0_SB_DQ<25>'
 '@T6G_MB_LIB.T6G(SCH_1):M_B_CPU0_SB_DQ'<25>:
 C_SIGNAL='@t6g_mb_lib.t6g(sch_1):m_b_cpu0_sb_dq(25)';
NODE_NAME     U25 DA62
 '@T6G_MB_LIB.T6G(SCH_1):PAGE11_I171@PURE_QUANTA.GENOA_SP5(CHIPS)':
 'MBB_DATA25': CDS_PINID='MBB_DATA25';
NODE_NAME     J15 135
 '@T6G_MB_LIB.T6G(SCH_1):PAGE86_I350@PURE_QUANTA.SCONN288_DDR506112002KQ(CHIPS)':
 'DQ25_B': CDS_PINID='DQ25_B';
NET_NAME
'M_B_CPU0_SB_DQ<26>'
 '@T6G_MB_LIB.T6G(SCH_1):M_B_CPU0_SB_DQ'<26>:
 C_SIGNAL='@t6g_mb_lib.t6g(sch_1):m_b_cpu0_sb_dq(26)';
NODE_NAME     U25 DA64
 '@T6G_MB_LIB.T6G(SCH_1):PAGE11_I171@PURE_QUANTA.GENOA_SP5(CHIPS)':
 'MBB_DATA26': CDS_PINID='MBB_DATA26';
NODE_NAME     J15 278
 '@T6G_MB_LIB.T6G(SCH_1):PAGE86_I350@PURE_QUANTA.SCONN288_DDR506112002KQ(CHIPS)':
 'DQ26_B': CDS_PINID='DQ26_B';
NET_NAME
'M_B_CPU0_SB_DQ<27>'
 '@T6G_MB_LIB.T6G(SCH_1):M_B_CPU0_SB_DQ'<27>:
 C_SIGNAL='@t6g_mb_lib.t6g(sch_1):m_b_cpu0_sb_dq(27)';
NODE_NAME     U25 DB62
 '@T6G_MB_LIB.T6G(SCH_1):PAGE11_I171@PURE_QUANTA.GENOA_SP5(CHIPS)':
 'MBB_DATA27': CDS_PINID='MBB_DATA27';
NODE_NAME     J15 280
 '@T6G_MB_LIB.T6G(SCH_1):PAGE86_I350@PURE_QUANTA.SCONN288_DDR506112002KQ(CHIPS)':
 'DQ27_B': CDS_PINID='DQ27_B';
NET_NAME
'M_B_CPU0_SB_DQ<28>'
 '@T6G_MB_LIB.T6G(SCH_1):M_B_CPU0_SB_DQ'<28>:
 C_SIGNAL='@t6g_mb_lib.t6g(sch_1):m_b_cpu0_sb_dq(28)';
NODE_NAME     U25 DD63
 '@T6G_MB_LIB.T6G(SCH_1):PAGE11_I171@PURE_QUANTA.GENOA_SP5(CHIPS)':
 'MBB_DATA28': CDS_PINID='MBB_DATA28';
NODE_NAME     J15 140
 '@T6G_MB_LIB.T6G(SCH_1):PAGE86_I350@PURE_QUANTA.SCONN288_DDR506112002KQ(CHIPS)':
 'DQ28_B': CDS_PINID='DQ28_B';
NET_NAME
'M_B_CPU0_SB_DQ<29>'
 '@T6G_MB_LIB.T6G(SCH_1):M_B_CPU0_SB_DQ'<29>:
 C_SIGNAL='@t6g_mb_lib.t6g(sch_1):m_b_cpu0_sb_dq(29)';
NODE_NAME     U25 DE62
 '@T6G_MB_LIB.T6G(SCH_1):PAGE11_I171@PURE_QUANTA.GENOA_SP5(CHIPS)':
 'MBB_DATA29': CDS_PINID='MBB_DATA29';
NODE_NAME     J15 142
 '@T6G_MB_LIB.T6G(SCH_1):PAGE86_I350@PURE_QUANTA.SCONN288_DDR506112002KQ(CHIPS)':
 'DQ29_B': CDS_PINID='DQ29_B';
NET_NAME
'M_B_CPU0_SB_DQ<2>'
 '@T6G_MB_LIB.T6G(SCH_1):M_B_CPU0_SB_DQ'<2>:
 C_SIGNAL='@t6g_mb_lib.t6g(sch_1):m_b_cpu0_sb_dq(2)';
NODE_NAME     U25 CC64
 '@T6G_MB_LIB.T6G(SCH_1):PAGE11_I171@PURE_QUANTA.GENOA_SP5(CHIPS)':
 'MBB_DATA2': CDS_PINID='MBB_DATA2';
NODE_NAME     J15 245
 '@T6G_MB_LIB.T6G(SCH_1):PAGE86_I350@PURE_QUANTA.SCONN288_DDR506112002KQ(CHIPS)':
 'DQ2_B': CDS_PINID='DQ2_B';
NET_NAME
'M_B_CPU0_SB_DQ<30>'
 '@T6G_MB_LIB.T6G(SCH_1):M_B_CPU0_SB_DQ'<30>:
 C_SIGNAL='@t6g_mb_lib.t6g(sch_1):m_b_cpu0_sb_dq(30)';
NODE_NAME     U25 DE64
 '@T6G_MB_LIB.T6G(SCH_1):PAGE11_I171@PURE_QUANTA.GENOA_SP5(CHIPS)':
 'MBB_DATA30': CDS_PINID='MBB_DATA30';
NODE_NAME     J15 285
 '@T6G_MB_LIB.T6G(SCH_1):PAGE86_I350@PURE_QUANTA.SCONN288_DDR506112002KQ(CHIPS)':
 'DQ30_B': CDS_PINID='DQ30_B';
NET_NAME
'M_B_CPU0_SB_DQ<31>'
 '@T6G_MB_LIB.T6G(SCH_1):M_B_CPU0_SB_DQ'<31>:
 C_SIGNAL='@t6g_mb_lib.t6g(sch_1):m_b_cpu0_sb_dq(31)';
NODE_NAME     U25 DF62
 '@T6G_MB_LIB.T6G(SCH_1):PAGE11_I171@PURE_QUANTA.GENOA_SP5(CHIPS)':
 'MBB_DATA31': CDS_PINID='MBB_DATA31';
NODE_NAME     J15 287
 '@T6G_MB_LIB.T6G(SCH_1):PAGE86_I350@PURE_QUANTA.SCONN288_DDR506112002KQ(CHIPS)':
 'DQ31_B': CDS_PINID='DQ31_B';
NET_NAME
'M_B_CPU0_SB_DQ<3>'
 '@T6G_MB_LIB.T6G(SCH_1):M_B_CPU0_SB_DQ'<3>:
 C_SIGNAL='@t6g_mb_lib.t6g(sch_1):m_b_cpu0_sb_dq(3)';
NODE_NAME     U25 CD62
 '@T6G_MB_LIB.T6G(SCH_1):PAGE11_I171@PURE_QUANTA.GENOA_SP5(CHIPS)':
 'MBB_DATA3': CDS_PINID='MBB_DATA3';
NODE_NAME     J15 247
 '@T6G_MB_LIB.T6G(SCH_1):PAGE86_I350@PURE_QUANTA.SCONN288_DDR506112002KQ(CHIPS)':
 'DQ3_B': CDS_PINID='DQ3_B';
NET_NAME
'M_B_CPU0_SB_DQ<4>'
 '@T6G_MB_LIB.T6G(SCH_1):M_B_CPU0_SB_DQ'<4>:
 C_SIGNAL='@t6g_mb_lib.t6g(sch_1):m_b_cpu0_sb_dq(4)';
NODE_NAME     U25 CF63
 '@T6G_MB_LIB.T6G(SCH_1):PAGE11_I171@PURE_QUANTA.GENOA_SP5(CHIPS)':
 'MBB_DATA4': CDS_PINID='MBB_DATA4';
NODE_NAME     J15 107
 '@T6G_MB_LIB.T6G(SCH_1):PAGE86_I350@PURE_QUANTA.SCONN288_DDR506112002KQ(CHIPS)':
 'DQ4_B': CDS_PINID='DQ4_B';
NET_NAME
'M_B_CPU0_SB_DQ<5>'
 '@T6G_MB_LIB.T6G(SCH_1):M_B_CPU0_SB_DQ'<5>:
 C_SIGNAL='@t6g_mb_lib.t6g(sch_1):m_b_cpu0_sb_dq(5)';
NODE_NAME     U25 CG62
 '@T6G_MB_LIB.T6G(SCH_1):PAGE11_I171@PURE_QUANTA.GENOA_SP5(CHIPS)':
 'MBB_DATA5': CDS_PINID='MBB_DATA5';
NODE_NAME     J15 109
 '@T6G_MB_LIB.T6G(SCH_1):PAGE86_I350@PURE_QUANTA.SCONN288_DDR506112002KQ(CHIPS)':
 'DQ5_B': CDS_PINID='DQ5_B';
NET_NAME
'M_B_CPU0_SB_DQ<6>'
 '@T6G_MB_LIB.T6G(SCH_1):M_B_CPU0_SB_DQ'<6>:
 C_SIGNAL='@t6g_mb_lib.t6g(sch_1):m_b_cpu0_sb_dq(6)';
NODE_NAME     U25 CG64
 '@T6G_MB_LIB.T6G(SCH_1):PAGE11_I171@PURE_QUANTA.GENOA_SP5(CHIPS)':
 'MBB_DATA6': CDS_PINID='MBB_DATA6';
NODE_NAME     J15 252
 '@T6G_MB_LIB.T6G(SCH_1):PAGE86_I350@PURE_QUANTA.SCONN288_DDR506112002KQ(CHIPS)':
 'DQ6_B': CDS_PINID='DQ6_B';
NET_NAME
'M_B_CPU0_SB_DQ<7>'
 '@T6G_MB_LIB.T6G(SCH_1):M_B_CPU0_SB_DQ'<7>:
 C_SIGNAL='@t6g_mb_lib.t6g(sch_1):m_b_cpu0_sb_dq(7)';
NODE_NAME     U25 CH62
 '@T6G_MB_LIB.T6G(SCH_1):PAGE11_I171@PURE_QUANTA.GENOA_SP5(CHIPS)':
 'MBB_DATA7': CDS_PINID='MBB_DATA7';
NODE_NAME     J15 254
 '@T6G_MB_LIB.T6G(SCH_1):PAGE86_I350@PURE_QUANTA.SCONN288_DDR506112002KQ(CHIPS)':
 'DQ7_B': CDS_PINID='DQ7_B';
NET_NAME
'M_B_CPU0_SB_DQ<8>'
 '@T6G_MB_LIB.T6G(SCH_1):M_B_CPU0_SB_DQ'<8>:
 C_SIGNAL='@t6g_mb_lib.t6g(sch_1):m_b_cpu0_sb_dq(8)';
NODE_NAME     U25 CH63
 '@T6G_MB_LIB.T6G(SCH_1):PAGE11_I171@PURE_QUANTA.GENOA_SP5(CHIPS)':
 'MBB_DATA8': CDS_PINID='MBB_DATA8';
NODE_NAME     J15 111
 '@T6G_MB_LIB.T6G(SCH_1):PAGE86_I350@PURE_QUANTA.SCONN288_DDR506112002KQ(CHIPS)':
 'DQ8_B': CDS_PINID='DQ8_B';
NET_NAME
'M_B_CPU0_SB_DQ<9>'
 '@T6G_MB_LIB.T6G(SCH_1):M_B_CPU0_SB_DQ'<9>:
 C_SIGNAL='@t6g_mb_lib.t6g(sch_1):m_b_cpu0_sb_dq(9)';
NODE_NAME     U25 CJ62
 '@T6G_MB_LIB.T6G(SCH_1):PAGE11_I171@PURE_QUANTA.GENOA_SP5(CHIPS)':
 'MBB_DATA9': CDS_PINID='MBB_DATA9';
NODE_NAME     J15 113
 '@T6G_MB_LIB.T6G(SCH_1):PAGE86_I350@PURE_QUANTA.SCONN288_DDR506112002KQ(CHIPS)':
 'DQ9_B': CDS_PINID='DQ9_B';
NET_NAME
'M_B_CPU0_SB_DQS_DN<0>'
 '@T6G_MB_LIB.T6G(SCH_1):M_B_CPU0_SB_DQS_DN'<0>:
 C_SIGNAL='@t6g_mb_lib.t6g(sch_1):m_b_cpu0_sb_dqs_dn(0)';
NODE_NAME     U25 CE64
 '@T6G_MB_LIB.T6G(SCH_1):PAGE11_I171@PURE_QUANTA.GENOA_SP5(CHIPS)':
 'MBB_DQS_L0': CDS_PINID='MBB_DQS_L0';
NODE_NAME     J15 105
 '@T6G_MB_LIB.T6G(SCH_1):PAGE86_I367@PURE_QUANTA.SCONN288_DDR506112002KQ(CHIPS)':
 'DQS0_B_C': CDS_PINID='DQS0_B_C';
NET_NAME
'M_B_CPU0_SB_DQS_DN<1>'
 '@T6G_MB_LIB.T6G(SCH_1):M_B_CPU0_SB_DQS_DN'<1>:
 C_SIGNAL='@t6g_mb_lib.t6g(sch_1):m_b_cpu0_sb_dqs_dn(1)';
NODE_NAME     U25 CL64
 '@T6G_MB_LIB.T6G(SCH_1):PAGE11_I171@PURE_QUANTA.GENOA_SP5(CHIPS)':
 'MBB_DQS_L1': CDS_PINID='MBB_DQS_L1';
NODE_NAME     J15 116
 '@T6G_MB_LIB.T6G(SCH_1):PAGE86_I367@PURE_QUANTA.SCONN288_DDR506112002KQ(CHIPS)':
 'DQS1_B_C': CDS_PINID='DQS1_B_C';
NET_NAME
'M_B_CPU0_SB_DQS_DN<2>'
 '@T6G_MB_LIB.T6G(SCH_1):M_B_CPU0_SB_DQS_DN'<2>:
 C_SIGNAL='@t6g_mb_lib.t6g(sch_1):m_b_cpu0_sb_dqs_dn(2)';
NODE_NAME     U25 CU64
 '@T6G_MB_LIB.T6G(SCH_1):PAGE11_I171@PURE_QUANTA.GENOA_SP5(CHIPS)':
 'MBB_DQS_L2': CDS_PINID='MBB_DQS_L2';
NODE_NAME     J15 127
 '@T6G_MB_LIB.T6G(SCH_1):PAGE86_I367@PURE_QUANTA.SCONN288_DDR506112002KQ(CHIPS)':
 'DQS2_B_C': CDS_PINID='DQS2_B_C';
NET_NAME
'M_B_CPU0_SB_DQS_DN<3>'
 '@T6G_MB_LIB.T6G(SCH_1):M_B_CPU0_SB_DQS_DN'<3>:
 C_SIGNAL='@t6g_mb_lib.t6g(sch_1):m_b_cpu0_sb_dqs_dn(3)';
NODE_NAME     U25 DC64
 '@T6G_MB_LIB.T6G(SCH_1):PAGE11_I171@PURE_QUANTA.GENOA_SP5(CHIPS)':
 'MBB_DQS_L3': CDS_PINID='MBB_DQS_L3';
NODE_NAME     J15 138
 '@T6G_MB_LIB.T6G(SCH_1):PAGE86_I367@PURE_QUANTA.SCONN288_DDR506112002KQ(CHIPS)':
 'DQS3_B_C': CDS_PINID='DQS3_B_C';
NET_NAME
'M_B_CPU0_SB_DQS_DN<4>'
 '@T6G_MB_LIB.T6G(SCH_1):M_B_CPU0_SB_DQS_DN'<4>:
 C_SIGNAL='@t6g_mb_lib.t6g(sch_1):m_b_cpu0_sb_dqs_dn(4)';
NODE_NAME     U25 BW62
 '@T6G_MB_LIB.T6G(SCH_1):PAGE11_I171@PURE_QUANTA.GENOA_SP5(CHIPS)':
 'MBB_DQS_L4': CDS_PINID='MBB_DQS_L4';
NODE_NAME     J15 238
 '@T6G_MB_LIB.T6G(SCH_1):PAGE86_I367@PURE_QUANTA.SCONN288_DDR506112002KQ(CHIPS)':
 'DQS4_B_C': CDS_PINID='DQS4_B_C';
NET_NAME
'M_B_CPU0_SB_DQS_DN<5>'
 '@T6G_MB_LIB.T6G(SCH_1):M_B_CPU0_SB_DQS_DN'<5>:
 C_SIGNAL='@t6g_mb_lib.t6g(sch_1):m_b_cpu0_sb_dqs_dn(5)';
NODE_NAME     U25 CE62
 '@T6G_MB_LIB.T6G(SCH_1):PAGE11_I171@PURE_QUANTA.GENOA_SP5(CHIPS)':
 'MBB_DQS_L5': CDS_PINID='MBB_DQS_L5';
NODE_NAME     J15 249
 '@T6G_MB_LIB.T6G(SCH_1):PAGE86_I367@PURE_QUANTA.SCONN288_DDR506112002KQ(CHIPS)':
 'DQS5_B_C||TDQS5_B_C': CDS_PINID='\dqs5_b_c||tdqs5_b_c\';
NET_NAME
'M_B_CPU0_SB_DQS_DN<6>'
 '@T6G_MB_LIB.T6G(SCH_1):M_B_CPU0_SB_DQS_DN'<6>:
 C_SIGNAL='@t6g_mb_lib.t6g(sch_1):m_b_cpu0_sb_dqs_dn(6)';
NODE_NAME     U25 CL62
 '@T6G_MB_LIB.T6G(SCH_1):PAGE11_I171@PURE_QUANTA.GENOA_SP5(CHIPS)':
 'MBB_DQS_L6': CDS_PINID='MBB_DQS_L6';
NODE_NAME     J15 260
 '@T6G_MB_LIB.T6G(SCH_1):PAGE86_I367@PURE_QUANTA.SCONN288_DDR506112002KQ(CHIPS)':
 'DQS6_B_C||TDQS6_B_C': CDS_PINID='\dqs6_b_c||tdqs6_b_c\';
NET_NAME
'M_B_CPU0_SB_DQS_DN<7>'
 '@T6G_MB_LIB.T6G(SCH_1):M_B_CPU0_SB_DQS_DN'<7>:
 C_SIGNAL='@t6g_mb_lib.t6g(sch_1):m_b_cpu0_sb_dqs_dn(7)';
NODE_NAME     U25 CU62
 '@T6G_MB_LIB.T6G(SCH_1):PAGE11_I171@PURE_QUANTA.GENOA_SP5(CHIPS)':
 'MBB_DQS_L7': CDS_PINID='MBB_DQS_L7';
NODE_NAME     J15 271
 '@T6G_MB_LIB.T6G(SCH_1):PAGE86_I367@PURE_QUANTA.SCONN288_DDR506112002KQ(CHIPS)':
 'DQS7_B_C||TDQS7_B_C': CDS_PINID='\dqs7_b_c||tdqs7_b_c\';
NET_NAME
'M_B_CPU0_SB_DQS_DN<8>'
 '@T6G_MB_LIB.T6G(SCH_1):M_B_CPU0_SB_DQS_DN'<8>:
 C_SIGNAL='@t6g_mb_lib.t6g(sch_1):m_b_cpu0_sb_dqs_dn(8)';
NODE_NAME     U25 DC62
 '@T6G_MB_LIB.T6G(SCH_1):PAGE11_I171@PURE_QUANTA.GENOA_SP5(CHIPS)':
 'MBB_DQS_L8': CDS_PINID='MBB_DQS_L8';
NODE_NAME     J15 282
 '@T6G_MB_LIB.T6G(SCH_1):PAGE86_I367@PURE_QUANTA.SCONN288_DDR506112002KQ(CHIPS)':
 'DQS8_B_C||TDQS8_B_C': CDS_PINID='\dqs8_b_c||tdqs8_b_c\';
NET_NAME
'M_B_CPU0_SB_DQS_DN<9>'
 '@T6G_MB_LIB.T6G(SCH_1):M_B_CPU0_SB_DQS_DN'<9>:
 C_SIGNAL='@t6g_mb_lib.t6g(sch_1):m_b_cpu0_sb_dqs_dn(9)';
NODE_NAME     U25 BW64
 '@T6G_MB_LIB.T6G(SCH_1):PAGE11_I171@PURE_QUANTA.GENOA_SP5(CHIPS)':
 'MBB_DQS_L9': CDS_PINID='MBB_DQS_L9';
NODE_NAME     J15 94
 '@T6G_MB_LIB.T6G(SCH_1):PAGE86_I367@PURE_QUANTA.SCONN288_DDR506112002KQ(CHIPS)':
 'DQS9_B_C||TDQS9_B_C': CDS_PINID='\dqs9_b_c||tdqs9_b_c\';
NET_NAME
'M_B_CPU0_SB_DQS_DP<0>'
 '@T6G_MB_LIB.T6G(SCH_1):M_B_CPU0_SB_DQS_DP'<0>:
 C_SIGNAL='@t6g_mb_lib.t6g(sch_1):m_b_cpu0_sb_dqs_dp(0)';
NODE_NAME     U25 CD63
 '@T6G_MB_LIB.T6G(SCH_1):PAGE11_I171@PURE_QUANTA.GENOA_SP5(CHIPS)':
 'MBB_DQS_H0': CDS_PINID='MBB_DQS_H0';
NODE_NAME     J15 104
 '@T6G_MB_LIB.T6G(SCH_1):PAGE86_I367@PURE_QUANTA.SCONN288_DDR506112002KQ(CHIPS)':
 'DQS0_B_T': CDS_PINID='DQS0_B_T';
NET_NAME
'M_B_CPU0_SB_DQS_DP<1>'
 '@T6G_MB_LIB.T6G(SCH_1):M_B_CPU0_SB_DQS_DP'<1>:
 C_SIGNAL='@t6g_mb_lib.t6g(sch_1):m_b_cpu0_sb_dqs_dp(1)';
NODE_NAME     U25 CK63
 '@T6G_MB_LIB.T6G(SCH_1):PAGE11_I171@PURE_QUANTA.GENOA_SP5(CHIPS)':
 'MBB_DQS_H1': CDS_PINID='MBB_DQS_H1';
NODE_NAME     J15 115
 '@T6G_MB_LIB.T6G(SCH_1):PAGE86_I367@PURE_QUANTA.SCONN288_DDR506112002KQ(CHIPS)':
 'DQS1_B_T': CDS_PINID='DQS1_B_T';
NET_NAME
'M_B_CPU0_SB_DQS_DP<2>'
 '@T6G_MB_LIB.T6G(SCH_1):M_B_CPU0_SB_DQS_DP'<2>:
 C_SIGNAL='@t6g_mb_lib.t6g(sch_1):m_b_cpu0_sb_dqs_dp(2)';
NODE_NAME     U25 CT63
 '@T6G_MB_LIB.T6G(SCH_1):PAGE11_I171@PURE_QUANTA.GENOA_SP5(CHIPS)':
 'MBB_DQS_H2': CDS_PINID='MBB_DQS_H2';
NODE_NAME     J15 126
 '@T6G_MB_LIB.T6G(SCH_1):PAGE86_I367@PURE_QUANTA.SCONN288_DDR506112002KQ(CHIPS)':
 'DQS2_B_T': CDS_PINID='DQS2_B_T';
NET_NAME
'M_B_CPU0_SB_DQS_DP<3>'
 '@T6G_MB_LIB.T6G(SCH_1):M_B_CPU0_SB_DQS_DP'<3>:
 C_SIGNAL='@t6g_mb_lib.t6g(sch_1):m_b_cpu0_sb_dqs_dp(3)';
NODE_NAME     U25 DB63
 '@T6G_MB_LIB.T6G(SCH_1):PAGE11_I171@PURE_QUANTA.GENOA_SP5(CHIPS)':
 'MBB_DQS_H3': CDS_PINID='MBB_DQS_H3';
NODE_NAME     J15 137
 '@T6G_MB_LIB.T6G(SCH_1):PAGE86_I367@PURE_QUANTA.SCONN288_DDR506112002KQ(CHIPS)':
 'DQS3_B_T': CDS_PINID='DQS3_B_T';
NET_NAME
'M_B_CPU0_SB_DQS_DP<4>'
 '@T6G_MB_LIB.T6G(SCH_1):M_B_CPU0_SB_DQS_DP'<4>:
 C_SIGNAL='@t6g_mb_lib.t6g(sch_1):m_b_cpu0_sb_dqs_dp(4)';
NODE_NAME     U25 BY62
 '@T6G_MB_LIB.T6G(SCH_1):PAGE11_I171@PURE_QUANTA.GENOA_SP5(CHIPS)':
 'MBB_DQS_H4': CDS_PINID='MBB_DQS_H4';
NODE_NAME     J15 239
 '@T6G_MB_LIB.T6G(SCH_1):PAGE86_I367@PURE_QUANTA.SCONN288_DDR506112002KQ(CHIPS)':
 'DQS4_B_T': CDS_PINID='DQS4_B_T';
NET_NAME
'M_B_CPU0_SB_DQS_DP<5>'
 '@T6G_MB_LIB.T6G(SCH_1):M_B_CPU0_SB_DQS_DP'<5>:
 C_SIGNAL='@t6g_mb_lib.t6g(sch_1):m_b_cpu0_sb_dqs_dp(5)';
NODE_NAME     U25 CF62
 '@T6G_MB_LIB.T6G(SCH_1):PAGE11_I171@PURE_QUANTA.GENOA_SP5(CHIPS)':
 'MBB_DQS_H5': CDS_PINID='MBB_DQS_H5';
NODE_NAME     J15 250
 '@T6G_MB_LIB.T6G(SCH_1):PAGE86_I367@PURE_QUANTA.SCONN288_DDR506112002KQ(CHIPS)':
 'DQS5_B_T||TDQS5_B_T': CDS_PINID='\dqs5_b_t||tdqs5_b_t\';
NET_NAME
'M_B_CPU0_SB_DQS_DP<6>'
 '@T6G_MB_LIB.T6G(SCH_1):M_B_CPU0_SB_DQS_DP'<6>:
 C_SIGNAL='@t6g_mb_lib.t6g(sch_1):m_b_cpu0_sb_dqs_dp(6)';
NODE_NAME     U25 CM62
 '@T6G_MB_LIB.T6G(SCH_1):PAGE11_I171@PURE_QUANTA.GENOA_SP5(CHIPS)':
 'MBB_DQS_H6': CDS_PINID='MBB_DQS_H6';
NODE_NAME     J15 261
 '@T6G_MB_LIB.T6G(SCH_1):PAGE86_I367@PURE_QUANTA.SCONN288_DDR506112002KQ(CHIPS)':
 'DQS6_B_T||TDQS6_B_T': CDS_PINID='\dqs6_b_t||tdqs6_b_t\';
NET_NAME
'M_B_CPU0_SB_DQS_DP<7>'
 '@T6G_MB_LIB.T6G(SCH_1):M_B_CPU0_SB_DQS_DP'<7>:
 C_SIGNAL='@t6g_mb_lib.t6g(sch_1):m_b_cpu0_sb_dqs_dp(7)';
NODE_NAME     U25 CV62
 '@T6G_MB_LIB.T6G(SCH_1):PAGE11_I171@PURE_QUANTA.GENOA_SP5(CHIPS)':
 'MBB_DQS_H7': CDS_PINID='MBB_DQS_H7';
NODE_NAME     J15 272
 '@T6G_MB_LIB.T6G(SCH_1):PAGE86_I367@PURE_QUANTA.SCONN288_DDR506112002KQ(CHIPS)':
 'DQS7_B_T||TDQS7_B_T': CDS_PINID='\dqs7_b_t||tdqs7_b_t\';
NET_NAME
'M_B_CPU0_SB_DQS_DP<8>'
 '@T6G_MB_LIB.T6G(SCH_1):M_B_CPU0_SB_DQS_DP'<8>:
 C_SIGNAL='@t6g_mb_lib.t6g(sch_1):m_b_cpu0_sb_dqs_dp(8)';
NODE_NAME     U25 DD62
 '@T6G_MB_LIB.T6G(SCH_1):PAGE11_I171@PURE_QUANTA.GENOA_SP5(CHIPS)':
 'MBB_DQS_H8': CDS_PINID='MBB_DQS_H8';
NODE_NAME     J15 283
 '@T6G_MB_LIB.T6G(SCH_1):PAGE86_I367@PURE_QUANTA.SCONN288_DDR506112002KQ(CHIPS)':
 'DQS8_B_T||TDQS8_B_T': CDS_PINID='\dqs8_b_t||tdqs8_b_t\';
NET_NAME
'M_B_CPU0_SB_DQS_DP<9>'
 '@T6G_MB_LIB.T6G(SCH_1):M_B_CPU0_SB_DQS_DP'<9>:
 C_SIGNAL='@t6g_mb_lib.t6g(sch_1):m_b_cpu0_sb_dqs_dp(9)';
NODE_NAME     U25 BV63
 '@T6G_MB_LIB.T6G(SCH_1):PAGE11_I171@PURE_QUANTA.GENOA_SP5(CHIPS)':
 'MBB_DQS_H9': CDS_PINID='MBB_DQS_H9';
NODE_NAME     J15 93
 '@T6G_MB_LIB.T6G(SCH_1):PAGE86_I367@PURE_QUANTA.SCONN288_DDR506112002KQ(CHIPS)':
 'DQS9_B_T||TDQS9_B_T||DBI4_B_N': CDS_PINID='\dqs9_b_t||tdqs9_b_t||dbi4_b_n\';
NET_NAME
'M_B_CPU0_SB_PAR'
 '@T6G_MB_LIB.T6G(SCH_1):M_B_CPU0_SB_PAR':
 C_SIGNAL='@t6g_mb_lib.t6g(sch_1):m_b_cpu0_sb_par';
NODE_NAME     U25 BL64
 '@T6G_MB_LIB.T6G(SCH_1):PAGE11_I171@PURE_QUANTA.GENOA_SP5(CHIPS)':
 'MBB_PAR': CDS_PINID='MBB_PAR';
NODE_NAME     J15 227
 '@T6G_MB_LIB.T6G(SCH_1):PAGE86_I350@PURE_QUANTA.SCONN288_DDR506112002KQ(CHIPS)':
 'PAR_B': CDS_PINID='PAR_B';
NET_NAME
'M_B_CPU0_SB_RSP<0>'
 '@T6G_MB_LIB.T6G(SCH_1):M_B_CPU0_SB_RSP'<0>:
 C_SIGNAL='@t6g_mb_lib.t6g(sch_1):m_b_cpu0_sb_rsp(0)';
NODE_NAME     U25 BP63
 '@T6G_MB_LIB.T6G(SCH_1):PAGE11_I171@PURE_QUANTA.GENOA_SP5(CHIPS)':
 'MBB0_RSP_L': CDS_PINID='MBB0_RSP_L';
NODE_NAME     J15 87
 '@T6G_MB_LIB.T6G(SCH_1):PAGE86_I350@PURE_QUANTA.SCONN288_DDR506112002KQ(CHIPS)':
 'LBS||RSP_B_N': CDS_PINID='\lbs||rsp_b_n\';
NET_NAME
'M_B_CPU1_ALERT_N'
 '@T6G_MB_LIB.T6G(SCH_1):M_B_CPU1_ALERT_N':
 C_SIGNAL='@t6g_mb_lib.t6g(sch_1):m_b_cpu1_alert_n';
NODE_NAME     R501 1
 '@T6G_MB_LIB.T6G(SCH_1):PAGE38_I314@PURE_QUANTA.Q_RES(CHIPS)':
 'A': CDS_PINID='A';
NODE_NAME     J26 62
 '@T6G_MB_LIB.T6G(SCH_1):PAGE98_I22@PURE_QUANTA.SCONN288_DDR506112002KQ(CHIPS)':
 'ALERT_N': CDS_PINID='ALERT_N';
NET_NAME
'M_B_CPU1_ALERT_R_N'
 '@T6G_MB_LIB.T6G(SCH_1):M_B_CPU1_ALERT_R_N':
 C_SIGNAL='@t6g_mb_lib.t6g(sch_1):m_b_cpu1_alert_r_n';
NODE_NAME     U26 AT62
 '@T6G_MB_LIB.T6G(SCH_1):PAGE38_I159@PURE_QUANTA.GENOA_SP5(CHIPS)':
 'MB_ALERT_L': CDS_PINID='MB_ALERT_L';
NODE_NAME     R501 2
 '@T6G_MB_LIB.T6G(SCH_1):PAGE38_I314@PURE_QUANTA.Q_RES(CHIPS)':
 'B': CDS_PINID='B';
NET_NAME
'M_B_CPU1_CLK_DN<0>'
 '@T6G_MB_LIB.T6G(SCH_1):M_B_CPU1_CLK_DN'<0>:
 C_SIGNAL='@t6g_mb_lib.t6g(sch_1):m_b_cpu1_clk_dn(0)';
NODE_NAME     U26 BD63
 '@T6G_MB_LIB.T6G(SCH_1):PAGE38_I159@PURE_QUANTA.GENOA_SP5(CHIPS)':
 'MB0_CLK_L': CDS_PINID='MB0_CLK_L';
NODE_NAME     J26 218
 '@T6G_MB_LIB.T6G(SCH_1):PAGE98_I22@PURE_QUANTA.SCONN288_DDR506112002KQ(CHIPS)':
 'CK_C': CDS_PINID='CK_C';
NET_NAME
'M_B_CPU1_CLK_DP<0>'
 '@T6G_MB_LIB.T6G(SCH_1):M_B_CPU1_CLK_DP'<0>:
 C_SIGNAL='@t6g_mb_lib.t6g(sch_1):m_b_cpu1_clk_dp(0)';
NODE_NAME     U26 BC64
 '@T6G_MB_LIB.T6G(SCH_1):PAGE38_I159@PURE_QUANTA.GENOA_SP5(CHIPS)':
 'MB0_CLK_H': CDS_PINID='MB0_CLK_H';
NODE_NAME     J26 217
 '@T6G_MB_LIB.T6G(SCH_1):PAGE98_I22@PURE_QUANTA.SCONN288_DDR506112002KQ(CHIPS)':
 'CK_T': CDS_PINID='CK_T';
NET_NAME
'M_B_CPU1_RESET_N'
 '@T6G_MB_LIB.T6G(SCH_1):M_B_CPU1_RESET_N':
 C_SIGNAL='@t6g_mb_lib.t6g(sch_1):m_b_cpu1_reset_n';
NODE_NAME     U26 AU62
 '@T6G_MB_LIB.T6G(SCH_1):PAGE38_I159@PURE_QUANTA.GENOA_SP5(CHIPS)':
 'MB_RESET_L': CDS_PINID='MB_RESET_L';
NODE_NAME     J26 207
 '@T6G_MB_LIB.T6G(SCH_1):PAGE98_I22@PURE_QUANTA.SCONN288_DDR506112002KQ(CHIPS)':
 'RESET_N': CDS_PINID='RESET_N';
NET_NAME
'M_B_CPU1_SA_CA<0>'
 '@T6G_MB_LIB.T6G(SCH_1):M_B_CPU1_SA_CA'<0>:
 C_SIGNAL='@t6g_mb_lib.t6g(sch_1):m_b_cpu1_sa_ca(0)';
NODE_NAME     U26 AW64
 '@T6G_MB_LIB.T6G(SCH_1):PAGE38_I159@PURE_QUANTA.GENOA_SP5(CHIPS)':
 'MBA_CA0': CDS_PINID='MBA_CA0';
NODE_NAME     J26 66
 '@T6G_MB_LIB.T6G(SCH_1):PAGE98_I22@PURE_QUANTA.SCONN288_DDR506112002KQ(CHIPS)':
 'CA0_A': CDS_PINID='CA0_A';
NET_NAME
'M_B_CPU1_SA_CA<1>'
 '@T6G_MB_LIB.T6G(SCH_1):M_B_CPU1_SA_CA'<1>:
 C_SIGNAL='@t6g_mb_lib.t6g(sch_1):m_b_cpu1_sa_ca(1)';
NODE_NAME     U26 AY63
 '@T6G_MB_LIB.T6G(SCH_1):PAGE38_I159@PURE_QUANTA.GENOA_SP5(CHIPS)':
 'MBA_CA1': CDS_PINID='MBA_CA1';
NODE_NAME     J26 211
 '@T6G_MB_LIB.T6G(SCH_1):PAGE98_I22@PURE_QUANTA.SCONN288_DDR506112002KQ(CHIPS)':
 'CA1_A': CDS_PINID='CA1_A';
NET_NAME
'M_B_CPU1_SA_CA<2>'
 '@T6G_MB_LIB.T6G(SCH_1):M_B_CPU1_SA_CA'<2>:
 C_SIGNAL='@t6g_mb_lib.t6g(sch_1):m_b_cpu1_sa_ca(2)';
NODE_NAME     U26 AY62
 '@T6G_MB_LIB.T6G(SCH_1):PAGE38_I159@PURE_QUANTA.GENOA_SP5(CHIPS)':
 'MBA_CA2': CDS_PINID='MBA_CA2';
NODE_NAME     J26 68
 '@T6G_MB_LIB.T6G(SCH_1):PAGE98_I22@PURE_QUANTA.SCONN288_DDR506112002KQ(CHIPS)':
 'CA2_A': CDS_PINID='CA2_A';
NET_NAME
'M_B_CPU1_SA_CA<3>'
 '@T6G_MB_LIB.T6G(SCH_1):M_B_CPU1_SA_CA'<3>:
 C_SIGNAL='@t6g_mb_lib.t6g(sch_1):m_b_cpu1_sa_ca(3)';
NODE_NAME     U26 BA62
 '@T6G_MB_LIB.T6G(SCH_1):PAGE38_I159@PURE_QUANTA.GENOA_SP5(CHIPS)':
 'MBA_CA3': CDS_PINID='MBA_CA3';
NODE_NAME     J26 213
 '@T6G_MB_LIB.T6G(SCH_1):PAGE98_I22@PURE_QUANTA.SCONN288_DDR506112002KQ(CHIPS)':
 'CA3_A': CDS_PINID='CA3_A';
NET_NAME
'M_B_CPU1_SA_CA<4>'
 '@T6G_MB_LIB.T6G(SCH_1):M_B_CPU1_SA_CA'<4>:
 C_SIGNAL='@t6g_mb_lib.t6g(sch_1):m_b_cpu1_sa_ca(4)';
NODE_NAME     U26 BA64
 '@T6G_MB_LIB.T6G(SCH_1):PAGE38_I159@PURE_QUANTA.GENOA_SP5(CHIPS)':
 'MBA_CA4': CDS_PINID='MBA_CA4';
NODE_NAME     J26 70
 '@T6G_MB_LIB.T6G(SCH_1):PAGE98_I22@PURE_QUANTA.SCONN288_DDR506112002KQ(CHIPS)':
 'CA4_A': CDS_PINID='CA4_A';
NET_NAME
'M_B_CPU1_SA_CA<5>'
 '@T6G_MB_LIB.T6G(SCH_1):M_B_CPU1_SA_CA'<5>:
 C_SIGNAL='@t6g_mb_lib.t6g(sch_1):m_b_cpu1_sa_ca(5)';
NODE_NAME     U26 BB63
 '@T6G_MB_LIB.T6G(SCH_1):PAGE38_I159@PURE_QUANTA.GENOA_SP5(CHIPS)':
 'MBA_CA5': CDS_PINID='MBA_CA5';
NODE_NAME     J26 215
 '@T6G_MB_LIB.T6G(SCH_1):PAGE98_I22@PURE_QUANTA.SCONN288_DDR506112002KQ(CHIPS)':
 'CA5_A': CDS_PINID='CA5_A';
NET_NAME
'M_B_CPU1_SA_CA<6>'
 '@T6G_MB_LIB.T6G(SCH_1):M_B_CPU1_SA_CA'<6>:
 C_SIGNAL='@t6g_mb_lib.t6g(sch_1):m_b_cpu1_sa_ca(6)';
NODE_NAME     U26 BB62
 '@T6G_MB_LIB.T6G(SCH_1):PAGE38_I159@PURE_QUANTA.GENOA_SP5(CHIPS)':
 'MBA_CA6': CDS_PINID='MBA_CA6';
NODE_NAME     J26 72
 '@T6G_MB_LIB.T6G(SCH_1):PAGE98_I22@PURE_QUANTA.SCONN288_DDR506112002KQ(CHIPS)':
 'CA6_A': CDS_PINID='CA6_A';
NET_NAME
'M_B_CPU1_SA_CB<0>'
 '@T6G_MB_LIB.T6G(SCH_1):M_B_CPU1_SA_CB'<0>:
 C_SIGNAL='@t6g_mb_lib.t6g(sch_1):m_b_cpu1_sa_cb(0)';
NODE_NAME     U26 AJ64
 '@T6G_MB_LIB.T6G(SCH_1):PAGE38_I159@PURE_QUANTA.GENOA_SP5(CHIPS)':
 'MBA_CHECK0': CDS_PINID='MBA_CHECK0';
NODE_NAME     J26 51
 '@T6G_MB_LIB.T6G(SCH_1):PAGE98_I22@PURE_QUANTA.SCONN288_DDR506112002KQ(CHIPS)':
 'CB0_A': CDS_PINID='CB0_A';
NET_NAME
'M_B_CPU1_SA_CB<1>'
 '@T6G_MB_LIB.T6G(SCH_1):M_B_CPU1_SA_CB'<1>:
 C_SIGNAL='@t6g_mb_lib.t6g(sch_1):m_b_cpu1_sa_cb(1)';
NODE_NAME     U26 AK62
 '@T6G_MB_LIB.T6G(SCH_1):PAGE38_I159@PURE_QUANTA.GENOA_SP5(CHIPS)':
 'MBA_CHECK1': CDS_PINID='MBA_CHECK1';
NODE_NAME     J26 53
 '@T6G_MB_LIB.T6G(SCH_1):PAGE98_I22@PURE_QUANTA.SCONN288_DDR506112002KQ(CHIPS)':
 'CB1_A': CDS_PINID='CB1_A';
NET_NAME
'M_B_CPU1_SA_CB<2>'
 '@T6G_MB_LIB.T6G(SCH_1):M_B_CPU1_SA_CB'<2>:
 C_SIGNAL='@t6g_mb_lib.t6g(sch_1):m_b_cpu1_sa_cb(2)';
NODE_NAME     U26 AK63
 '@T6G_MB_LIB.T6G(SCH_1):PAGE38_I159@PURE_QUANTA.GENOA_SP5(CHIPS)':
 'MBA_CHECK2': CDS_PINID='MBA_CHECK2';
NODE_NAME     J26 196
 '@T6G_MB_LIB.T6G(SCH_1):PAGE98_I22@PURE_QUANTA.SCONN288_DDR506112002KQ(CHIPS)':
 'CB2_A': CDS_PINID='CB2_A';
NET_NAME
'M_B_CPU1_SA_CB<3>'
 '@T6G_MB_LIB.T6G(SCH_1):M_B_CPU1_SA_CB'<3>:
 C_SIGNAL='@t6g_mb_lib.t6g(sch_1):m_b_cpu1_sa_cb(3)';
NODE_NAME     U26 AL62
 '@T6G_MB_LIB.T6G(SCH_1):PAGE38_I159@PURE_QUANTA.GENOA_SP5(CHIPS)':
 'MBA_CHECK3': CDS_PINID='MBA_CHECK3';
NODE_NAME     J26 198
 '@T6G_MB_LIB.T6G(SCH_1):PAGE98_I22@PURE_QUANTA.SCONN288_DDR506112002KQ(CHIPS)':
 'CB3_A': CDS_PINID='CB3_A';
NET_NAME
'M_B_CPU1_SA_CB<4>'
 '@T6G_MB_LIB.T6G(SCH_1):M_B_CPU1_SA_CB'<4>:
 C_SIGNAL='@t6g_mb_lib.t6g(sch_1):m_b_cpu1_sa_cb(4)';
NODE_NAME     U26 AN64
 '@T6G_MB_LIB.T6G(SCH_1):PAGE38_I159@PURE_QUANTA.GENOA_SP5(CHIPS)':
 'MBA_CHECK4': CDS_PINID='MBA_CHECK4';
NODE_NAME     J26 58
 '@T6G_MB_LIB.T6G(SCH_1):PAGE98_I22@PURE_QUANTA.SCONN288_DDR506112002KQ(CHIPS)':
 'CB4_A': CDS_PINID='CB4_A';
NET_NAME
'M_B_CPU1_SA_CB<5>'
 '@T6G_MB_LIB.T6G(SCH_1):M_B_CPU1_SA_CB'<5>:
 C_SIGNAL='@t6g_mb_lib.t6g(sch_1):m_b_cpu1_sa_cb(5)';
NODE_NAME     U26 AP62
 '@T6G_MB_LIB.T6G(SCH_1):PAGE38_I159@PURE_QUANTA.GENOA_SP5(CHIPS)':
 'MBA_CHECK5': CDS_PINID='MBA_CHECK5';
NODE_NAME     J26 60
 '@T6G_MB_LIB.T6G(SCH_1):PAGE98_I22@PURE_QUANTA.SCONN288_DDR506112002KQ(CHIPS)':
 'CB5_A': CDS_PINID='CB5_A';
NET_NAME
'M_B_CPU1_SA_CB<6>'
 '@T6G_MB_LIB.T6G(SCH_1):M_B_CPU1_SA_CB'<6>:
 C_SIGNAL='@t6g_mb_lib.t6g(sch_1):m_b_cpu1_sa_cb(6)';
NODE_NAME     U26 AP63
 '@T6G_MB_LIB.T6G(SCH_1):PAGE38_I159@PURE_QUANTA.GENOA_SP5(CHIPS)':
 'MBA_CHECK6': CDS_PINID='MBA_CHECK6';
NODE_NAME     J26 203
 '@T6G_MB_LIB.T6G(SCH_1):PAGE98_I22@PURE_QUANTA.SCONN288_DDR506112002KQ(CHIPS)':
 'CB6_A': CDS_PINID='CB6_A';
NET_NAME
'M_B_CPU1_SA_CB<7>'
 '@T6G_MB_LIB.T6G(SCH_1):M_B_CPU1_SA_CB'<7>:
 C_SIGNAL='@t6g_mb_lib.t6g(sch_1):m_b_cpu1_sa_cb(7)';
NODE_NAME     U26 AR62
 '@T6G_MB_LIB.T6G(SCH_1):PAGE38_I159@PURE_QUANTA.GENOA_SP5(CHIPS)':
 'MBA_CHECK7': CDS_PINID='MBA_CHECK7';
NODE_NAME     J26 205
 '@T6G_MB_LIB.T6G(SCH_1):PAGE98_I22@PURE_QUANTA.SCONN288_DDR506112002KQ(CHIPS)':
 'CB7_A': CDS_PINID='CB7_A';
NET_NAME
'M_B_CPU1_SA_CS_N<0>'
 '@T6G_MB_LIB.T6G(SCH_1):M_B_CPU1_SA_CS_N'<0>:
 C_SIGNAL='@t6g_mb_lib.t6g(sch_1):m_b_cpu1_sa_cs_n(0)';
NODE_NAME     U26 AV63
 '@T6G_MB_LIB.T6G(SCH_1):PAGE38_I159@PURE_QUANTA.GENOA_SP5(CHIPS)':
 'MBA0_CS_L0': CDS_PINID='MBA0_CS_L0';
NODE_NAME     J26 64
 '@T6G_MB_LIB.T6G(SCH_1):PAGE98_I22@PURE_QUANTA.SCONN288_DDR506112002KQ(CHIPS)':
 'CS0_A_N': CDS_PINID='CS0_A_N';
NET_NAME
'M_B_CPU1_SA_CS_N<1>'
 '@T6G_MB_LIB.T6G(SCH_1):M_B_CPU1_SA_CS_N'<1>:
 C_SIGNAL='@t6g_mb_lib.t6g(sch_1):m_b_cpu1_sa_cs_n(1)';
NODE_NAME     U26 AW62
 '@T6G_MB_LIB.T6G(SCH_1):PAGE38_I159@PURE_QUANTA.GENOA_SP5(CHIPS)':
 'MBA0_CS_L1': CDS_PINID='MBA0_CS_L1';
NODE_NAME     J26 209
 '@T6G_MB_LIB.T6G(SCH_1):PAGE98_I22@PURE_QUANTA.SCONN288_DDR506112002KQ(CHIPS)':
 'CS1_A_N': CDS_PINID='CS1_A_N';
NET_NAME
'M_B_CPU1_SA_DQ<0>'
 '@T6G_MB_LIB.T6G(SCH_1):M_B_CPU1_SA_DQ'<0>:
 C_SIGNAL='@t6g_mb_lib.t6g(sch_1):m_b_cpu1_sa_dq(0)';
NODE_NAME     U26 E64
 '@T6G_MB_LIB.T6G(SCH_1):PAGE38_I159@PURE_QUANTA.GENOA_SP5(CHIPS)':
 'MBA_DATA0': CDS_PINID='MBA_DATA0';
NODE_NAME     J26 7
 '@T6G_MB_LIB.T6G(SCH_1):PAGE98_I22@PURE_QUANTA.SCONN288_DDR506112002KQ(CHIPS)':
 'DQ0_A': CDS_PINID='DQ0_A';
NET_NAME
'M_B_CPU1_SA_DQ<10>'
 '@T6G_MB_LIB.T6G(SCH_1):M_B_CPU1_SA_DQ'<10>:
 C_SIGNAL='@t6g_mb_lib.t6g(sch_1):m_b_cpu1_sa_dq(10)';
NODE_NAME     U26 M63
 '@T6G_MB_LIB.T6G(SCH_1):PAGE38_I159@PURE_QUANTA.GENOA_SP5(CHIPS)':
 'MBA_DATA10': CDS_PINID='MBA_DATA10';
NODE_NAME     J26 163
 '@T6G_MB_LIB.T6G(SCH_1):PAGE98_I22@PURE_QUANTA.SCONN288_DDR506112002KQ(CHIPS)':
 'DQ10_A': CDS_PINID='DQ10_A';
NET_NAME
'M_B_CPU1_SA_DQ<11>'
 '@T6G_MB_LIB.T6G(SCH_1):M_B_CPU1_SA_DQ'<11>:
 C_SIGNAL='@t6g_mb_lib.t6g(sch_1):m_b_cpu1_sa_dq(11)';
NODE_NAME     U26 N62
 '@T6G_MB_LIB.T6G(SCH_1):PAGE38_I159@PURE_QUANTA.GENOA_SP5(CHIPS)':
 'MBA_DATA11': CDS_PINID='MBA_DATA11';
NODE_NAME     J26 165
 '@T6G_MB_LIB.T6G(SCH_1):PAGE98_I22@PURE_QUANTA.SCONN288_DDR506112002KQ(CHIPS)':
 'DQ11_A': CDS_PINID='DQ11_A';
NET_NAME
'M_B_CPU1_SA_DQ<12>'
 '@T6G_MB_LIB.T6G(SCH_1):M_B_CPU1_SA_DQ'<12>:
 C_SIGNAL='@t6g_mb_lib.t6g(sch_1):m_b_cpu1_sa_dq(12)';
NODE_NAME     U26 R64
 '@T6G_MB_LIB.T6G(SCH_1):PAGE38_I159@PURE_QUANTA.GENOA_SP5(CHIPS)':
 'MBA_DATA12': CDS_PINID='MBA_DATA12';
NODE_NAME     J26 25
 '@T6G_MB_LIB.T6G(SCH_1):PAGE98_I22@PURE_QUANTA.SCONN288_DDR506112002KQ(CHIPS)':
 'DQ12_A': CDS_PINID='DQ12_A';
NET_NAME
'M_B_CPU1_SA_DQ<13>'
 '@T6G_MB_LIB.T6G(SCH_1):M_B_CPU1_SA_DQ'<13>:
 C_SIGNAL='@t6g_mb_lib.t6g(sch_1):m_b_cpu1_sa_dq(13)';
NODE_NAME     U26 T62
 '@T6G_MB_LIB.T6G(SCH_1):PAGE38_I159@PURE_QUANTA.GENOA_SP5(CHIPS)':
 'MBA_DATA13': CDS_PINID='MBA_DATA13';
NODE_NAME     J26 27
 '@T6G_MB_LIB.T6G(SCH_1):PAGE98_I22@PURE_QUANTA.SCONN288_DDR506112002KQ(CHIPS)':
 'DQ13_A': CDS_PINID='DQ13_A';
NET_NAME
'M_B_CPU1_SA_DQ<14>'
 '@T6G_MB_LIB.T6G(SCH_1):M_B_CPU1_SA_DQ'<14>:
 C_SIGNAL='@t6g_mb_lib.t6g(sch_1):m_b_cpu1_sa_dq(14)';
NODE_NAME     U26 T63
 '@T6G_MB_LIB.T6G(SCH_1):PAGE38_I159@PURE_QUANTA.GENOA_SP5(CHIPS)':
 'MBA_DATA14': CDS_PINID='MBA_DATA14';
NODE_NAME     J26 170
 '@T6G_MB_LIB.T6G(SCH_1):PAGE98_I22@PURE_QUANTA.SCONN288_DDR506112002KQ(CHIPS)':
 'DQ14_A': CDS_PINID='DQ14_A';
NET_NAME
'M_B_CPU1_SA_DQ<15>'
 '@T6G_MB_LIB.T6G(SCH_1):M_B_CPU1_SA_DQ'<15>:
 C_SIGNAL='@t6g_mb_lib.t6g(sch_1):m_b_cpu1_sa_dq(15)';
NODE_NAME     U26 U62
 '@T6G_MB_LIB.T6G(SCH_1):PAGE38_I159@PURE_QUANTA.GENOA_SP5(CHIPS)':
 'MBA_DATA15': CDS_PINID='MBA_DATA15';
NODE_NAME     J26 172
 '@T6G_MB_LIB.T6G(SCH_1):PAGE98_I22@PURE_QUANTA.SCONN288_DDR506112002KQ(CHIPS)':
 'DQ15_A': CDS_PINID='DQ15_A';
NET_NAME
'M_B_CPU1_SA_DQ<16>'
 '@T6G_MB_LIB.T6G(SCH_1):M_B_CPU1_SA_DQ'<16>:
 C_SIGNAL='@t6g_mb_lib.t6g(sch_1):m_b_cpu1_sa_dq(16)';
NODE_NAME     U26 U64
 '@T6G_MB_LIB.T6G(SCH_1):PAGE38_I159@PURE_QUANTA.GENOA_SP5(CHIPS)':
 'MBA_DATA16': CDS_PINID='MBA_DATA16';
NODE_NAME     J26 29
 '@T6G_MB_LIB.T6G(SCH_1):PAGE98_I22@PURE_QUANTA.SCONN288_DDR506112002KQ(CHIPS)':
 'DQ16_A': CDS_PINID='DQ16_A';
NET_NAME
'M_B_CPU1_SA_DQ<17>'
 '@T6G_MB_LIB.T6G(SCH_1):M_B_CPU1_SA_DQ'<17>:
 C_SIGNAL='@t6g_mb_lib.t6g(sch_1):m_b_cpu1_sa_dq(17)';
NODE_NAME     U26 V62
 '@T6G_MB_LIB.T6G(SCH_1):PAGE38_I159@PURE_QUANTA.GENOA_SP5(CHIPS)':
 'MBA_DATA17': CDS_PINID='MBA_DATA17';
NODE_NAME     J26 31
 '@T6G_MB_LIB.T6G(SCH_1):PAGE98_I22@PURE_QUANTA.SCONN288_DDR506112002KQ(CHIPS)':
 'DQ17_A': CDS_PINID='DQ17_A';
NET_NAME
'M_B_CPU1_SA_DQ<18>'
 '@T6G_MB_LIB.T6G(SCH_1):M_B_CPU1_SA_DQ'<18>:
 C_SIGNAL='@t6g_mb_lib.t6g(sch_1):m_b_cpu1_sa_dq(18)';
NODE_NAME     U26 V63
 '@T6G_MB_LIB.T6G(SCH_1):PAGE38_I159@PURE_QUANTA.GENOA_SP5(CHIPS)':
 'MBA_DATA18': CDS_PINID='MBA_DATA18';
NODE_NAME     J26 174
 '@T6G_MB_LIB.T6G(SCH_1):PAGE98_I22@PURE_QUANTA.SCONN288_DDR506112002KQ(CHIPS)':
 'DQ18_A': CDS_PINID='DQ18_A';
NET_NAME
'M_B_CPU1_SA_DQ<19>'
 '@T6G_MB_LIB.T6G(SCH_1):M_B_CPU1_SA_DQ'<19>:
 C_SIGNAL='@t6g_mb_lib.t6g(sch_1):m_b_cpu1_sa_dq(19)';
NODE_NAME     U26 W62
 '@T6G_MB_LIB.T6G(SCH_1):PAGE38_I159@PURE_QUANTA.GENOA_SP5(CHIPS)':
 'MBA_DATA19': CDS_PINID='MBA_DATA19';
NODE_NAME     J26 176
 '@T6G_MB_LIB.T6G(SCH_1):PAGE98_I22@PURE_QUANTA.SCONN288_DDR506112002KQ(CHIPS)':
 'DQ19_A': CDS_PINID='DQ19_A';
NET_NAME
'M_B_CPU1_SA_DQ<1>'
 '@T6G_MB_LIB.T6G(SCH_1):M_B_CPU1_SA_DQ'<1>:
 C_SIGNAL='@t6g_mb_lib.t6g(sch_1):m_b_cpu1_sa_dq(1)';
NODE_NAME     U26 F62
 '@T6G_MB_LIB.T6G(SCH_1):PAGE38_I159@PURE_QUANTA.GENOA_SP5(CHIPS)':
 'MBA_DATA1': CDS_PINID='MBA_DATA1';
NODE_NAME     J26 9
 '@T6G_MB_LIB.T6G(SCH_1):PAGE98_I22@PURE_QUANTA.SCONN288_DDR506112002KQ(CHIPS)':
 'DQ1_A': CDS_PINID='DQ1_A';
NET_NAME
'M_B_CPU1_SA_DQ<20>'
 '@T6G_MB_LIB.T6G(SCH_1):M_B_CPU1_SA_DQ'<20>:
 C_SIGNAL='@t6g_mb_lib.t6g(sch_1):m_b_cpu1_sa_dq(20)';
NODE_NAME     U26 AA64
 '@T6G_MB_LIB.T6G(SCH_1):PAGE38_I159@PURE_QUANTA.GENOA_SP5(CHIPS)':
 'MBA_DATA20': CDS_PINID='MBA_DATA20';
NODE_NAME     J26 36
 '@T6G_MB_LIB.T6G(SCH_1):PAGE98_I22@PURE_QUANTA.SCONN288_DDR506112002KQ(CHIPS)':
 'DQ20_A': CDS_PINID='DQ20_A';
NET_NAME
'M_B_CPU1_SA_DQ<21>'
 '@T6G_MB_LIB.T6G(SCH_1):M_B_CPU1_SA_DQ'<21>:
 C_SIGNAL='@t6g_mb_lib.t6g(sch_1):m_b_cpu1_sa_dq(21)';
NODE_NAME     U26 AB62
 '@T6G_MB_LIB.T6G(SCH_1):PAGE38_I159@PURE_QUANTA.GENOA_SP5(CHIPS)':
 'MBA_DATA21': CDS_PINID='MBA_DATA21';
NODE_NAME     J26 38
 '@T6G_MB_LIB.T6G(SCH_1):PAGE98_I22@PURE_QUANTA.SCONN288_DDR506112002KQ(CHIPS)':
 'DQ21_A': CDS_PINID='DQ21_A';
NET_NAME
'M_B_CPU1_SA_DQ<22>'
 '@T6G_MB_LIB.T6G(SCH_1):M_B_CPU1_SA_DQ'<22>:
 C_SIGNAL='@t6g_mb_lib.t6g(sch_1):m_b_cpu1_sa_dq(22)';
NODE_NAME     U26 AB63
 '@T6G_MB_LIB.T6G(SCH_1):PAGE38_I159@PURE_QUANTA.GENOA_SP5(CHIPS)':
 'MBA_DATA22': CDS_PINID='MBA_DATA22';
NODE_NAME     J26 181
 '@T6G_MB_LIB.T6G(SCH_1):PAGE98_I22@PURE_QUANTA.SCONN288_DDR506112002KQ(CHIPS)':
 'DQ22_A': CDS_PINID='DQ22_A';
NET_NAME
'M_B_CPU1_SA_DQ<23>'
 '@T6G_MB_LIB.T6G(SCH_1):M_B_CPU1_SA_DQ'<23>:
 C_SIGNAL='@t6g_mb_lib.t6g(sch_1):m_b_cpu1_sa_dq(23)';
NODE_NAME     U26 AC62
 '@T6G_MB_LIB.T6G(SCH_1):PAGE38_I159@PURE_QUANTA.GENOA_SP5(CHIPS)':
 'MBA_DATA23': CDS_PINID='MBA_DATA23';
NODE_NAME     J26 183
 '@T6G_MB_LIB.T6G(SCH_1):PAGE98_I22@PURE_QUANTA.SCONN288_DDR506112002KQ(CHIPS)':
 'DQ23_A': CDS_PINID='DQ23_A';
NET_NAME
'M_B_CPU1_SA_DQ<24>'
 '@T6G_MB_LIB.T6G(SCH_1):M_B_CPU1_SA_DQ'<24>:
 C_SIGNAL='@t6g_mb_lib.t6g(sch_1):m_b_cpu1_sa_dq(24)';
NODE_NAME     U26 AC64
 '@T6G_MB_LIB.T6G(SCH_1):PAGE38_I159@PURE_QUANTA.GENOA_SP5(CHIPS)':
 'MBA_DATA24': CDS_PINID='MBA_DATA24';
NODE_NAME     J26 40
 '@T6G_MB_LIB.T6G(SCH_1):PAGE98_I22@PURE_QUANTA.SCONN288_DDR506112002KQ(CHIPS)':
 'DQ24_A': CDS_PINID='DQ24_A';
NET_NAME
'M_B_CPU1_SA_DQ<25>'
 '@T6G_MB_LIB.T6G(SCH_1):M_B_CPU1_SA_DQ'<25>:
 C_SIGNAL='@t6g_mb_lib.t6g(sch_1):m_b_cpu1_sa_dq(25)';
NODE_NAME     U26 AD62
 '@T6G_MB_LIB.T6G(SCH_1):PAGE38_I159@PURE_QUANTA.GENOA_SP5(CHIPS)':
 'MBA_DATA25': CDS_PINID='MBA_DATA25';
NODE_NAME     J26 42
 '@T6G_MB_LIB.T6G(SCH_1):PAGE98_I22@PURE_QUANTA.SCONN288_DDR506112002KQ(CHIPS)':
 'DQ25_A': CDS_PINID='DQ25_A';
NET_NAME
'M_B_CPU1_SA_DQ<26>'
 '@T6G_MB_LIB.T6G(SCH_1):M_B_CPU1_SA_DQ'<26>:
 C_SIGNAL='@t6g_mb_lib.t6g(sch_1):m_b_cpu1_sa_dq(26)';
NODE_NAME     U26 AD63
 '@T6G_MB_LIB.T6G(SCH_1):PAGE38_I159@PURE_QUANTA.GENOA_SP5(CHIPS)':
 'MBA_DATA26': CDS_PINID='MBA_DATA26';
NODE_NAME     J26 185
 '@T6G_MB_LIB.T6G(SCH_1):PAGE98_I22@PURE_QUANTA.SCONN288_DDR506112002KQ(CHIPS)':
 'DQ26_A': CDS_PINID='DQ26_A';
NET_NAME
'M_B_CPU1_SA_DQ<27>'
 '@T6G_MB_LIB.T6G(SCH_1):M_B_CPU1_SA_DQ'<27>:
 C_SIGNAL='@t6g_mb_lib.t6g(sch_1):m_b_cpu1_sa_dq(27)';
NODE_NAME     U26 AE62
 '@T6G_MB_LIB.T6G(SCH_1):PAGE38_I159@PURE_QUANTA.GENOA_SP5(CHIPS)':
 'MBA_DATA27': CDS_PINID='MBA_DATA27';
NODE_NAME     J26 187
 '@T6G_MB_LIB.T6G(SCH_1):PAGE98_I22@PURE_QUANTA.SCONN288_DDR506112002KQ(CHIPS)':
 'DQ27_A': CDS_PINID='DQ27_A';
NET_NAME
'M_B_CPU1_SA_DQ<28>'
 '@T6G_MB_LIB.T6G(SCH_1):M_B_CPU1_SA_DQ'<28>:
 C_SIGNAL='@t6g_mb_lib.t6g(sch_1):m_b_cpu1_sa_dq(28)';
NODE_NAME     U26 AG64
 '@T6G_MB_LIB.T6G(SCH_1):PAGE38_I159@PURE_QUANTA.GENOA_SP5(CHIPS)':
 'MBA_DATA28': CDS_PINID='MBA_DATA28';
NODE_NAME     J26 47
 '@T6G_MB_LIB.T6G(SCH_1):PAGE98_I22@PURE_QUANTA.SCONN288_DDR506112002KQ(CHIPS)':
 'DQ28_A': CDS_PINID='DQ28_A';
NET_NAME
'M_B_CPU1_SA_DQ<29>'
 '@T6G_MB_LIB.T6G(SCH_1):M_B_CPU1_SA_DQ'<29>:
 C_SIGNAL='@t6g_mb_lib.t6g(sch_1):m_b_cpu1_sa_dq(29)';
NODE_NAME     U26 AH62
 '@T6G_MB_LIB.T6G(SCH_1):PAGE38_I159@PURE_QUANTA.GENOA_SP5(CHIPS)':
 'MBA_DATA29': CDS_PINID='MBA_DATA29';
NODE_NAME     J26 49
 '@T6G_MB_LIB.T6G(SCH_1):PAGE98_I22@PURE_QUANTA.SCONN288_DDR506112002KQ(CHIPS)':
 'DQ29_A': CDS_PINID='DQ29_A';
NET_NAME
'M_B_CPU1_SA_DQ<2>'
 '@T6G_MB_LIB.T6G(SCH_1):M_B_CPU1_SA_DQ'<2>:
 C_SIGNAL='@t6g_mb_lib.t6g(sch_1):m_b_cpu1_sa_dq(2)';
NODE_NAME     U26 F63
 '@T6G_MB_LIB.T6G(SCH_1):PAGE38_I159@PURE_QUANTA.GENOA_SP5(CHIPS)':
 'MBA_DATA2': CDS_PINID='MBA_DATA2';
NODE_NAME     J26 152
 '@T6G_MB_LIB.T6G(SCH_1):PAGE98_I22@PURE_QUANTA.SCONN288_DDR506112002KQ(CHIPS)':
 'DQ2_A': CDS_PINID='DQ2_A';
NET_NAME
'M_B_CPU1_SA_DQ<30>'
 '@T6G_MB_LIB.T6G(SCH_1):M_B_CPU1_SA_DQ'<30>:
 C_SIGNAL='@t6g_mb_lib.t6g(sch_1):m_b_cpu1_sa_dq(30)';
NODE_NAME     U26 AH63
 '@T6G_MB_LIB.T6G(SCH_1):PAGE38_I159@PURE_QUANTA.GENOA_SP5(CHIPS)':
 'MBA_DATA30': CDS_PINID='MBA_DATA30';
NODE_NAME     J26 192
 '@T6G_MB_LIB.T6G(SCH_1):PAGE98_I22@PURE_QUANTA.SCONN288_DDR506112002KQ(CHIPS)':
 'DQ30_A': CDS_PINID='DQ30_A';
NET_NAME
'M_B_CPU1_SA_DQ<31>'
 '@T6G_MB_LIB.T6G(SCH_1):M_B_CPU1_SA_DQ'<31>:
 C_SIGNAL='@t6g_mb_lib.t6g(sch_1):m_b_cpu1_sa_dq(31)';
NODE_NAME     U26 AJ62
 '@T6G_MB_LIB.T6G(SCH_1):PAGE38_I159@PURE_QUANTA.GENOA_SP5(CHIPS)':
 'MBA_DATA31': CDS_PINID='MBA_DATA31';
NODE_NAME     J26 194
 '@T6G_MB_LIB.T6G(SCH_1):PAGE98_I22@PURE_QUANTA.SCONN288_DDR506112002KQ(CHIPS)':
 'DQ31_A': CDS_PINID='DQ31_A';
NET_NAME
'M_B_CPU1_SA_DQ<3>'
 '@T6G_MB_LIB.T6G(SCH_1):M_B_CPU1_SA_DQ'<3>:
 C_SIGNAL='@t6g_mb_lib.t6g(sch_1):m_b_cpu1_sa_dq(3)';
NODE_NAME     U26 G62
 '@T6G_MB_LIB.T6G(SCH_1):PAGE38_I159@PURE_QUANTA.GENOA_SP5(CHIPS)':
 'MBA_DATA3': CDS_PINID='MBA_DATA3';
NODE_NAME     J26 154
 '@T6G_MB_LIB.T6G(SCH_1):PAGE98_I22@PURE_QUANTA.SCONN288_DDR506112002KQ(CHIPS)':
 'DQ3_A': CDS_PINID='DQ3_A';
NET_NAME
'M_B_CPU1_SA_DQ<4>'
 '@T6G_MB_LIB.T6G(SCH_1):M_B_CPU1_SA_DQ'<4>:
 C_SIGNAL='@t6g_mb_lib.t6g(sch_1):m_b_cpu1_sa_dq(4)';
NODE_NAME     U26 J64
 '@T6G_MB_LIB.T6G(SCH_1):PAGE38_I159@PURE_QUANTA.GENOA_SP5(CHIPS)':
 'MBA_DATA4': CDS_PINID='MBA_DATA4';
NODE_NAME     J26 14
 '@T6G_MB_LIB.T6G(SCH_1):PAGE98_I22@PURE_QUANTA.SCONN288_DDR506112002KQ(CHIPS)':
 'DQ4_A': CDS_PINID='DQ4_A';
NET_NAME
'M_B_CPU1_SA_DQ<5>'
 '@T6G_MB_LIB.T6G(SCH_1):M_B_CPU1_SA_DQ'<5>:
 C_SIGNAL='@t6g_mb_lib.t6g(sch_1):m_b_cpu1_sa_dq(5)';
NODE_NAME     U26 K62
 '@T6G_MB_LIB.T6G(SCH_1):PAGE38_I159@PURE_QUANTA.GENOA_SP5(CHIPS)':
 'MBA_DATA5': CDS_PINID='MBA_DATA5';
NODE_NAME     J26 16
 '@T6G_MB_LIB.T6G(SCH_1):PAGE98_I22@PURE_QUANTA.SCONN288_DDR506112002KQ(CHIPS)':
 'DQ5_A': CDS_PINID='DQ5_A';
NET_NAME
'M_B_CPU1_SA_DQ<6>'
 '@T6G_MB_LIB.T6G(SCH_1):M_B_CPU1_SA_DQ'<6>:
 C_SIGNAL='@t6g_mb_lib.t6g(sch_1):m_b_cpu1_sa_dq(6)';
NODE_NAME     U26 K63
 '@T6G_MB_LIB.T6G(SCH_1):PAGE38_I159@PURE_QUANTA.GENOA_SP5(CHIPS)':
 'MBA_DATA6': CDS_PINID='MBA_DATA6';
NODE_NAME     J26 159
 '@T6G_MB_LIB.T6G(SCH_1):PAGE98_I22@PURE_QUANTA.SCONN288_DDR506112002KQ(CHIPS)':
 'DQ6_A': CDS_PINID='DQ6_A';
NET_NAME
'M_B_CPU1_SA_DQ<7>'
 '@T6G_MB_LIB.T6G(SCH_1):M_B_CPU1_SA_DQ'<7>:
 C_SIGNAL='@t6g_mb_lib.t6g(sch_1):m_b_cpu1_sa_dq(7)';
NODE_NAME     U26 L62
 '@T6G_MB_LIB.T6G(SCH_1):PAGE38_I159@PURE_QUANTA.GENOA_SP5(CHIPS)':
 'MBA_DATA7': CDS_PINID='MBA_DATA7';
NODE_NAME     J26 161
 '@T6G_MB_LIB.T6G(SCH_1):PAGE98_I22@PURE_QUANTA.SCONN288_DDR506112002KQ(CHIPS)':
 'DQ7_A': CDS_PINID='DQ7_A';
NET_NAME
'M_B_CPU1_SA_DQ<8>'
 '@T6G_MB_LIB.T6G(SCH_1):M_B_CPU1_SA_DQ'<8>:
 C_SIGNAL='@t6g_mb_lib.t6g(sch_1):m_b_cpu1_sa_dq(8)';
NODE_NAME     U26 L64
 '@T6G_MB_LIB.T6G(SCH_1):PAGE38_I159@PURE_QUANTA.GENOA_SP5(CHIPS)':
 'MBA_DATA8': CDS_PINID='MBA_DATA8';
NODE_NAME     J26 18
 '@T6G_MB_LIB.T6G(SCH_1):PAGE98_I22@PURE_QUANTA.SCONN288_DDR506112002KQ(CHIPS)':
 'DQ8_A': CDS_PINID='DQ8_A';
NET_NAME
'M_B_CPU1_SA_DQ<9>'
 '@T6G_MB_LIB.T6G(SCH_1):M_B_CPU1_SA_DQ'<9>:
 C_SIGNAL='@t6g_mb_lib.t6g(sch_1):m_b_cpu1_sa_dq(9)';
NODE_NAME     U26 M62
 '@T6G_MB_LIB.T6G(SCH_1):PAGE38_I159@PURE_QUANTA.GENOA_SP5(CHIPS)':
 'MBA_DATA9': CDS_PINID='MBA_DATA9';
NODE_NAME     J26 20
 '@T6G_MB_LIB.T6G(SCH_1):PAGE98_I22@PURE_QUANTA.SCONN288_DDR506112002KQ(CHIPS)':
 'DQ9_A': CDS_PINID='DQ9_A';
NET_NAME
'M_B_CPU1_SA_DQS_DN<0>'
 '@T6G_MB_LIB.T6G(SCH_1):M_B_CPU1_SA_DQS_DN'<0>:
 C_SIGNAL='@t6g_mb_lib.t6g(sch_1):m_b_cpu1_sa_dqs_dn(0)';
NODE_NAME     U26 H63
 '@T6G_MB_LIB.T6G(SCH_1):PAGE38_I159@PURE_QUANTA.GENOA_SP5(CHIPS)':
 'MBA_DQS_L0': CDS_PINID='MBA_DQS_L0';
NODE_NAME     J26 12
 '@T6G_MB_LIB.T6G(SCH_1):PAGE98_I236@PURE_QUANTA.SCONN288_DDR506112002KQ(CHIPS)':
 'DQS0_A_C': CDS_PINID='DQS0_A_C';
NET_NAME
'M_B_CPU1_SA_DQS_DN<1>'
 '@T6G_MB_LIB.T6G(SCH_1):M_B_CPU1_SA_DQS_DN'<1>:
 C_SIGNAL='@t6g_mb_lib.t6g(sch_1):m_b_cpu1_sa_dqs_dn(1)';
NODE_NAME     U26 P63
 '@T6G_MB_LIB.T6G(SCH_1):PAGE38_I159@PURE_QUANTA.GENOA_SP5(CHIPS)':
 'MBA_DQS_L1': CDS_PINID='MBA_DQS_L1';
NODE_NAME     J26 23
 '@T6G_MB_LIB.T6G(SCH_1):PAGE98_I236@PURE_QUANTA.SCONN288_DDR506112002KQ(CHIPS)':
 'DQS1_A_C': CDS_PINID='DQS1_A_C';
NET_NAME
'M_B_CPU1_SA_DQS_DN<2>'
 '@T6G_MB_LIB.T6G(SCH_1):M_B_CPU1_SA_DQS_DN'<2>:
 C_SIGNAL='@t6g_mb_lib.t6g(sch_1):m_b_cpu1_sa_dqs_dn(2)';
NODE_NAME     U26 Y63
 '@T6G_MB_LIB.T6G(SCH_1):PAGE38_I159@PURE_QUANTA.GENOA_SP5(CHIPS)':
 'MBA_DQS_L2': CDS_PINID='MBA_DQS_L2';
NODE_NAME     J26 34
 '@T6G_MB_LIB.T6G(SCH_1):PAGE98_I236@PURE_QUANTA.SCONN288_DDR506112002KQ(CHIPS)':
 'DQS2_A_C': CDS_PINID='DQS2_A_C';
NET_NAME
'M_B_CPU1_SA_DQS_DN<3>'
 '@T6G_MB_LIB.T6G(SCH_1):M_B_CPU1_SA_DQS_DN'<3>:
 C_SIGNAL='@t6g_mb_lib.t6g(sch_1):m_b_cpu1_sa_dqs_dn(3)';
NODE_NAME     U26 AF63
 '@T6G_MB_LIB.T6G(SCH_1):PAGE38_I159@PURE_QUANTA.GENOA_SP5(CHIPS)':
 'MBA_DQS_L3': CDS_PINID='MBA_DQS_L3';
NODE_NAME     J26 45
 '@T6G_MB_LIB.T6G(SCH_1):PAGE98_I236@PURE_QUANTA.SCONN288_DDR506112002KQ(CHIPS)':
 'DQS3_A_C': CDS_PINID='DQS3_A_C';
NET_NAME
'M_B_CPU1_SA_DQS_DN<4>'
 '@T6G_MB_LIB.T6G(SCH_1):M_B_CPU1_SA_DQS_DN'<4>:
 C_SIGNAL='@t6g_mb_lib.t6g(sch_1):m_b_cpu1_sa_dqs_dn(4)';
NODE_NAME     U26 AM63
 '@T6G_MB_LIB.T6G(SCH_1):PAGE38_I159@PURE_QUANTA.GENOA_SP5(CHIPS)':
 'MBA_DQS_L4': CDS_PINID='MBA_DQS_L4';
NODE_NAME     J26 56
 '@T6G_MB_LIB.T6G(SCH_1):PAGE98_I236@PURE_QUANTA.SCONN288_DDR506112002KQ(CHIPS)':
 'DQS4_A_C': CDS_PINID='DQS4_A_C';
NET_NAME
'M_B_CPU1_SA_DQS_DN<5>'
 '@T6G_MB_LIB.T6G(SCH_1):M_B_CPU1_SA_DQS_DN'<5>:
 C_SIGNAL='@t6g_mb_lib.t6g(sch_1):m_b_cpu1_sa_dqs_dn(5)';
NODE_NAME     U26 H62
 '@T6G_MB_LIB.T6G(SCH_1):PAGE38_I159@PURE_QUANTA.GENOA_SP5(CHIPS)':
 'MBA_DQS_L5': CDS_PINID='MBA_DQS_L5';
NODE_NAME     J26 156
 '@T6G_MB_LIB.T6G(SCH_1):PAGE98_I236@PURE_QUANTA.SCONN288_DDR506112002KQ(CHIPS)':
 'DQS5_A_C||TDQS5_A_C||DQS5_A_T||TDQS5_A_T': CDS_PINID='\dqs5_a_c||tdqs5_a_c||dqs5_a_t||tdqs5_a_t\';
NET_NAME
'M_B_CPU1_SA_DQS_DN<6>'
 '@T6G_MB_LIB.T6G(SCH_1):M_B_CPU1_SA_DQS_DN'<6>:
 C_SIGNAL='@t6g_mb_lib.t6g(sch_1):m_b_cpu1_sa_dqs_dn(6)';
NODE_NAME     U26 P62
 '@T6G_MB_LIB.T6G(SCH_1):PAGE38_I159@PURE_QUANTA.GENOA_SP5(CHIPS)':
 'MBA_DQS_L6': CDS_PINID='MBA_DQS_L6';
NODE_NAME     J26 167
 '@T6G_MB_LIB.T6G(SCH_1):PAGE98_I236@PURE_QUANTA.SCONN288_DDR506112002KQ(CHIPS)':
 'DQS6_A_C||TDQS6_A_C||DQS6_A_T||TDQS6_A_T': CDS_PINID='\dqs6_a_c||tdqs6_a_c||dqs6_a_t||tdqs6_a_t\';
NET_NAME
'M_B_CPU1_SA_DQS_DN<7>'
 '@T6G_MB_LIB.T6G(SCH_1):M_B_CPU1_SA_DQS_DN'<7>:
 C_SIGNAL='@t6g_mb_lib.t6g(sch_1):m_b_cpu1_sa_dqs_dn(7)';
NODE_NAME     U26 Y62
 '@T6G_MB_LIB.T6G(SCH_1):PAGE38_I159@PURE_QUANTA.GENOA_SP5(CHIPS)':
 'MBA_DQS_L7': CDS_PINID='MBA_DQS_L7';
NODE_NAME     J26 178
 '@T6G_MB_LIB.T6G(SCH_1):PAGE98_I236@PURE_QUANTA.SCONN288_DDR506112002KQ(CHIPS)':
 'DQS7_A_C||TDQS7_A_C': CDS_PINID='\dqs7_a_c||tdqs7_a_c\';
NET_NAME
'M_B_CPU1_SA_DQS_DN<8>'
 '@T6G_MB_LIB.T6G(SCH_1):M_B_CPU1_SA_DQS_DN'<8>:
 C_SIGNAL='@t6g_mb_lib.t6g(sch_1):m_b_cpu1_sa_dqs_dn(8)';
NODE_NAME     U26 AF62
 '@T6G_MB_LIB.T6G(SCH_1):PAGE38_I159@PURE_QUANTA.GENOA_SP5(CHIPS)':
 'MBA_DQS_L8': CDS_PINID='MBA_DQS_L8';
NODE_NAME     J26 189
 '@T6G_MB_LIB.T6G(SCH_1):PAGE98_I236@PURE_QUANTA.SCONN288_DDR506112002KQ(CHIPS)':
 'DQS8_A_C||TDQS8_A_C': CDS_PINID='\dqs8_a_c||tdqs8_a_c\';
NET_NAME
'M_B_CPU1_SA_DQS_DN<9>'
 '@T6G_MB_LIB.T6G(SCH_1):M_B_CPU1_SA_DQS_DN'<9>:
 C_SIGNAL='@t6g_mb_lib.t6g(sch_1):m_b_cpu1_sa_dqs_dn(9)';
NODE_NAME     U26 AM62
 '@T6G_MB_LIB.T6G(SCH_1):PAGE38_I159@PURE_QUANTA.GENOA_SP5(CHIPS)':
 'MBA_DQS_L9': CDS_PINID='MBA_DQS_L9';
NODE_NAME     J26 200
 '@T6G_MB_LIB.T6G(SCH_1):PAGE98_I236@PURE_QUANTA.SCONN288_DDR506112002KQ(CHIPS)':
 'DQS9_A_C||TDQS9_A_C': CDS_PINID='\dqs9_a_c||tdqs9_a_c\';
NET_NAME
'M_B_CPU1_SA_DQS_DP<0>'
 '@T6G_MB_LIB.T6G(SCH_1):M_B_CPU1_SA_DQS_DP'<0>:
 C_SIGNAL='@t6g_mb_lib.t6g(sch_1):m_b_cpu1_sa_dqs_dp(0)';
NODE_NAME     U26 G64
 '@T6G_MB_LIB.T6G(SCH_1):PAGE38_I159@PURE_QUANTA.GENOA_SP5(CHIPS)':
 'MBA_DQS_H0': CDS_PINID='MBA_DQS_H0';
NODE_NAME     J26 11
 '@T6G_MB_LIB.T6G(SCH_1):PAGE98_I236@PURE_QUANTA.SCONN288_DDR506112002KQ(CHIPS)':
 'DQS0_A_T': CDS_PINID='DQS0_A_T';
NET_NAME
'M_B_CPU1_SA_DQS_DP<1>'
 '@T6G_MB_LIB.T6G(SCH_1):M_B_CPU1_SA_DQS_DP'<1>:
 C_SIGNAL='@t6g_mb_lib.t6g(sch_1):m_b_cpu1_sa_dqs_dp(1)';
NODE_NAME     U26 N64
 '@T6G_MB_LIB.T6G(SCH_1):PAGE38_I159@PURE_QUANTA.GENOA_SP5(CHIPS)':
 'MBA_DQS_H1': CDS_PINID='MBA_DQS_H1';
NODE_NAME     J26 22
 '@T6G_MB_LIB.T6G(SCH_1):PAGE98_I236@PURE_QUANTA.SCONN288_DDR506112002KQ(CHIPS)':
 'DQS1_A_T': CDS_PINID='DQS1_A_T';
NET_NAME
'M_B_CPU1_SA_DQS_DP<2>'
 '@T6G_MB_LIB.T6G(SCH_1):M_B_CPU1_SA_DQS_DP'<2>:
 C_SIGNAL='@t6g_mb_lib.t6g(sch_1):m_b_cpu1_sa_dqs_dp(2)';
NODE_NAME     U26 W64
 '@T6G_MB_LIB.T6G(SCH_1):PAGE38_I159@PURE_QUANTA.GENOA_SP5(CHIPS)':
 'MBA_DQS_H2': CDS_PINID='MBA_DQS_H2';
NODE_NAME     J26 33
 '@T6G_MB_LIB.T6G(SCH_1):PAGE98_I236@PURE_QUANTA.SCONN288_DDR506112002KQ(CHIPS)':
 'DQS2_A_T': CDS_PINID='DQS2_A_T';
NET_NAME
'M_B_CPU1_SA_DQS_DP<3>'
 '@T6G_MB_LIB.T6G(SCH_1):M_B_CPU1_SA_DQS_DP'<3>:
 C_SIGNAL='@t6g_mb_lib.t6g(sch_1):m_b_cpu1_sa_dqs_dp(3)';
NODE_NAME     U26 AE64
 '@T6G_MB_LIB.T6G(SCH_1):PAGE38_I159@PURE_QUANTA.GENOA_SP5(CHIPS)':
 'MBA_DQS_H3': CDS_PINID='MBA_DQS_H3';
NODE_NAME     J26 44
 '@T6G_MB_LIB.T6G(SCH_1):PAGE98_I236@PURE_QUANTA.SCONN288_DDR506112002KQ(CHIPS)':
 'DQS3_A_T': CDS_PINID='DQS3_A_T';
NET_NAME
'M_B_CPU1_SA_DQS_DP<4>'
 '@T6G_MB_LIB.T6G(SCH_1):M_B_CPU1_SA_DQS_DP'<4>:
 C_SIGNAL='@t6g_mb_lib.t6g(sch_1):m_b_cpu1_sa_dqs_dp(4)';
NODE_NAME     U26 AL64
 '@T6G_MB_LIB.T6G(SCH_1):PAGE38_I159@PURE_QUANTA.GENOA_SP5(CHIPS)':
 'MBA_DQS_H4': CDS_PINID='MBA_DQS_H4';
NODE_NAME     J26 55
 '@T6G_MB_LIB.T6G(SCH_1):PAGE98_I236@PURE_QUANTA.SCONN288_DDR506112002KQ(CHIPS)':
 'DQS4_A_T': CDS_PINID='DQS4_A_T';
NET_NAME
'M_B_CPU1_SA_DQS_DP<5>'
 '@T6G_MB_LIB.T6G(SCH_1):M_B_CPU1_SA_DQS_DP'<5>:
 C_SIGNAL='@t6g_mb_lib.t6g(sch_1):m_b_cpu1_sa_dqs_dp(5)';
NODE_NAME     U26 J62
 '@T6G_MB_LIB.T6G(SCH_1):PAGE38_I159@PURE_QUANTA.GENOA_SP5(CHIPS)':
 'MBA_DQS_H5': CDS_PINID='MBA_DQS_H5';
NODE_NAME     J26 157
 '@T6G_MB_LIB.T6G(SCH_1):PAGE98_I236@PURE_QUANTA.SCONN288_DDR506112002KQ(CHIPS)':
 'DQS5_A_T||TDQS5_A_T': CDS_PINID='\dqs5_a_t||tdqs5_a_t\';
NET_NAME
'M_B_CPU1_SA_DQS_DP<6>'
 '@T6G_MB_LIB.T6G(SCH_1):M_B_CPU1_SA_DQS_DP'<6>:
 C_SIGNAL='@t6g_mb_lib.t6g(sch_1):m_b_cpu1_sa_dqs_dp(6)';
NODE_NAME     U26 R62
 '@T6G_MB_LIB.T6G(SCH_1):PAGE38_I159@PURE_QUANTA.GENOA_SP5(CHIPS)':
 'MBA_DQS_H6': CDS_PINID='MBA_DQS_H6';
NODE_NAME     J26 168
 '@T6G_MB_LIB.T6G(SCH_1):PAGE98_I236@PURE_QUANTA.SCONN288_DDR506112002KQ(CHIPS)':
 'DQS6_A_T||TDQS6_A_T': CDS_PINID='\dqs6_a_t||tdqs6_a_t\';
NET_NAME
'M_B_CPU1_SA_DQS_DP<7>'
 '@T6G_MB_LIB.T6G(SCH_1):M_B_CPU1_SA_DQS_DP'<7>:
 C_SIGNAL='@t6g_mb_lib.t6g(sch_1):m_b_cpu1_sa_dqs_dp(7)';
NODE_NAME     U26 AA62
 '@T6G_MB_LIB.T6G(SCH_1):PAGE38_I159@PURE_QUANTA.GENOA_SP5(CHIPS)':
 'MBA_DQS_H7': CDS_PINID='MBA_DQS_H7';
NODE_NAME     J26 179
 '@T6G_MB_LIB.T6G(SCH_1):PAGE98_I236@PURE_QUANTA.SCONN288_DDR506112002KQ(CHIPS)':
 'DQS7_A_T||TDQS7_A_T': CDS_PINID='\dqs7_a_t||tdqs7_a_t\';
NET_NAME
'M_B_CPU1_SA_DQS_DP<8>'
 '@T6G_MB_LIB.T6G(SCH_1):M_B_CPU1_SA_DQS_DP'<8>:
 C_SIGNAL='@t6g_mb_lib.t6g(sch_1):m_b_cpu1_sa_dqs_dp(8)';
NODE_NAME     U26 AG62
 '@T6G_MB_LIB.T6G(SCH_1):PAGE38_I159@PURE_QUANTA.GENOA_SP5(CHIPS)':
 'MBA_DQS_H8': CDS_PINID='MBA_DQS_H8';
NODE_NAME     J26 190
 '@T6G_MB_LIB.T6G(SCH_1):PAGE98_I236@PURE_QUANTA.SCONN288_DDR506112002KQ(CHIPS)':
 'DQS8_A_T||TDQS8_A_T': CDS_PINID='\dqs8_a_t||tdqs8_a_t\';
NET_NAME
'M_B_CPU1_SA_DQS_DP<9>'
 '@T6G_MB_LIB.T6G(SCH_1):M_B_CPU1_SA_DQS_DP'<9>:
 C_SIGNAL='@t6g_mb_lib.t6g(sch_1):m_b_cpu1_sa_dqs_dp(9)';
NODE_NAME     U26 AN62
 '@T6G_MB_LIB.T6G(SCH_1):PAGE38_I159@PURE_QUANTA.GENOA_SP5(CHIPS)':
 'MBA_DQS_H9': CDS_PINID='MBA_DQS_H9';
NODE_NAME     J26 201
 '@T6G_MB_LIB.T6G(SCH_1):PAGE98_I236@PURE_QUANTA.SCONN288_DDR506112002KQ(CHIPS)':
 'DQS9_A_T||TDQS9_A_T': CDS_PINID='\dqs9_a_t||tdqs9_a_t\';
NET_NAME
'M_B_CPU1_SA_PAR'
 '@T6G_MB_LIB.T6G(SCH_1):M_B_CPU1_SA_PAR':
 C_SIGNAL='@t6g_mb_lib.t6g(sch_1):m_b_cpu1_sa_par';
NODE_NAME     U26 BC62
 '@T6G_MB_LIB.T6G(SCH_1):PAGE38_I159@PURE_QUANTA.GENOA_SP5(CHIPS)':
 'MBA_PAR': CDS_PINID='MBA_PAR';
NODE_NAME     J26 74
 '@T6G_MB_LIB.T6G(SCH_1):PAGE98_I22@PURE_QUANTA.SCONN288_DDR506112002KQ(CHIPS)':
 'PAR_A': CDS_PINID='PAR_A';
NET_NAME
'M_B_CPU1_SA_RSP<0>'
 '@T6G_MB_LIB.T6G(SCH_1):M_B_CPU1_SA_RSP'<0>:
 C_SIGNAL='@t6g_mb_lib.t6g(sch_1):m_b_cpu1_sa_rsp(0)';
NODE_NAME     U26 BN62
 '@T6G_MB_LIB.T6G(SCH_1):PAGE38_I159@PURE_QUANTA.GENOA_SP5(CHIPS)':
 'MBA0_RSP_L': CDS_PINID='MBA0_RSP_L';
NODE_NAME     J26 86
 '@T6G_MB_LIB.T6G(SCH_1):PAGE98_I22@PURE_QUANTA.SCONN288_DDR506112002KQ(CHIPS)':
 'LBD||RSP_A_N': CDS_PINID='\lbd||rsp_a_n\';
NET_NAME
'M_B_CPU1_SB_CA<0>'
 '@T6G_MB_LIB.T6G(SCH_1):M_B_CPU1_SB_CA'<0>:
 C_SIGNAL='@t6g_mb_lib.t6g(sch_1):m_b_cpu1_sb_ca(0)';
NODE_NAME     U26 BG62
 '@T6G_MB_LIB.T6G(SCH_1):PAGE38_I159@PURE_QUANTA.GENOA_SP5(CHIPS)':
 'MBB_CA0': CDS_PINID='MBB_CA0';
NODE_NAME     J26 76
 '@T6G_MB_LIB.T6G(SCH_1):PAGE98_I22@PURE_QUANTA.SCONN288_DDR506112002KQ(CHIPS)':
 'CA0_B': CDS_PINID='CA0_B';
NET_NAME
'M_B_CPU1_SB_CA<1>'
 '@T6G_MB_LIB.T6G(SCH_1):M_B_CPU1_SB_CA'<1>:
 C_SIGNAL='@t6g_mb_lib.t6g(sch_1):m_b_cpu1_sb_ca(1)';
NODE_NAME     U26 BH62
 '@T6G_MB_LIB.T6G(SCH_1):PAGE38_I159@PURE_QUANTA.GENOA_SP5(CHIPS)':
 'MBB_CA1': CDS_PINID='MBB_CA1';
NODE_NAME     J26 221
 '@T6G_MB_LIB.T6G(SCH_1):PAGE98_I22@PURE_QUANTA.SCONN288_DDR506112002KQ(CHIPS)':
 'CA1_B': CDS_PINID='CA1_B';
NET_NAME
'M_B_CPU1_SB_CA<2>'
 '@T6G_MB_LIB.T6G(SCH_1):M_B_CPU1_SB_CA'<2>:
 C_SIGNAL='@t6g_mb_lib.t6g(sch_1):m_b_cpu1_sb_ca(2)';
NODE_NAME     U26 BH63
 '@T6G_MB_LIB.T6G(SCH_1):PAGE38_I159@PURE_QUANTA.GENOA_SP5(CHIPS)':
 'MBB_CA2': CDS_PINID='MBB_CA2';
NODE_NAME     J26 78
 '@T6G_MB_LIB.T6G(SCH_1):PAGE98_I22@PURE_QUANTA.SCONN288_DDR506112002KQ(CHIPS)':
 'CA2_B': CDS_PINID='CA2_B';
NET_NAME
'M_B_CPU1_SB_CA<3>'
 '@T6G_MB_LIB.T6G(SCH_1):M_B_CPU1_SB_CA'<3>:
 C_SIGNAL='@t6g_mb_lib.t6g(sch_1):m_b_cpu1_sb_ca(3)';
NODE_NAME     U26 BJ64
 '@T6G_MB_LIB.T6G(SCH_1):PAGE38_I159@PURE_QUANTA.GENOA_SP5(CHIPS)':
 'MBB_CA3': CDS_PINID='MBB_CA3';
NODE_NAME     J26 223
 '@T6G_MB_LIB.T6G(SCH_1):PAGE98_I22@PURE_QUANTA.SCONN288_DDR506112002KQ(CHIPS)':
 'CA3_B': CDS_PINID='CA3_B';
NET_NAME
'M_B_CPU1_SB_CA<4>'
 '@T6G_MB_LIB.T6G(SCH_1):M_B_CPU1_SB_CA'<4>:
 C_SIGNAL='@t6g_mb_lib.t6g(sch_1):m_b_cpu1_sb_ca(4)';
NODE_NAME     U26 BJ62
 '@T6G_MB_LIB.T6G(SCH_1):PAGE38_I159@PURE_QUANTA.GENOA_SP5(CHIPS)':
 'MBB_CA4': CDS_PINID='MBB_CA4';
NODE_NAME     J26 80
 '@T6G_MB_LIB.T6G(SCH_1):PAGE98_I22@PURE_QUANTA.SCONN288_DDR506112002KQ(CHIPS)':
 'CA4_B': CDS_PINID='CA4_B';
NET_NAME
'M_B_CPU1_SB_CA<5>'
 '@T6G_MB_LIB.T6G(SCH_1):M_B_CPU1_SB_CA'<5>:
 C_SIGNAL='@t6g_mb_lib.t6g(sch_1):m_b_cpu1_sb_ca(5)';
NODE_NAME     U26 BK62
 '@T6G_MB_LIB.T6G(SCH_1):PAGE38_I159@PURE_QUANTA.GENOA_SP5(CHIPS)':
 'MBB_CA5': CDS_PINID='MBB_CA5';
NODE_NAME     J26 225
 '@T6G_MB_LIB.T6G(SCH_1):PAGE98_I22@PURE_QUANTA.SCONN288_DDR506112002KQ(CHIPS)':
 'CA5_B': CDS_PINID='CA5_B';
NET_NAME
'M_B_CPU1_SB_CA<6>'
 '@T6G_MB_LIB.T6G(SCH_1):M_B_CPU1_SB_CA'<6>:
 C_SIGNAL='@t6g_mb_lib.t6g(sch_1):m_b_cpu1_sb_ca(6)';
NODE_NAME     U26 BK63
 '@T6G_MB_LIB.T6G(SCH_1):PAGE38_I159@PURE_QUANTA.GENOA_SP5(CHIPS)':
 'MBB_CA6': CDS_PINID='MBB_CA6';
NODE_NAME     J26 82
 '@T6G_MB_LIB.T6G(SCH_1):PAGE98_I22@PURE_QUANTA.SCONN288_DDR506112002KQ(CHIPS)':
 'CA6_B': CDS_PINID='CA6_B';
NET_NAME
'M_B_CPU1_SB_CB<0>'
 '@T6G_MB_LIB.T6G(SCH_1):M_B_CPU1_SB_CB'<0>:
 C_SIGNAL='@t6g_mb_lib.t6g(sch_1):m_b_cpu1_sb_cb(0)';
NODE_NAME     U26 BY63
 '@T6G_MB_LIB.T6G(SCH_1):PAGE38_I159@PURE_QUANTA.GENOA_SP5(CHIPS)':
 'MBB_CHECK0': CDS_PINID='MBB_CHECK0';
NODE_NAME     J26 96
 '@T6G_MB_LIB.T6G(SCH_1):PAGE98_I22@PURE_QUANTA.SCONN288_DDR506112002KQ(CHIPS)':
 'CB0_B': CDS_PINID='CB0_B';
NET_NAME
'M_B_CPU1_SB_CB<1>'
 '@T6G_MB_LIB.T6G(SCH_1):M_B_CPU1_SB_CB'<1>:
 C_SIGNAL='@t6g_mb_lib.t6g(sch_1):m_b_cpu1_sb_cb(1)';
NODE_NAME     U26 CA62
 '@T6G_MB_LIB.T6G(SCH_1):PAGE38_I159@PURE_QUANTA.GENOA_SP5(CHIPS)':
 'MBB_CHECK1': CDS_PINID='MBB_CHECK1';
NODE_NAME     J26 98
 '@T6G_MB_LIB.T6G(SCH_1):PAGE98_I22@PURE_QUANTA.SCONN288_DDR506112002KQ(CHIPS)':
 'CB1_B': CDS_PINID='CB1_B';
NET_NAME
'M_B_CPU1_SB_CB<2>'
 '@T6G_MB_LIB.T6G(SCH_1):M_B_CPU1_SB_CB'<2>:
 C_SIGNAL='@t6g_mb_lib.t6g(sch_1):m_b_cpu1_sb_cb(2)';
NODE_NAME     U26 CA64
 '@T6G_MB_LIB.T6G(SCH_1):PAGE38_I159@PURE_QUANTA.GENOA_SP5(CHIPS)':
 'MBB_CHECK2': CDS_PINID='MBB_CHECK2';
NODE_NAME     J26 241
 '@T6G_MB_LIB.T6G(SCH_1):PAGE98_I22@PURE_QUANTA.SCONN288_DDR506112002KQ(CHIPS)':
 'CB2_B': CDS_PINID='CB2_B';
NET_NAME
'M_B_CPU1_SB_CB<3>'
 '@T6G_MB_LIB.T6G(SCH_1):M_B_CPU1_SB_CB'<3>:
 C_SIGNAL='@t6g_mb_lib.t6g(sch_1):m_b_cpu1_sb_cb(3)';
NODE_NAME     U26 CB62
 '@T6G_MB_LIB.T6G(SCH_1):PAGE38_I159@PURE_QUANTA.GENOA_SP5(CHIPS)':
 'MBB_CHECK3': CDS_PINID='MBB_CHECK3';
NODE_NAME     J26 243
 '@T6G_MB_LIB.T6G(SCH_1):PAGE98_I22@PURE_QUANTA.SCONN288_DDR506112002KQ(CHIPS)':
 'CB3_B': CDS_PINID='CB3_B';
NET_NAME
'M_B_CPU1_SB_CB<4>'
 '@T6G_MB_LIB.T6G(SCH_1):M_B_CPU1_SB_CB'<4>:
 C_SIGNAL='@t6g_mb_lib.t6g(sch_1):m_b_cpu1_sb_cb(4)';
NODE_NAME     U26 BT63
 '@T6G_MB_LIB.T6G(SCH_1):PAGE38_I159@PURE_QUANTA.GENOA_SP5(CHIPS)':
 'MBB_CHECK4': CDS_PINID='MBB_CHECK4';
NODE_NAME     J26 89
 '@T6G_MB_LIB.T6G(SCH_1):PAGE98_I22@PURE_QUANTA.SCONN288_DDR506112002KQ(CHIPS)':
 'CB4_B': CDS_PINID='CB4_B';
NET_NAME
'M_B_CPU1_SB_CB<5>'
 '@T6G_MB_LIB.T6G(SCH_1):M_B_CPU1_SB_CB'<5>:
 C_SIGNAL='@t6g_mb_lib.t6g(sch_1):m_b_cpu1_sb_cb(5)';
NODE_NAME     U26 BU62
 '@T6G_MB_LIB.T6G(SCH_1):PAGE38_I159@PURE_QUANTA.GENOA_SP5(CHIPS)':
 'MBB_CHECK5': CDS_PINID='MBB_CHECK5';
NODE_NAME     J26 91
 '@T6G_MB_LIB.T6G(SCH_1):PAGE98_I22@PURE_QUANTA.SCONN288_DDR506112002KQ(CHIPS)':
 'CB5_B': CDS_PINID='CB5_B';
NET_NAME
'M_B_CPU1_SB_CB<6>'
 '@T6G_MB_LIB.T6G(SCH_1):M_B_CPU1_SB_CB'<6>:
 C_SIGNAL='@t6g_mb_lib.t6g(sch_1):m_b_cpu1_sb_cb(6)';
NODE_NAME     U26 BU64
 '@T6G_MB_LIB.T6G(SCH_1):PAGE38_I159@PURE_QUANTA.GENOA_SP5(CHIPS)':
 'MBB_CHECK6': CDS_PINID='MBB_CHECK6';
NODE_NAME     J26 234
 '@T6G_MB_LIB.T6G(SCH_1):PAGE98_I22@PURE_QUANTA.SCONN288_DDR506112002KQ(CHIPS)':
 'CB6_B': CDS_PINID='CB6_B';
NET_NAME
'M_B_CPU1_SB_CB<7>'
 '@T6G_MB_LIB.T6G(SCH_1):M_B_CPU1_SB_CB'<7>:
 C_SIGNAL='@t6g_mb_lib.t6g(sch_1):m_b_cpu1_sb_cb(7)';
NODE_NAME     U26 BV62
 '@T6G_MB_LIB.T6G(SCH_1):PAGE38_I159@PURE_QUANTA.GENOA_SP5(CHIPS)':
 'MBB_CHECK7': CDS_PINID='MBB_CHECK7';
NODE_NAME     J26 236
 '@T6G_MB_LIB.T6G(SCH_1):PAGE98_I22@PURE_QUANTA.SCONN288_DDR506112002KQ(CHIPS)':
 'CB7_B': CDS_PINID='CB7_B';
NET_NAME
'M_B_CPU1_SB_CS_N<0>'
 '@T6G_MB_LIB.T6G(SCH_1):M_B_CPU1_SB_CS_N'<0>:
 C_SIGNAL='@t6g_mb_lib.t6g(sch_1):m_b_cpu1_sb_cs_n(0)';
NODE_NAME     U26 BM62
 '@T6G_MB_LIB.T6G(SCH_1):PAGE38_I159@PURE_QUANTA.GENOA_SP5(CHIPS)':
 'MBB0_CS_L0': CDS_PINID='MBB0_CS_L0';
NODE_NAME     J26 84
 '@T6G_MB_LIB.T6G(SCH_1):PAGE98_I22@PURE_QUANTA.SCONN288_DDR506112002KQ(CHIPS)':
 'CS0_B_N': CDS_PINID='CS0_B_N';
NET_NAME
'M_B_CPU1_SB_CS_N<1>'
 '@T6G_MB_LIB.T6G(SCH_1):M_B_CPU1_SB_CS_N'<1>:
 C_SIGNAL='@t6g_mb_lib.t6g(sch_1):m_b_cpu1_sb_cs_n(1)';
NODE_NAME     U26 BN64
 '@T6G_MB_LIB.T6G(SCH_1):PAGE38_I159@PURE_QUANTA.GENOA_SP5(CHIPS)':
 'MBB0_CS_L1': CDS_PINID='MBB0_CS_L1';
NODE_NAME     J26 229
 '@T6G_MB_LIB.T6G(SCH_1):PAGE98_I22@PURE_QUANTA.SCONN288_DDR506112002KQ(CHIPS)':
 'CS1_B_N': CDS_PINID='CS1_B_N';
NET_NAME
'M_B_CPU1_SB_DQ<0>'
 '@T6G_MB_LIB.T6G(SCH_1):M_B_CPU1_SB_DQ'<0>:
 C_SIGNAL='@t6g_mb_lib.t6g(sch_1):m_b_cpu1_sb_dq(0)';
NODE_NAME     U26 CB63
 '@T6G_MB_LIB.T6G(SCH_1):PAGE38_I159@PURE_QUANTA.GENOA_SP5(CHIPS)':
 'MBB_DATA0': CDS_PINID='MBB_DATA0';
NODE_NAME     J26 100
 '@T6G_MB_LIB.T6G(SCH_1):PAGE98_I22@PURE_QUANTA.SCONN288_DDR506112002KQ(CHIPS)':
 'DQ0_B': CDS_PINID='DQ0_B';
NET_NAME
'M_B_CPU1_SB_DQ<10>'
 '@T6G_MB_LIB.T6G(SCH_1):M_B_CPU1_SB_DQ'<10>:
 C_SIGNAL='@t6g_mb_lib.t6g(sch_1):m_b_cpu1_sb_dq(10)';
NODE_NAME     U26 CJ64
 '@T6G_MB_LIB.T6G(SCH_1):PAGE38_I159@PURE_QUANTA.GENOA_SP5(CHIPS)':
 'MBB_DATA10': CDS_PINID='MBB_DATA10';
NODE_NAME     J26 256
 '@T6G_MB_LIB.T6G(SCH_1):PAGE98_I22@PURE_QUANTA.SCONN288_DDR506112002KQ(CHIPS)':
 'DQ10_B': CDS_PINID='DQ10_B';
NET_NAME
'M_B_CPU1_SB_DQ<11>'
 '@T6G_MB_LIB.T6G(SCH_1):M_B_CPU1_SB_DQ'<11>:
 C_SIGNAL='@t6g_mb_lib.t6g(sch_1):m_b_cpu1_sb_dq(11)';
NODE_NAME     U26 CK62
 '@T6G_MB_LIB.T6G(SCH_1):PAGE38_I159@PURE_QUANTA.GENOA_SP5(CHIPS)':
 'MBB_DATA11': CDS_PINID='MBB_DATA11';
NODE_NAME     J26 258
 '@T6G_MB_LIB.T6G(SCH_1):PAGE98_I22@PURE_QUANTA.SCONN288_DDR506112002KQ(CHIPS)':
 'DQ11_B': CDS_PINID='DQ11_B';
NET_NAME
'M_B_CPU1_SB_DQ<12>'
 '@T6G_MB_LIB.T6G(SCH_1):M_B_CPU1_SB_DQ'<12>:
 C_SIGNAL='@t6g_mb_lib.t6g(sch_1):m_b_cpu1_sb_dq(12)';
NODE_NAME     U26 CM63
 '@T6G_MB_LIB.T6G(SCH_1):PAGE38_I159@PURE_QUANTA.GENOA_SP5(CHIPS)':
 'MBB_DATA12': CDS_PINID='MBB_DATA12';
NODE_NAME     J26 118
 '@T6G_MB_LIB.T6G(SCH_1):PAGE98_I22@PURE_QUANTA.SCONN288_DDR506112002KQ(CHIPS)':
 'DQ12_B': CDS_PINID='DQ12_B';
NET_NAME
'M_B_CPU1_SB_DQ<13>'
 '@T6G_MB_LIB.T6G(SCH_1):M_B_CPU1_SB_DQ'<13>:
 C_SIGNAL='@t6g_mb_lib.t6g(sch_1):m_b_cpu1_sb_dq(13)';
NODE_NAME     U26 CN62
 '@T6G_MB_LIB.T6G(SCH_1):PAGE38_I159@PURE_QUANTA.GENOA_SP5(CHIPS)':
 'MBB_DATA13': CDS_PINID='MBB_DATA13';
NODE_NAME     J26 120
 '@T6G_MB_LIB.T6G(SCH_1):PAGE98_I22@PURE_QUANTA.SCONN288_DDR506112002KQ(CHIPS)':
 'DQ13_B': CDS_PINID='DQ13_B';
NET_NAME
'M_B_CPU1_SB_DQ<14>'
 '@T6G_MB_LIB.T6G(SCH_1):M_B_CPU1_SB_DQ'<14>:
 C_SIGNAL='@t6g_mb_lib.t6g(sch_1):m_b_cpu1_sb_dq(14)';
NODE_NAME     U26 CN64
 '@T6G_MB_LIB.T6G(SCH_1):PAGE38_I159@PURE_QUANTA.GENOA_SP5(CHIPS)':
 'MBB_DATA14': CDS_PINID='MBB_DATA14';
NODE_NAME     J26 263
 '@T6G_MB_LIB.T6G(SCH_1):PAGE98_I22@PURE_QUANTA.SCONN288_DDR506112002KQ(CHIPS)':
 'DQ14_B': CDS_PINID='DQ14_B';
NET_NAME
'M_B_CPU1_SB_DQ<15>'
 '@T6G_MB_LIB.T6G(SCH_1):M_B_CPU1_SB_DQ'<15>:
 C_SIGNAL='@t6g_mb_lib.t6g(sch_1):m_b_cpu1_sb_dq(15)';
NODE_NAME     U26 CP62
 '@T6G_MB_LIB.T6G(SCH_1):PAGE38_I159@PURE_QUANTA.GENOA_SP5(CHIPS)':
 'MBB_DATA15': CDS_PINID='MBB_DATA15';
NODE_NAME     J26 265
 '@T6G_MB_LIB.T6G(SCH_1):PAGE98_I22@PURE_QUANTA.SCONN288_DDR506112002KQ(CHIPS)':
 'DQ15_B': CDS_PINID='DQ15_B';
NET_NAME
'M_B_CPU1_SB_DQ<16>'
 '@T6G_MB_LIB.T6G(SCH_1):M_B_CPU1_SB_DQ'<16>:
 C_SIGNAL='@t6g_mb_lib.t6g(sch_1):m_b_cpu1_sb_dq(16)';
NODE_NAME     U26 CP63
 '@T6G_MB_LIB.T6G(SCH_1):PAGE38_I159@PURE_QUANTA.GENOA_SP5(CHIPS)':
 'MBB_DATA16': CDS_PINID='MBB_DATA16';
NODE_NAME     J26 122
 '@T6G_MB_LIB.T6G(SCH_1):PAGE98_I22@PURE_QUANTA.SCONN288_DDR506112002KQ(CHIPS)':
 'DQ16_B': CDS_PINID='DQ16_B';
NET_NAME
'M_B_CPU1_SB_DQ<17>'
 '@T6G_MB_LIB.T6G(SCH_1):M_B_CPU1_SB_DQ'<17>:
 C_SIGNAL='@t6g_mb_lib.t6g(sch_1):m_b_cpu1_sb_dq(17)';
NODE_NAME     U26 CR62
 '@T6G_MB_LIB.T6G(SCH_1):PAGE38_I159@PURE_QUANTA.GENOA_SP5(CHIPS)':
 'MBB_DATA17': CDS_PINID='MBB_DATA17';
NODE_NAME     J26 124
 '@T6G_MB_LIB.T6G(SCH_1):PAGE98_I22@PURE_QUANTA.SCONN288_DDR506112002KQ(CHIPS)':
 'DQ17_B': CDS_PINID='DQ17_B';
NET_NAME
'M_B_CPU1_SB_DQ<18>'
 '@T6G_MB_LIB.T6G(SCH_1):M_B_CPU1_SB_DQ'<18>:
 C_SIGNAL='@t6g_mb_lib.t6g(sch_1):m_b_cpu1_sb_dq(18)';
NODE_NAME     U26 CR64
 '@T6G_MB_LIB.T6G(SCH_1):PAGE38_I159@PURE_QUANTA.GENOA_SP5(CHIPS)':
 'MBB_DATA18': CDS_PINID='MBB_DATA18';
NODE_NAME     J26 267
 '@T6G_MB_LIB.T6G(SCH_1):PAGE98_I22@PURE_QUANTA.SCONN288_DDR506112002KQ(CHIPS)':
 'DQ18_B': CDS_PINID='DQ18_B';
NET_NAME
'M_B_CPU1_SB_DQ<19>'
 '@T6G_MB_LIB.T6G(SCH_1):M_B_CPU1_SB_DQ'<19>:
 C_SIGNAL='@t6g_mb_lib.t6g(sch_1):m_b_cpu1_sb_dq(19)';
NODE_NAME     U26 CT62
 '@T6G_MB_LIB.T6G(SCH_1):PAGE38_I159@PURE_QUANTA.GENOA_SP5(CHIPS)':
 'MBB_DATA19': CDS_PINID='MBB_DATA19';
NODE_NAME     J26 269
 '@T6G_MB_LIB.T6G(SCH_1):PAGE98_I22@PURE_QUANTA.SCONN288_DDR506112002KQ(CHIPS)':
 'DQ19_B': CDS_PINID='DQ19_B';
NET_NAME
'M_B_CPU1_SB_DQ<1>'
 '@T6G_MB_LIB.T6G(SCH_1):M_B_CPU1_SB_DQ'<1>:
 C_SIGNAL='@t6g_mb_lib.t6g(sch_1):m_b_cpu1_sb_dq(1)';
NODE_NAME     U26 CC62
 '@T6G_MB_LIB.T6G(SCH_1):PAGE38_I159@PURE_QUANTA.GENOA_SP5(CHIPS)':
 'MBB_DATA1': CDS_PINID='MBB_DATA1';
NODE_NAME     J26 102
 '@T6G_MB_LIB.T6G(SCH_1):PAGE98_I22@PURE_QUANTA.SCONN288_DDR506112002KQ(CHIPS)':
 'DQ1_B': CDS_PINID='DQ1_B';
NET_NAME
'M_B_CPU1_SB_DQ<20>'
 '@T6G_MB_LIB.T6G(SCH_1):M_B_CPU1_SB_DQ'<20>:
 C_SIGNAL='@t6g_mb_lib.t6g(sch_1):m_b_cpu1_sb_dq(20)';
NODE_NAME     U26 CV63
 '@T6G_MB_LIB.T6G(SCH_1):PAGE38_I159@PURE_QUANTA.GENOA_SP5(CHIPS)':
 'MBB_DATA20': CDS_PINID='MBB_DATA20';
NODE_NAME     J26 129
 '@T6G_MB_LIB.T6G(SCH_1):PAGE98_I22@PURE_QUANTA.SCONN288_DDR506112002KQ(CHIPS)':
 'DQ20_B': CDS_PINID='DQ20_B';
NET_NAME
'M_B_CPU1_SB_DQ<21>'
 '@T6G_MB_LIB.T6G(SCH_1):M_B_CPU1_SB_DQ'<21>:
 C_SIGNAL='@t6g_mb_lib.t6g(sch_1):m_b_cpu1_sb_dq(21)';
NODE_NAME     U26 CW62
 '@T6G_MB_LIB.T6G(SCH_1):PAGE38_I159@PURE_QUANTA.GENOA_SP5(CHIPS)':
 'MBB_DATA21': CDS_PINID='MBB_DATA21';
NODE_NAME     J26 131
 '@T6G_MB_LIB.T6G(SCH_1):PAGE98_I22@PURE_QUANTA.SCONN288_DDR506112002KQ(CHIPS)':
 'DQ21_B': CDS_PINID='DQ21_B';
NET_NAME
'M_B_CPU1_SB_DQ<22>'
 '@T6G_MB_LIB.T6G(SCH_1):M_B_CPU1_SB_DQ'<22>:
 C_SIGNAL='@t6g_mb_lib.t6g(sch_1):m_b_cpu1_sb_dq(22)';
NODE_NAME     U26 CW64
 '@T6G_MB_LIB.T6G(SCH_1):PAGE38_I159@PURE_QUANTA.GENOA_SP5(CHIPS)':
 'MBB_DATA22': CDS_PINID='MBB_DATA22';
NODE_NAME     J26 274
 '@T6G_MB_LIB.T6G(SCH_1):PAGE98_I22@PURE_QUANTA.SCONN288_DDR506112002KQ(CHIPS)':
 'DQ22_B': CDS_PINID='DQ22_B';
NET_NAME
'M_B_CPU1_SB_DQ<23>'
 '@T6G_MB_LIB.T6G(SCH_1):M_B_CPU1_SB_DQ'<23>:
 C_SIGNAL='@t6g_mb_lib.t6g(sch_1):m_b_cpu1_sb_dq(23)';
NODE_NAME     U26 CY62
 '@T6G_MB_LIB.T6G(SCH_1):PAGE38_I159@PURE_QUANTA.GENOA_SP5(CHIPS)':
 'MBB_DATA23': CDS_PINID='MBB_DATA23';
NODE_NAME     J26 276
 '@T6G_MB_LIB.T6G(SCH_1):PAGE98_I22@PURE_QUANTA.SCONN288_DDR506112002KQ(CHIPS)':
 'DQ23_B': CDS_PINID='DQ23_B';
NET_NAME
'M_B_CPU1_SB_DQ<24>'
 '@T6G_MB_LIB.T6G(SCH_1):M_B_CPU1_SB_DQ'<24>:
 C_SIGNAL='@t6g_mb_lib.t6g(sch_1):m_b_cpu1_sb_dq(24)';
NODE_NAME     U26 CY63
 '@T6G_MB_LIB.T6G(SCH_1):PAGE38_I159@PURE_QUANTA.GENOA_SP5(CHIPS)':
 'MBB_DATA24': CDS_PINID='MBB_DATA24';
NODE_NAME     J26 133
 '@T6G_MB_LIB.T6G(SCH_1):PAGE98_I22@PURE_QUANTA.SCONN288_DDR506112002KQ(CHIPS)':
 'DQ24_B': CDS_PINID='DQ24_B';
NET_NAME
'M_B_CPU1_SB_DQ<25>'
 '@T6G_MB_LIB.T6G(SCH_1):M_B_CPU1_SB_DQ'<25>:
 C_SIGNAL='@t6g_mb_lib.t6g(sch_1):m_b_cpu1_sb_dq(25)';
NODE_NAME     U26 DA62
 '@T6G_MB_LIB.T6G(SCH_1):PAGE38_I159@PURE_QUANTA.GENOA_SP5(CHIPS)':
 'MBB_DATA25': CDS_PINID='MBB_DATA25';
NODE_NAME     J26 135
 '@T6G_MB_LIB.T6G(SCH_1):PAGE98_I22@PURE_QUANTA.SCONN288_DDR506112002KQ(CHIPS)':
 'DQ25_B': CDS_PINID='DQ25_B';
NET_NAME
'M_B_CPU1_SB_DQ<26>'
 '@T6G_MB_LIB.T6G(SCH_1):M_B_CPU1_SB_DQ'<26>:
 C_SIGNAL='@t6g_mb_lib.t6g(sch_1):m_b_cpu1_sb_dq(26)';
NODE_NAME     U26 DA64
 '@T6G_MB_LIB.T6G(SCH_1):PAGE38_I159@PURE_QUANTA.GENOA_SP5(CHIPS)':
 'MBB_DATA26': CDS_PINID='MBB_DATA26';
NODE_NAME     J26 278
 '@T6G_MB_LIB.T6G(SCH_1):PAGE98_I22@PURE_QUANTA.SCONN288_DDR506112002KQ(CHIPS)':
 'DQ26_B': CDS_PINID='DQ26_B';
NET_NAME
'M_B_CPU1_SB_DQ<27>'
 '@T6G_MB_LIB.T6G(SCH_1):M_B_CPU1_SB_DQ'<27>:
 C_SIGNAL='@t6g_mb_lib.t6g(sch_1):m_b_cpu1_sb_dq(27)';
NODE_NAME     U26 DB62
 '@T6G_MB_LIB.T6G(SCH_1):PAGE38_I159@PURE_QUANTA.GENOA_SP5(CHIPS)':
 'MBB_DATA27': CDS_PINID='MBB_DATA27';
NODE_NAME     J26 280
 '@T6G_MB_LIB.T6G(SCH_1):PAGE98_I22@PURE_QUANTA.SCONN288_DDR506112002KQ(CHIPS)':
 'DQ27_B': CDS_PINID='DQ27_B';
NET_NAME
'M_B_CPU1_SB_DQ<28>'
 '@T6G_MB_LIB.T6G(SCH_1):M_B_CPU1_SB_DQ'<28>:
 C_SIGNAL='@t6g_mb_lib.t6g(sch_1):m_b_cpu1_sb_dq(28)';
NODE_NAME     U26 DD63
 '@T6G_MB_LIB.T6G(SCH_1):PAGE38_I159@PURE_QUANTA.GENOA_SP5(CHIPS)':
 'MBB_DATA28': CDS_PINID='MBB_DATA28';
NODE_NAME     J26 140
 '@T6G_MB_LIB.T6G(SCH_1):PAGE98_I22@PURE_QUANTA.SCONN288_DDR506112002KQ(CHIPS)':
 'DQ28_B': CDS_PINID='DQ28_B';
NET_NAME
'M_B_CPU1_SB_DQ<29>'
 '@T6G_MB_LIB.T6G(SCH_1):M_B_CPU1_SB_DQ'<29>:
 C_SIGNAL='@t6g_mb_lib.t6g(sch_1):m_b_cpu1_sb_dq(29)';
NODE_NAME     U26 DE62
 '@T6G_MB_LIB.T6G(SCH_1):PAGE38_I159@PURE_QUANTA.GENOA_SP5(CHIPS)':
 'MBB_DATA29': CDS_PINID='MBB_DATA29';
NODE_NAME     J26 142
 '@T6G_MB_LIB.T6G(SCH_1):PAGE98_I22@PURE_QUANTA.SCONN288_DDR506112002KQ(CHIPS)':
 'DQ29_B': CDS_PINID='DQ29_B';
NET_NAME
'M_B_CPU1_SB_DQ<2>'
 '@T6G_MB_LIB.T6G(SCH_1):M_B_CPU1_SB_DQ'<2>:
 C_SIGNAL='@t6g_mb_lib.t6g(sch_1):m_b_cpu1_sb_dq(2)';
NODE_NAME     U26 CC64
 '@T6G_MB_LIB.T6G(SCH_1):PAGE38_I159@PURE_QUANTA.GENOA_SP5(CHIPS)':
 'MBB_DATA2': CDS_PINID='MBB_DATA2';
NODE_NAME     J26 245
 '@T6G_MB_LIB.T6G(SCH_1):PAGE98_I22@PURE_QUANTA.SCONN288_DDR506112002KQ(CHIPS)':
 'DQ2_B': CDS_PINID='DQ2_B';
NET_NAME
'M_B_CPU1_SB_DQ<30>'
 '@T6G_MB_LIB.T6G(SCH_1):M_B_CPU1_SB_DQ'<30>:
 C_SIGNAL='@t6g_mb_lib.t6g(sch_1):m_b_cpu1_sb_dq(30)';
NODE_NAME     U26 DE64
 '@T6G_MB_LIB.T6G(SCH_1):PAGE38_I159@PURE_QUANTA.GENOA_SP5(CHIPS)':
 'MBB_DATA30': CDS_PINID='MBB_DATA30';
NODE_NAME     J26 285
 '@T6G_MB_LIB.T6G(SCH_1):PAGE98_I22@PURE_QUANTA.SCONN288_DDR506112002KQ(CHIPS)':
 'DQ30_B': CDS_PINID='DQ30_B';
NET_NAME
'M_B_CPU1_SB_DQ<31>'
 '@T6G_MB_LIB.T6G(SCH_1):M_B_CPU1_SB_DQ'<31>:
 C_SIGNAL='@t6g_mb_lib.t6g(sch_1):m_b_cpu1_sb_dq(31)';
NODE_NAME     U26 DF62
 '@T6G_MB_LIB.T6G(SCH_1):PAGE38_I159@PURE_QUANTA.GENOA_SP5(CHIPS)':
 'MBB_DATA31': CDS_PINID='MBB_DATA31';
NODE_NAME     J26 287
 '@T6G_MB_LIB.T6G(SCH_1):PAGE98_I22@PURE_QUANTA.SCONN288_DDR506112002KQ(CHIPS)':
 'DQ31_B': CDS_PINID='DQ31_B';
NET_NAME
'M_B_CPU1_SB_DQ<3>'
 '@T6G_MB_LIB.T6G(SCH_1):M_B_CPU1_SB_DQ'<3>:
 C_SIGNAL='@t6g_mb_lib.t6g(sch_1):m_b_cpu1_sb_dq(3)';
NODE_NAME     U26 CD62
 '@T6G_MB_LIB.T6G(SCH_1):PAGE38_I159@PURE_QUANTA.GENOA_SP5(CHIPS)':
 'MBB_DATA3': CDS_PINID='MBB_DATA3';
NODE_NAME     J26 247
 '@T6G_MB_LIB.T6G(SCH_1):PAGE98_I22@PURE_QUANTA.SCONN288_DDR506112002KQ(CHIPS)':
 'DQ3_B': CDS_PINID='DQ3_B';
NET_NAME
'M_B_CPU1_SB_DQ<4>'
 '@T6G_MB_LIB.T6G(SCH_1):M_B_CPU1_SB_DQ'<4>:
 C_SIGNAL='@t6g_mb_lib.t6g(sch_1):m_b_cpu1_sb_dq(4)';
NODE_NAME     U26 CF63
 '@T6G_MB_LIB.T6G(SCH_1):PAGE38_I159@PURE_QUANTA.GENOA_SP5(CHIPS)':
 'MBB_DATA4': CDS_PINID='MBB_DATA4';
NODE_NAME     J26 107
 '@T6G_MB_LIB.T6G(SCH_1):PAGE98_I22@PURE_QUANTA.SCONN288_DDR506112002KQ(CHIPS)':
 'DQ4_B': CDS_PINID='DQ4_B';
NET_NAME
'M_B_CPU1_SB_DQ<5>'
 '@T6G_MB_LIB.T6G(SCH_1):M_B_CPU1_SB_DQ'<5>:
 C_SIGNAL='@t6g_mb_lib.t6g(sch_1):m_b_cpu1_sb_dq(5)';
NODE_NAME     U26 CG62
 '@T6G_MB_LIB.T6G(SCH_1):PAGE38_I159@PURE_QUANTA.GENOA_SP5(CHIPS)':
 'MBB_DATA5': CDS_PINID='MBB_DATA5';
NODE_NAME     J26 109
 '@T6G_MB_LIB.T6G(SCH_1):PAGE98_I22@PURE_QUANTA.SCONN288_DDR506112002KQ(CHIPS)':
 'DQ5_B': CDS_PINID='DQ5_B';
NET_NAME
'M_B_CPU1_SB_DQ<6>'
 '@T6G_MB_LIB.T6G(SCH_1):M_B_CPU1_SB_DQ'<6>:
 C_SIGNAL='@t6g_mb_lib.t6g(sch_1):m_b_cpu1_sb_dq(6)';
NODE_NAME     U26 CG64
 '@T6G_MB_LIB.T6G(SCH_1):PAGE38_I159@PURE_QUANTA.GENOA_SP5(CHIPS)':
 'MBB_DATA6': CDS_PINID='MBB_DATA6';
NODE_NAME     J26 252
 '@T6G_MB_LIB.T6G(SCH_1):PAGE98_I22@PURE_QUANTA.SCONN288_DDR506112002KQ(CHIPS)':
 'DQ6_B': CDS_PINID='DQ6_B';
NET_NAME
'M_B_CPU1_SB_DQ<7>'
 '@T6G_MB_LIB.T6G(SCH_1):M_B_CPU1_SB_DQ'<7>:
 C_SIGNAL='@t6g_mb_lib.t6g(sch_1):m_b_cpu1_sb_dq(7)';
NODE_NAME     U26 CH62
 '@T6G_MB_LIB.T6G(SCH_1):PAGE38_I159@PURE_QUANTA.GENOA_SP5(CHIPS)':
 'MBB_DATA7': CDS_PINID='MBB_DATA7';
NODE_NAME     J26 254
 '@T6G_MB_LIB.T6G(SCH_1):PAGE98_I22@PURE_QUANTA.SCONN288_DDR506112002KQ(CHIPS)':
 'DQ7_B': CDS_PINID='DQ7_B';
NET_NAME
'M_B_CPU1_SB_DQ<8>'
 '@T6G_MB_LIB.T6G(SCH_1):M_B_CPU1_SB_DQ'<8>:
 C_SIGNAL='@t6g_mb_lib.t6g(sch_1):m_b_cpu1_sb_dq(8)';
NODE_NAME     U26 CH63
 '@T6G_MB_LIB.T6G(SCH_1):PAGE38_I159@PURE_QUANTA.GENOA_SP5(CHIPS)':
 'MBB_DATA8': CDS_PINID='MBB_DATA8';
NODE_NAME     J26 111
 '@T6G_MB_LIB.T6G(SCH_1):PAGE98_I22@PURE_QUANTA.SCONN288_DDR506112002KQ(CHIPS)':
 'DQ8_B': CDS_PINID='DQ8_B';
NET_NAME
'M_B_CPU1_SB_DQ<9>'
 '@T6G_MB_LIB.T6G(SCH_1):M_B_CPU1_SB_DQ'<9>:
 C_SIGNAL='@t6g_mb_lib.t6g(sch_1):m_b_cpu1_sb_dq(9)';
NODE_NAME     U26 CJ62
 '@T6G_MB_LIB.T6G(SCH_1):PAGE38_I159@PURE_QUANTA.GENOA_SP5(CHIPS)':
 'MBB_DATA9': CDS_PINID='MBB_DATA9';
NODE_NAME     J26 113
 '@T6G_MB_LIB.T6G(SCH_1):PAGE98_I22@PURE_QUANTA.SCONN288_DDR506112002KQ(CHIPS)':
 'DQ9_B': CDS_PINID='DQ9_B';
NET_NAME
'M_B_CPU1_SB_DQS_DN<0>'
 '@T6G_MB_LIB.T6G(SCH_1):M_B_CPU1_SB_DQS_DN'<0>:
 C_SIGNAL='@t6g_mb_lib.t6g(sch_1):m_b_cpu1_sb_dqs_dn(0)';
NODE_NAME     U26 CE64
 '@T6G_MB_LIB.T6G(SCH_1):PAGE38_I159@PURE_QUANTA.GENOA_SP5(CHIPS)':
 'MBB_DQS_L0': CDS_PINID='MBB_DQS_L0';
NODE_NAME     J26 105
 '@T6G_MB_LIB.T6G(SCH_1):PAGE98_I236@PURE_QUANTA.SCONN288_DDR506112002KQ(CHIPS)':
 'DQS0_B_C': CDS_PINID='DQS0_B_C';
NET_NAME
'M_B_CPU1_SB_DQS_DN<1>'
 '@T6G_MB_LIB.T6G(SCH_1):M_B_CPU1_SB_DQS_DN'<1>:
 C_SIGNAL='@t6g_mb_lib.t6g(sch_1):m_b_cpu1_sb_dqs_dn(1)';
NODE_NAME     U26 CL64
 '@T6G_MB_LIB.T6G(SCH_1):PAGE38_I159@PURE_QUANTA.GENOA_SP5(CHIPS)':
 'MBB_DQS_L1': CDS_PINID='MBB_DQS_L1';
NODE_NAME     J26 116
 '@T6G_MB_LIB.T6G(SCH_1):PAGE98_I236@PURE_QUANTA.SCONN288_DDR506112002KQ(CHIPS)':
 'DQS1_B_C': CDS_PINID='DQS1_B_C';
NET_NAME
'M_B_CPU1_SB_DQS_DN<2>'
 '@T6G_MB_LIB.T6G(SCH_1):M_B_CPU1_SB_DQS_DN'<2>:
 C_SIGNAL='@t6g_mb_lib.t6g(sch_1):m_b_cpu1_sb_dqs_dn(2)';
NODE_NAME     U26 CU64
 '@T6G_MB_LIB.T6G(SCH_1):PAGE38_I159@PURE_QUANTA.GENOA_SP5(CHIPS)':
 'MBB_DQS_L2': CDS_PINID='MBB_DQS_L2';
NODE_NAME     J26 127
 '@T6G_MB_LIB.T6G(SCH_1):PAGE98_I236@PURE_QUANTA.SCONN288_DDR506112002KQ(CHIPS)':
 'DQS2_B_C': CDS_PINID='DQS2_B_C';
NET_NAME
'M_B_CPU1_SB_DQS_DN<3>'
 '@T6G_MB_LIB.T6G(SCH_1):M_B_CPU1_SB_DQS_DN'<3>:
 C_SIGNAL='@t6g_mb_lib.t6g(sch_1):m_b_cpu1_sb_dqs_dn(3)';
NODE_NAME     U26 DC64
 '@T6G_MB_LIB.T6G(SCH_1):PAGE38_I159@PURE_QUANTA.GENOA_SP5(CHIPS)':
 'MBB_DQS_L3': CDS_PINID='MBB_DQS_L3';
NODE_NAME     J26 138
 '@T6G_MB_LIB.T6G(SCH_1):PAGE98_I236@PURE_QUANTA.SCONN288_DDR506112002KQ(CHIPS)':
 'DQS3_B_C': CDS_PINID='DQS3_B_C';
NET_NAME
'M_B_CPU1_SB_DQS_DN<4>'
 '@T6G_MB_LIB.T6G(SCH_1):M_B_CPU1_SB_DQS_DN'<4>:
 C_SIGNAL='@t6g_mb_lib.t6g(sch_1):m_b_cpu1_sb_dqs_dn(4)';
NODE_NAME     U26 BW62
 '@T6G_MB_LIB.T6G(SCH_1):PAGE38_I159@PURE_QUANTA.GENOA_SP5(CHIPS)':
 'MBB_DQS_L4': CDS_PINID='MBB_DQS_L4';
NODE_NAME     J26 238
 '@T6G_MB_LIB.T6G(SCH_1):PAGE98_I236@PURE_QUANTA.SCONN288_DDR506112002KQ(CHIPS)':
 'DQS4_B_C': CDS_PINID='DQS4_B_C';
NET_NAME
'M_B_CPU1_SB_DQS_DN<5>'
 '@T6G_MB_LIB.T6G(SCH_1):M_B_CPU1_SB_DQS_DN'<5>:
 C_SIGNAL='@t6g_mb_lib.t6g(sch_1):m_b_cpu1_sb_dqs_dn(5)';
NODE_NAME     U26 CE62
 '@T6G_MB_LIB.T6G(SCH_1):PAGE38_I159@PURE_QUANTA.GENOA_SP5(CHIPS)':
 'MBB_DQS_L5': CDS_PINID='MBB_DQS_L5';
NODE_NAME     J26 249
 '@T6G_MB_LIB.T6G(SCH_1):PAGE98_I236@PURE_QUANTA.SCONN288_DDR506112002KQ(CHIPS)':
 'DQS5_B_C||TDQS5_B_C': CDS_PINID='\dqs5_b_c||tdqs5_b_c\';
NET_NAME
'M_B_CPU1_SB_DQS_DN<6>'
 '@T6G_MB_LIB.T6G(SCH_1):M_B_CPU1_SB_DQS_DN'<6>:
 C_SIGNAL='@t6g_mb_lib.t6g(sch_1):m_b_cpu1_sb_dqs_dn(6)';
NODE_NAME     U26 CL62
 '@T6G_MB_LIB.T6G(SCH_1):PAGE38_I159@PURE_QUANTA.GENOA_SP5(CHIPS)':
 'MBB_DQS_L6': CDS_PINID='MBB_DQS_L6';
NODE_NAME     J26 260
 '@T6G_MB_LIB.T6G(SCH_1):PAGE98_I236@PURE_QUANTA.SCONN288_DDR506112002KQ(CHIPS)':
 'DQS6_B_C||TDQS6_B_C': CDS_PINID='\dqs6_b_c||tdqs6_b_c\';
NET_NAME
'M_B_CPU1_SB_DQS_DN<7>'
 '@T6G_MB_LIB.T6G(SCH_1):M_B_CPU1_SB_DQS_DN'<7>:
 C_SIGNAL='@t6g_mb_lib.t6g(sch_1):m_b_cpu1_sb_dqs_dn(7)';
NODE_NAME     U26 CU62
 '@T6G_MB_LIB.T6G(SCH_1):PAGE38_I159@PURE_QUANTA.GENOA_SP5(CHIPS)':
 'MBB_DQS_L7': CDS_PINID='MBB_DQS_L7';
NODE_NAME     J26 271
 '@T6G_MB_LIB.T6G(SCH_1):PAGE98_I236@PURE_QUANTA.SCONN288_DDR506112002KQ(CHIPS)':
 'DQS7_B_C||TDQS7_B_C': CDS_PINID='\dqs7_b_c||tdqs7_b_c\';
NET_NAME
'M_B_CPU1_SB_DQS_DN<8>'
 '@T6G_MB_LIB.T6G(SCH_1):M_B_CPU1_SB_DQS_DN'<8>:
 C_SIGNAL='@t6g_mb_lib.t6g(sch_1):m_b_cpu1_sb_dqs_dn(8)';
NODE_NAME     U26 DC62
 '@T6G_MB_LIB.T6G(SCH_1):PAGE38_I159@PURE_QUANTA.GENOA_SP5(CHIPS)':
 'MBB_DQS_L8': CDS_PINID='MBB_DQS_L8';
NODE_NAME     J26 282
 '@T6G_MB_LIB.T6G(SCH_1):PAGE98_I236@PURE_QUANTA.SCONN288_DDR506112002KQ(CHIPS)':
 'DQS8_B_C||TDQS8_B_C': CDS_PINID='\dqs8_b_c||tdqs8_b_c\';
NET_NAME
'M_B_CPU1_SB_DQS_DN<9>'
 '@T6G_MB_LIB.T6G(SCH_1):M_B_CPU1_SB_DQS_DN'<9>:
 C_SIGNAL='@t6g_mb_lib.t6g(sch_1):m_b_cpu1_sb_dqs_dn(9)';
NODE_NAME     U26 BW64
 '@T6G_MB_LIB.T6G(SCH_1):PAGE38_I159@PURE_QUANTA.GENOA_SP5(CHIPS)':
 'MBB_DQS_L9': CDS_PINID='MBB_DQS_L9';
NODE_NAME     J26 94
 '@T6G_MB_LIB.T6G(SCH_1):PAGE98_I236@PURE_QUANTA.SCONN288_DDR506112002KQ(CHIPS)':
 'DQS9_B_C||TDQS9_B_C': CDS_PINID='\dqs9_b_c||tdqs9_b_c\';
NET_NAME
'M_B_CPU1_SB_DQS_DP<0>'
 '@T6G_MB_LIB.T6G(SCH_1):M_B_CPU1_SB_DQS_DP'<0>:
 C_SIGNAL='@t6g_mb_lib.t6g(sch_1):m_b_cpu1_sb_dqs_dp(0)';
NODE_NAME     U26 CD63
 '@T6G_MB_LIB.T6G(SCH_1):PAGE38_I159@PURE_QUANTA.GENOA_SP5(CHIPS)':
 'MBB_DQS_H0': CDS_PINID='MBB_DQS_H0';
NODE_NAME     J26 104
 '@T6G_MB_LIB.T6G(SCH_1):PAGE98_I236@PURE_QUANTA.SCONN288_DDR506112002KQ(CHIPS)':
 'DQS0_B_T': CDS_PINID='DQS0_B_T';
NET_NAME
'M_B_CPU1_SB_DQS_DP<1>'
 '@T6G_MB_LIB.T6G(SCH_1):M_B_CPU1_SB_DQS_DP'<1>:
 C_SIGNAL='@t6g_mb_lib.t6g(sch_1):m_b_cpu1_sb_dqs_dp(1)';
NODE_NAME     U26 CK63
 '@T6G_MB_LIB.T6G(SCH_1):PAGE38_I159@PURE_QUANTA.GENOA_SP5(CHIPS)':
 'MBB_DQS_H1': CDS_PINID='MBB_DQS_H1';
NODE_NAME     J26 115
 '@T6G_MB_LIB.T6G(SCH_1):PAGE98_I236@PURE_QUANTA.SCONN288_DDR506112002KQ(CHIPS)':
 'DQS1_B_T': CDS_PINID='DQS1_B_T';
NET_NAME
'M_B_CPU1_SB_DQS_DP<2>'
 '@T6G_MB_LIB.T6G(SCH_1):M_B_CPU1_SB_DQS_DP'<2>:
 C_SIGNAL='@t6g_mb_lib.t6g(sch_1):m_b_cpu1_sb_dqs_dp(2)';
NODE_NAME     U26 CT63
 '@T6G_MB_LIB.T6G(SCH_1):PAGE38_I159@PURE_QUANTA.GENOA_SP5(CHIPS)':
 'MBB_DQS_H2': CDS_PINID='MBB_DQS_H2';
NODE_NAME     J26 126
 '@T6G_MB_LIB.T6G(SCH_1):PAGE98_I236@PURE_QUANTA.SCONN288_DDR506112002KQ(CHIPS)':
 'DQS2_B_T': CDS_PINID='DQS2_B_T';
NET_NAME
'M_B_CPU1_SB_DQS_DP<3>'
 '@T6G_MB_LIB.T6G(SCH_1):M_B_CPU1_SB_DQS_DP'<3>:
 C_SIGNAL='@t6g_mb_lib.t6g(sch_1):m_b_cpu1_sb_dqs_dp(3)';
NODE_NAME     U26 DB63
 '@T6G_MB_LIB.T6G(SCH_1):PAGE38_I159@PURE_QUANTA.GENOA_SP5(CHIPS)':
 'MBB_DQS_H3': CDS_PINID='MBB_DQS_H3';
NODE_NAME     J26 137
 '@T6G_MB_LIB.T6G(SCH_1):PAGE98_I236@PURE_QUANTA.SCONN288_DDR506112002KQ(CHIPS)':
 'DQS3_B_T': CDS_PINID='DQS3_B_T';
NET_NAME
'M_B_CPU1_SB_DQS_DP<4>'
 '@T6G_MB_LIB.T6G(SCH_1):M_B_CPU1_SB_DQS_DP'<4>:
 C_SIGNAL='@t6g_mb_lib.t6g(sch_1):m_b_cpu1_sb_dqs_dp(4)';
NODE_NAME     U26 BY62
 '@T6G_MB_LIB.T6G(SCH_1):PAGE38_I159@PURE_QUANTA.GENOA_SP5(CHIPS)':
 'MBB_DQS_H4': CDS_PINID='MBB_DQS_H4';
NODE_NAME     J26 239
 '@T6G_MB_LIB.T6G(SCH_1):PAGE98_I236@PURE_QUANTA.SCONN288_DDR506112002KQ(CHIPS)':
 'DQS4_B_T': CDS_PINID='DQS4_B_T';
NET_NAME
'M_B_CPU1_SB_DQS_DP<5>'
 '@T6G_MB_LIB.T6G(SCH_1):M_B_CPU1_SB_DQS_DP'<5>:
 C_SIGNAL='@t6g_mb_lib.t6g(sch_1):m_b_cpu1_sb_dqs_dp(5)';
NODE_NAME     U26 CF62
 '@T6G_MB_LIB.T6G(SCH_1):PAGE38_I159@PURE_QUANTA.GENOA_SP5(CHIPS)':
 'MBB_DQS_H5': CDS_PINID='MBB_DQS_H5';
NODE_NAME     J26 250
 '@T6G_MB_LIB.T6G(SCH_1):PAGE98_I236@PURE_QUANTA.SCONN288_DDR506112002KQ(CHIPS)':
 'DQS5_B_T||TDQS5_B_T': CDS_PINID='\dqs5_b_t||tdqs5_b_t\';
NET_NAME
'M_B_CPU1_SB_DQS_DP<6>'
 '@T6G_MB_LIB.T6G(SCH_1):M_B_CPU1_SB_DQS_DP'<6>:
 C_SIGNAL='@t6g_mb_lib.t6g(sch_1):m_b_cpu1_sb_dqs_dp(6)';
NODE_NAME     U26 CM62
 '@T6G_MB_LIB.T6G(SCH_1):PAGE38_I159@PURE_QUANTA.GENOA_SP5(CHIPS)':
 'MBB_DQS_H6': CDS_PINID='MBB_DQS_H6';
NODE_NAME     J26 261
 '@T6G_MB_LIB.T6G(SCH_1):PAGE98_I236@PURE_QUANTA.SCONN288_DDR506112002KQ(CHIPS)':
 'DQS6_B_T||TDQS6_B_T': CDS_PINID='\dqs6_b_t||tdqs6_b_t\';
NET_NAME
'M_B_CPU1_SB_DQS_DP<7>'
 '@T6G_MB_LIB.T6G(SCH_1):M_B_CPU1_SB_DQS_DP'<7>:
 C_SIGNAL='@t6g_mb_lib.t6g(sch_1):m_b_cpu1_sb_dqs_dp(7)';
NODE_NAME     U26 CV62
 '@T6G_MB_LIB.T6G(SCH_1):PAGE38_I159@PURE_QUANTA.GENOA_SP5(CHIPS)':
 'MBB_DQS_H7': CDS_PINID='MBB_DQS_H7';
NODE_NAME     J26 272
 '@T6G_MB_LIB.T6G(SCH_1):PAGE98_I236@PURE_QUANTA.SCONN288_DDR506112002KQ(CHIPS)':
 'DQS7_B_T||TDQS7_B_T': CDS_PINID='\dqs7_b_t||tdqs7_b_t\';
NET_NAME
'M_B_CPU1_SB_DQS_DP<8>'
 '@T6G_MB_LIB.T6G(SCH_1):M_B_CPU1_SB_DQS_DP'<8>:
 C_SIGNAL='@t6g_mb_lib.t6g(sch_1):m_b_cpu1_sb_dqs_dp(8)';
NODE_NAME     U26 DD62
 '@T6G_MB_LIB.T6G(SCH_1):PAGE38_I159@PURE_QUANTA.GENOA_SP5(CHIPS)':
 'MBB_DQS_H8': CDS_PINID='MBB_DQS_H8';
NODE_NAME     J26 283
 '@T6G_MB_LIB.T6G(SCH_1):PAGE98_I236@PURE_QUANTA.SCONN288_DDR506112002KQ(CHIPS)':
 'DQS8_B_T||TDQS8_B_T': CDS_PINID='\dqs8_b_t||tdqs8_b_t\';
NET_NAME
'M_B_CPU1_SB_DQS_DP<9>'
 '@T6G_MB_LIB.T6G(SCH_1):M_B_CPU1_SB_DQS_DP'<9>:
 C_SIGNAL='@t6g_mb_lib.t6g(sch_1):m_b_cpu1_sb_dqs_dp(9)';
NODE_NAME     U26 BV63
 '@T6G_MB_LIB.T6G(SCH_1):PAGE38_I159@PURE_QUANTA.GENOA_SP5(CHIPS)':
 'MBB_DQS_H9': CDS_PINID='MBB_DQS_H9';
NODE_NAME     J26 93
 '@T6G_MB_LIB.T6G(SCH_1):PAGE98_I236@PURE_QUANTA.SCONN288_DDR506112002KQ(CHIPS)':
 'DQS9_B_T||TDQS9_B_T||DBI4_B_N': CDS_PINID='\dqs9_b_t||tdqs9_b_t||dbi4_b_n\';
NET_NAME
'M_B_CPU1_SB_PAR'
 '@T6G_MB_LIB.T6G(SCH_1):M_B_CPU1_SB_PAR':
 C_SIGNAL='@t6g_mb_lib.t6g(sch_1):m_b_cpu1_sb_par';
NODE_NAME     U26 BL64
 '@T6G_MB_LIB.T6G(SCH_1):PAGE38_I159@PURE_QUANTA.GENOA_SP5(CHIPS)':
 'MBB_PAR': CDS_PINID='MBB_PAR';
NODE_NAME     J26 227
 '@T6G_MB_LIB.T6G(SCH_1):PAGE98_I22@PURE_QUANTA.SCONN288_DDR506112002KQ(CHIPS)':
 'PAR_B': CDS_PINID='PAR_B';
NET_NAME
'M_B_CPU1_SB_RSP<0>'
 '@T6G_MB_LIB.T6G(SCH_1):M_B_CPU1_SB_RSP'<0>:
 C_SIGNAL='@t6g_mb_lib.t6g(sch_1):m_b_cpu1_sb_rsp(0)';
NODE_NAME     U26 BP63
 '@T6G_MB_LIB.T6G(SCH_1):PAGE38_I159@PURE_QUANTA.GENOA_SP5(CHIPS)':
 'MBB0_RSP_L': CDS_PINID='MBB0_RSP_L';
NODE_NAME     J26 87
 '@T6G_MB_LIB.T6G(SCH_1):PAGE98_I22@PURE_QUANTA.SCONN288_DDR506112002KQ(CHIPS)':
 'LBS||RSP_B_N': CDS_PINID='\lbs||rsp_b_n\';
NET_NAME
'M_C_CPU0_ALERT_N'
 '@T6G_MB_LIB.T6G(SCH_1):M_C_CPU0_ALERT_N':
 C_SIGNAL='@t6g_mb_lib.t6g(sch_1):m_c_cpu0_alert_n';
NODE_NAME     R377 1
 '@T6G_MB_LIB.T6G(SCH_1):PAGE12_I314@PURE_QUANTA.Q_RES(CHIPS)':
 'A': CDS_PINID='A';
NODE_NAME     J17 62
 '@T6G_MB_LIB.T6G(SCH_1):PAGE87_I350@PURE_QUANTA.SCONN288_DDR506112002KQ(CHIPS)':
 'ALERT_N': CDS_PINID='ALERT_N';
NET_NAME
'M_C_CPU0_ALERT_R_N'
 '@T6G_MB_LIB.T6G(SCH_1):M_C_CPU0_ALERT_R_N':
 C_SIGNAL='@t6g_mb_lib.t6g(sch_1):m_c_cpu0_alert_r_n';
NODE_NAME     U25 AT55
 '@T6G_MB_LIB.T6G(SCH_1):PAGE12_I159@PURE_QUANTA.GENOA_SP5(CHIPS)':
 'MC_ALERT_L': CDS_PINID='MC_ALERT_L';
NODE_NAME     R377 2
 '@T6G_MB_LIB.T6G(SCH_1):PAGE12_I314@PURE_QUANTA.Q_RES(CHIPS)':
 'B': CDS_PINID='B';
NET_NAME
'M_C_CPU0_CLK_DN<0>'
 '@T6G_MB_LIB.T6G(SCH_1):M_C_CPU0_CLK_DN'<0>:
 C_SIGNAL='@t6g_mb_lib.t6g(sch_1):m_c_cpu0_clk_dn(0)';
NODE_NAME     U25 BD56
 '@T6G_MB_LIB.T6G(SCH_1):PAGE12_I159@PURE_QUANTA.GENOA_SP5(CHIPS)':
 'MC0_CLK_L': CDS_PINID='MC0_CLK_L';
NODE_NAME     J17 218
 '@T6G_MB_LIB.T6G(SCH_1):PAGE87_I350@PURE_QUANTA.SCONN288_DDR506112002KQ(CHIPS)':
 'CK_C': CDS_PINID='CK_C';
NET_NAME
'M_C_CPU0_CLK_DP<0>'
 '@T6G_MB_LIB.T6G(SCH_1):M_C_CPU0_CLK_DP'<0>:
 C_SIGNAL='@t6g_mb_lib.t6g(sch_1):m_c_cpu0_clk_dp(0)';
NODE_NAME     U25 BC57
 '@T6G_MB_LIB.T6G(SCH_1):PAGE12_I159@PURE_QUANTA.GENOA_SP5(CHIPS)':
 'MC0_CLK_H': CDS_PINID='MC0_CLK_H';
NODE_NAME     J17 217
 '@T6G_MB_LIB.T6G(SCH_1):PAGE87_I350@PURE_QUANTA.SCONN288_DDR506112002KQ(CHIPS)':
 'CK_T': CDS_PINID='CK_T';
NET_NAME
'M_C_CPU0_RESET_N'
 '@T6G_MB_LIB.T6G(SCH_1):M_C_CPU0_RESET_N':
 C_SIGNAL='@t6g_mb_lib.t6g(sch_1):m_c_cpu0_reset_n';
NODE_NAME     U25 AU55
 '@T6G_MB_LIB.T6G(SCH_1):PAGE12_I159@PURE_QUANTA.GENOA_SP5(CHIPS)':
 'MC_RESET_L': CDS_PINID='MC_RESET_L';
NODE_NAME     J17 207
 '@T6G_MB_LIB.T6G(SCH_1):PAGE87_I350@PURE_QUANTA.SCONN288_DDR506112002KQ(CHIPS)':
 'RESET_N': CDS_PINID='RESET_N';
NET_NAME
'M_C_CPU0_SA_CA<0>'
 '@T6G_MB_LIB.T6G(SCH_1):M_C_CPU0_SA_CA'<0>:
 C_SIGNAL='@t6g_mb_lib.t6g(sch_1):m_c_cpu0_sa_ca(0)';
NODE_NAME     U25 AW57
 '@T6G_MB_LIB.T6G(SCH_1):PAGE12_I159@PURE_QUANTA.GENOA_SP5(CHIPS)':
 'MCA_CA0': CDS_PINID='MCA_CA0';
NODE_NAME     J17 66
 '@T6G_MB_LIB.T6G(SCH_1):PAGE87_I350@PURE_QUANTA.SCONN288_DDR506112002KQ(CHIPS)':
 'CA0_A': CDS_PINID='CA0_A';
NET_NAME
'M_C_CPU0_SA_CA<1>'
 '@T6G_MB_LIB.T6G(SCH_1):M_C_CPU0_SA_CA'<1>:
 C_SIGNAL='@t6g_mb_lib.t6g(sch_1):m_c_cpu0_sa_ca(1)';
NODE_NAME     U25 AY56
 '@T6G_MB_LIB.T6G(SCH_1):PAGE12_I159@PURE_QUANTA.GENOA_SP5(CHIPS)':
 'MCA_CA1': CDS_PINID='MCA_CA1';
NODE_NAME     J17 211
 '@T6G_MB_LIB.T6G(SCH_1):PAGE87_I350@PURE_QUANTA.SCONN288_DDR506112002KQ(CHIPS)':
 'CA1_A': CDS_PINID='CA1_A';
NET_NAME
'M_C_CPU0_SA_CA<2>'
 '@T6G_MB_LIB.T6G(SCH_1):M_C_CPU0_SA_CA'<2>:
 C_SIGNAL='@t6g_mb_lib.t6g(sch_1):m_c_cpu0_sa_ca(2)';
NODE_NAME     U25 AY55
 '@T6G_MB_LIB.T6G(SCH_1):PAGE12_I159@PURE_QUANTA.GENOA_SP5(CHIPS)':
 'MCA_CA2': CDS_PINID='MCA_CA2';
NODE_NAME     J17 68
 '@T6G_MB_LIB.T6G(SCH_1):PAGE87_I350@PURE_QUANTA.SCONN288_DDR506112002KQ(CHIPS)':
 'CA2_A': CDS_PINID='CA2_A';
NET_NAME
'M_C_CPU0_SA_CA<3>'
 '@T6G_MB_LIB.T6G(SCH_1):M_C_CPU0_SA_CA'<3>:
 C_SIGNAL='@t6g_mb_lib.t6g(sch_1):m_c_cpu0_sa_ca(3)';
NODE_NAME     U25 BA55
 '@T6G_MB_LIB.T6G(SCH_1):PAGE12_I159@PURE_QUANTA.GENOA_SP5(CHIPS)':
 'MCA_CA3': CDS_PINID='MCA_CA3';
NODE_NAME     J17 213
 '@T6G_MB_LIB.T6G(SCH_1):PAGE87_I350@PURE_QUANTA.SCONN288_DDR506112002KQ(CHIPS)':
 'CA3_A': CDS_PINID='CA3_A';
NET_NAME
'M_C_CPU0_SA_CA<4>'
 '@T6G_MB_LIB.T6G(SCH_1):M_C_CPU0_SA_CA'<4>:
 C_SIGNAL='@t6g_mb_lib.t6g(sch_1):m_c_cpu0_sa_ca(4)';
NODE_NAME     U25 BA57
 '@T6G_MB_LIB.T6G(SCH_1):PAGE12_I159@PURE_QUANTA.GENOA_SP5(CHIPS)':
 'MCA_CA4': CDS_PINID='MCA_CA4';
NODE_NAME     J17 70
 '@T6G_MB_LIB.T6G(SCH_1):PAGE87_I350@PURE_QUANTA.SCONN288_DDR506112002KQ(CHIPS)':
 'CA4_A': CDS_PINID='CA4_A';
NET_NAME
'M_C_CPU0_SA_CA<5>'
 '@T6G_MB_LIB.T6G(SCH_1):M_C_CPU0_SA_CA'<5>:
 C_SIGNAL='@t6g_mb_lib.t6g(sch_1):m_c_cpu0_sa_ca(5)';
NODE_NAME     U25 BB56
 '@T6G_MB_LIB.T6G(SCH_1):PAGE12_I159@PURE_QUANTA.GENOA_SP5(CHIPS)':
 'MCA_CA5': CDS_PINID='MCA_CA5';
NODE_NAME     J17 215
 '@T6G_MB_LIB.T6G(SCH_1):PAGE87_I350@PURE_QUANTA.SCONN288_DDR506112002KQ(CHIPS)':
 'CA5_A': CDS_PINID='CA5_A';
NET_NAME
'M_C_CPU0_SA_CA<6>'
 '@T6G_MB_LIB.T6G(SCH_1):M_C_CPU0_SA_CA'<6>:
 C_SIGNAL='@t6g_mb_lib.t6g(sch_1):m_c_cpu0_sa_ca(6)';
NODE_NAME     U25 BB55
 '@T6G_MB_LIB.T6G(SCH_1):PAGE12_I159@PURE_QUANTA.GENOA_SP5(CHIPS)':
 'MCA_CA6': CDS_PINID='MCA_CA6';
NODE_NAME     J17 72
 '@T6G_MB_LIB.T6G(SCH_1):PAGE87_I350@PURE_QUANTA.SCONN288_DDR506112002KQ(CHIPS)':
 'CA6_A': CDS_PINID='CA6_A';
NET_NAME
'M_C_CPU0_SA_CB<0>'
 '@T6G_MB_LIB.T6G(SCH_1):M_C_CPU0_SA_CB'<0>:
 C_SIGNAL='@t6g_mb_lib.t6g(sch_1):m_c_cpu0_sa_cb(0)';
NODE_NAME     U25 AJ57
 '@T6G_MB_LIB.T6G(SCH_1):PAGE12_I159@PURE_QUANTA.GENOA_SP5(CHIPS)':
 'MCA_CHECK0': CDS_PINID='MCA_CHECK0';
NODE_NAME     J17 51
 '@T6G_MB_LIB.T6G(SCH_1):PAGE87_I350@PURE_QUANTA.SCONN288_DDR506112002KQ(CHIPS)':
 'CB0_A': CDS_PINID='CB0_A';
NET_NAME
'M_C_CPU0_SA_CB<1>'
 '@T6G_MB_LIB.T6G(SCH_1):M_C_CPU0_SA_CB'<1>:
 C_SIGNAL='@t6g_mb_lib.t6g(sch_1):m_c_cpu0_sa_cb(1)';
NODE_NAME     U25 AK55
 '@T6G_MB_LIB.T6G(SCH_1):PAGE12_I159@PURE_QUANTA.GENOA_SP5(CHIPS)':
 'MCA_CHECK1': CDS_PINID='MCA_CHECK1';
NODE_NAME     J17 53
 '@T6G_MB_LIB.T6G(SCH_1):PAGE87_I350@PURE_QUANTA.SCONN288_DDR506112002KQ(CHIPS)':
 'CB1_A': CDS_PINID='CB1_A';
NET_NAME
'M_C_CPU0_SA_CB<2>'
 '@T6G_MB_LIB.T6G(SCH_1):M_C_CPU0_SA_CB'<2>:
 C_SIGNAL='@t6g_mb_lib.t6g(sch_1):m_c_cpu0_sa_cb(2)';
NODE_NAME     U25 AK56
 '@T6G_MB_LIB.T6G(SCH_1):PAGE12_I159@PURE_QUANTA.GENOA_SP5(CHIPS)':
 'MCA_CHECK2': CDS_PINID='MCA_CHECK2';
NODE_NAME     J17 196
 '@T6G_MB_LIB.T6G(SCH_1):PAGE87_I350@PURE_QUANTA.SCONN288_DDR506112002KQ(CHIPS)':
 'CB2_A': CDS_PINID='CB2_A';
NET_NAME
'M_C_CPU0_SA_CB<3>'
 '@T6G_MB_LIB.T6G(SCH_1):M_C_CPU0_SA_CB'<3>:
 C_SIGNAL='@t6g_mb_lib.t6g(sch_1):m_c_cpu0_sa_cb(3)';
NODE_NAME     U25 AL55
 '@T6G_MB_LIB.T6G(SCH_1):PAGE12_I159@PURE_QUANTA.GENOA_SP5(CHIPS)':
 'MCA_CHECK3': CDS_PINID='MCA_CHECK3';
NODE_NAME     J17 198
 '@T6G_MB_LIB.T6G(SCH_1):PAGE87_I350@PURE_QUANTA.SCONN288_DDR506112002KQ(CHIPS)':
 'CB3_A': CDS_PINID='CB3_A';
NET_NAME
'M_C_CPU0_SA_CB<4>'
 '@T6G_MB_LIB.T6G(SCH_1):M_C_CPU0_SA_CB'<4>:
 C_SIGNAL='@t6g_mb_lib.t6g(sch_1):m_c_cpu0_sa_cb(4)';
NODE_NAME     U25 AN57
 '@T6G_MB_LIB.T6G(SCH_1):PAGE12_I159@PURE_QUANTA.GENOA_SP5(CHIPS)':
 'MCA_CHECK4': CDS_PINID='MCA_CHECK4';
NODE_NAME     J17 58
 '@T6G_MB_LIB.T6G(SCH_1):PAGE87_I350@PURE_QUANTA.SCONN288_DDR506112002KQ(CHIPS)':
 'CB4_A': CDS_PINID='CB4_A';
NET_NAME
'M_C_CPU0_SA_CB<5>'
 '@T6G_MB_LIB.T6G(SCH_1):M_C_CPU0_SA_CB'<5>:
 C_SIGNAL='@t6g_mb_lib.t6g(sch_1):m_c_cpu0_sa_cb(5)';
NODE_NAME     U25 AP55
 '@T6G_MB_LIB.T6G(SCH_1):PAGE12_I159@PURE_QUANTA.GENOA_SP5(CHIPS)':
 'MCA_CHECK5': CDS_PINID='MCA_CHECK5';
NODE_NAME     J17 60
 '@T6G_MB_LIB.T6G(SCH_1):PAGE87_I350@PURE_QUANTA.SCONN288_DDR506112002KQ(CHIPS)':
 'CB5_A': CDS_PINID='CB5_A';
NET_NAME
'M_C_CPU0_SA_CB<6>'
 '@T6G_MB_LIB.T6G(SCH_1):M_C_CPU0_SA_CB'<6>:
 C_SIGNAL='@t6g_mb_lib.t6g(sch_1):m_c_cpu0_sa_cb(6)';
NODE_NAME     U25 AP56
 '@T6G_MB_LIB.T6G(SCH_1):PAGE12_I159@PURE_QUANTA.GENOA_SP5(CHIPS)':
 'MCA_CHECK6': CDS_PINID='MCA_CHECK6';
NODE_NAME     J17 203
 '@T6G_MB_LIB.T6G(SCH_1):PAGE87_I350@PURE_QUANTA.SCONN288_DDR506112002KQ(CHIPS)':
 'CB6_A': CDS_PINID='CB6_A';
NET_NAME
'M_C_CPU0_SA_CB<7>'
 '@T6G_MB_LIB.T6G(SCH_1):M_C_CPU0_SA_CB'<7>:
 C_SIGNAL='@t6g_mb_lib.t6g(sch_1):m_c_cpu0_sa_cb(7)';
NODE_NAME     U25 AR55
 '@T6G_MB_LIB.T6G(SCH_1):PAGE12_I159@PURE_QUANTA.GENOA_SP5(CHIPS)':
 'MCA_CHECK7': CDS_PINID='MCA_CHECK7';
NODE_NAME     J17 205
 '@T6G_MB_LIB.T6G(SCH_1):PAGE87_I350@PURE_QUANTA.SCONN288_DDR506112002KQ(CHIPS)':
 'CB7_A': CDS_PINID='CB7_A';
NET_NAME
'M_C_CPU0_SA_CS_N<0>'
 '@T6G_MB_LIB.T6G(SCH_1):M_C_CPU0_SA_CS_N'<0>:
 C_SIGNAL='@t6g_mb_lib.t6g(sch_1):m_c_cpu0_sa_cs_n(0)';
NODE_NAME     U25 AV56
 '@T6G_MB_LIB.T6G(SCH_1):PAGE12_I159@PURE_QUANTA.GENOA_SP5(CHIPS)':
 'MCA0_CS_L0': CDS_PINID='MCA0_CS_L0';
NODE_NAME     J17 64
 '@T6G_MB_LIB.T6G(SCH_1):PAGE87_I350@PURE_QUANTA.SCONN288_DDR506112002KQ(CHIPS)':
 'CS0_A_N': CDS_PINID='CS0_A_N';
NET_NAME
'M_C_CPU0_SA_CS_N<1>'
 '@T6G_MB_LIB.T6G(SCH_1):M_C_CPU0_SA_CS_N'<1>:
 C_SIGNAL='@t6g_mb_lib.t6g(sch_1):m_c_cpu0_sa_cs_n(1)';
NODE_NAME     U25 AW55
 '@T6G_MB_LIB.T6G(SCH_1):PAGE12_I159@PURE_QUANTA.GENOA_SP5(CHIPS)':
 'MCA0_CS_L1': CDS_PINID='MCA0_CS_L1';
NODE_NAME     J17 209
 '@T6G_MB_LIB.T6G(SCH_1):PAGE87_I350@PURE_QUANTA.SCONN288_DDR506112002KQ(CHIPS)':
 'CS1_A_N': CDS_PINID='CS1_A_N';
NET_NAME
'M_C_CPU0_SA_DQ<0>'
 '@T6G_MB_LIB.T6G(SCH_1):M_C_CPU0_SA_DQ'<0>:
 C_SIGNAL='@t6g_mb_lib.t6g(sch_1):m_c_cpu0_sa_dq(0)';
NODE_NAME     U25 E57
 '@T6G_MB_LIB.T6G(SCH_1):PAGE12_I159@PURE_QUANTA.GENOA_SP5(CHIPS)':
 'MCA_DATA0': CDS_PINID='MCA_DATA0';
NODE_NAME     J17 7
 '@T6G_MB_LIB.T6G(SCH_1):PAGE87_I350@PURE_QUANTA.SCONN288_DDR506112002KQ(CHIPS)':
 'DQ0_A': CDS_PINID='DQ0_A';
NET_NAME
'M_C_CPU0_SA_DQ<10>'
 '@T6G_MB_LIB.T6G(SCH_1):M_C_CPU0_SA_DQ'<10>:
 C_SIGNAL='@t6g_mb_lib.t6g(sch_1):m_c_cpu0_sa_dq(10)';
NODE_NAME     U25 M56
 '@T6G_MB_LIB.T6G(SCH_1):PAGE12_I159@PURE_QUANTA.GENOA_SP5(CHIPS)':
 'MCA_DATA10': CDS_PINID='MCA_DATA10';
NODE_NAME     J17 163
 '@T6G_MB_LIB.T6G(SCH_1):PAGE87_I350@PURE_QUANTA.SCONN288_DDR506112002KQ(CHIPS)':
 'DQ10_A': CDS_PINID='DQ10_A';
NET_NAME
'M_C_CPU0_SA_DQ<11>'
 '@T6G_MB_LIB.T6G(SCH_1):M_C_CPU0_SA_DQ'<11>:
 C_SIGNAL='@t6g_mb_lib.t6g(sch_1):m_c_cpu0_sa_dq(11)';
NODE_NAME     U25 N55
 '@T6G_MB_LIB.T6G(SCH_1):PAGE12_I159@PURE_QUANTA.GENOA_SP5(CHIPS)':
 'MCA_DATA11': CDS_PINID='MCA_DATA11';
NODE_NAME     J17 165
 '@T6G_MB_LIB.T6G(SCH_1):PAGE87_I350@PURE_QUANTA.SCONN288_DDR506112002KQ(CHIPS)':
 'DQ11_A': CDS_PINID='DQ11_A';
NET_NAME
'M_C_CPU0_SA_DQ<12>'
 '@T6G_MB_LIB.T6G(SCH_1):M_C_CPU0_SA_DQ'<12>:
 C_SIGNAL='@t6g_mb_lib.t6g(sch_1):m_c_cpu0_sa_dq(12)';
NODE_NAME     U25 R57
 '@T6G_MB_LIB.T6G(SCH_1):PAGE12_I159@PURE_QUANTA.GENOA_SP5(CHIPS)':
 'MCA_DATA12': CDS_PINID='MCA_DATA12';
NODE_NAME     J17 25
 '@T6G_MB_LIB.T6G(SCH_1):PAGE87_I350@PURE_QUANTA.SCONN288_DDR506112002KQ(CHIPS)':
 'DQ12_A': CDS_PINID='DQ12_A';
NET_NAME
'M_C_CPU0_SA_DQ<13>'
 '@T6G_MB_LIB.T6G(SCH_1):M_C_CPU0_SA_DQ'<13>:
 C_SIGNAL='@t6g_mb_lib.t6g(sch_1):m_c_cpu0_sa_dq(13)';
NODE_NAME     U25 T55
 '@T6G_MB_LIB.T6G(SCH_1):PAGE12_I159@PURE_QUANTA.GENOA_SP5(CHIPS)':
 'MCA_DATA13': CDS_PINID='MCA_DATA13';
NODE_NAME     J17 27
 '@T6G_MB_LIB.T6G(SCH_1):PAGE87_I350@PURE_QUANTA.SCONN288_DDR506112002KQ(CHIPS)':
 'DQ13_A': CDS_PINID='DQ13_A';
NET_NAME
'M_C_CPU0_SA_DQ<14>'
 '@T6G_MB_LIB.T6G(SCH_1):M_C_CPU0_SA_DQ'<14>:
 C_SIGNAL='@t6g_mb_lib.t6g(sch_1):m_c_cpu0_sa_dq(14)';
NODE_NAME     U25 T56
 '@T6G_MB_LIB.T6G(SCH_1):PAGE12_I159@PURE_QUANTA.GENOA_SP5(CHIPS)':
 'MCA_DATA14': CDS_PINID='MCA_DATA14';
NODE_NAME     J17 170
 '@T6G_MB_LIB.T6G(SCH_1):PAGE87_I350@PURE_QUANTA.SCONN288_DDR506112002KQ(CHIPS)':
 'DQ14_A': CDS_PINID='DQ14_A';
NET_NAME
'M_C_CPU0_SA_DQ<15>'
 '@T6G_MB_LIB.T6G(SCH_1):M_C_CPU0_SA_DQ'<15>:
 C_SIGNAL='@t6g_mb_lib.t6g(sch_1):m_c_cpu0_sa_dq(15)';
NODE_NAME     U25 U55
 '@T6G_MB_LIB.T6G(SCH_1):PAGE12_I159@PURE_QUANTA.GENOA_SP5(CHIPS)':
 'MCA_DATA15': CDS_PINID='MCA_DATA15';
NODE_NAME     J17 172
 '@T6G_MB_LIB.T6G(SCH_1):PAGE87_I350@PURE_QUANTA.SCONN288_DDR506112002KQ(CHIPS)':
 'DQ15_A': CDS_PINID='DQ15_A';
NET_NAME
'M_C_CPU0_SA_DQ<16>'
 '@T6G_MB_LIB.T6G(SCH_1):M_C_CPU0_SA_DQ'<16>:
 C_SIGNAL='@t6g_mb_lib.t6g(sch_1):m_c_cpu0_sa_dq(16)';
NODE_NAME     U25 U57
 '@T6G_MB_LIB.T6G(SCH_1):PAGE12_I159@PURE_QUANTA.GENOA_SP5(CHIPS)':
 'MCA_DATA16': CDS_PINID='MCA_DATA16';
NODE_NAME     J17 29
 '@T6G_MB_LIB.T6G(SCH_1):PAGE87_I350@PURE_QUANTA.SCONN288_DDR506112002KQ(CHIPS)':
 'DQ16_A': CDS_PINID='DQ16_A';
NET_NAME
'M_C_CPU0_SA_DQ<17>'
 '@T6G_MB_LIB.T6G(SCH_1):M_C_CPU0_SA_DQ'<17>:
 C_SIGNAL='@t6g_mb_lib.t6g(sch_1):m_c_cpu0_sa_dq(17)';
NODE_NAME     U25 V55
 '@T6G_MB_LIB.T6G(SCH_1):PAGE12_I159@PURE_QUANTA.GENOA_SP5(CHIPS)':
 'MCA_DATA17': CDS_PINID='MCA_DATA17';
NODE_NAME     J17 31
 '@T6G_MB_LIB.T6G(SCH_1):PAGE87_I350@PURE_QUANTA.SCONN288_DDR506112002KQ(CHIPS)':
 'DQ17_A': CDS_PINID='DQ17_A';
NET_NAME
'M_C_CPU0_SA_DQ<18>'
 '@T6G_MB_LIB.T6G(SCH_1):M_C_CPU0_SA_DQ'<18>:
 C_SIGNAL='@t6g_mb_lib.t6g(sch_1):m_c_cpu0_sa_dq(18)';
NODE_NAME     U25 V56
 '@T6G_MB_LIB.T6G(SCH_1):PAGE12_I159@PURE_QUANTA.GENOA_SP5(CHIPS)':
 'MCA_DATA18': CDS_PINID='MCA_DATA18';
NODE_NAME     J17 174
 '@T6G_MB_LIB.T6G(SCH_1):PAGE87_I350@PURE_QUANTA.SCONN288_DDR506112002KQ(CHIPS)':
 'DQ18_A': CDS_PINID='DQ18_A';
NET_NAME
'M_C_CPU0_SA_DQ<19>'
 '@T6G_MB_LIB.T6G(SCH_1):M_C_CPU0_SA_DQ'<19>:
 C_SIGNAL='@t6g_mb_lib.t6g(sch_1):m_c_cpu0_sa_dq(19)';
NODE_NAME     U25 W55
 '@T6G_MB_LIB.T6G(SCH_1):PAGE12_I159@PURE_QUANTA.GENOA_SP5(CHIPS)':
 'MCA_DATA19': CDS_PINID='MCA_DATA19';
NODE_NAME     J17 176
 '@T6G_MB_LIB.T6G(SCH_1):PAGE87_I350@PURE_QUANTA.SCONN288_DDR506112002KQ(CHIPS)':
 'DQ19_A': CDS_PINID='DQ19_A';
NET_NAME
'M_C_CPU0_SA_DQ<1>'
 '@T6G_MB_LIB.T6G(SCH_1):M_C_CPU0_SA_DQ'<1>:
 C_SIGNAL='@t6g_mb_lib.t6g(sch_1):m_c_cpu0_sa_dq(1)';
NODE_NAME     U25 F55
 '@T6G_MB_LIB.T6G(SCH_1):PAGE12_I159@PURE_QUANTA.GENOA_SP5(CHIPS)':
 'MCA_DATA1': CDS_PINID='MCA_DATA1';
NODE_NAME     J17 9
 '@T6G_MB_LIB.T6G(SCH_1):PAGE87_I350@PURE_QUANTA.SCONN288_DDR506112002KQ(CHIPS)':
 'DQ1_A': CDS_PINID='DQ1_A';
NET_NAME
'M_C_CPU0_SA_DQ<20>'
 '@T6G_MB_LIB.T6G(SCH_1):M_C_CPU0_SA_DQ'<20>:
 C_SIGNAL='@t6g_mb_lib.t6g(sch_1):m_c_cpu0_sa_dq(20)';
NODE_NAME     U25 AA57
 '@T6G_MB_LIB.T6G(SCH_1):PAGE12_I159@PURE_QUANTA.GENOA_SP5(CHIPS)':
 'MCA_DATA20': CDS_PINID='MCA_DATA20';
NODE_NAME     J17 36
 '@T6G_MB_LIB.T6G(SCH_1):PAGE87_I350@PURE_QUANTA.SCONN288_DDR506112002KQ(CHIPS)':
 'DQ20_A': CDS_PINID='DQ20_A';
NET_NAME
'M_C_CPU0_SA_DQ<21>'
 '@T6G_MB_LIB.T6G(SCH_1):M_C_CPU0_SA_DQ'<21>:
 C_SIGNAL='@t6g_mb_lib.t6g(sch_1):m_c_cpu0_sa_dq(21)';
NODE_NAME     U25 AB55
 '@T6G_MB_LIB.T6G(SCH_1):PAGE12_I159@PURE_QUANTA.GENOA_SP5(CHIPS)':
 'MCA_DATA21': CDS_PINID='MCA_DATA21';
NODE_NAME     J17 38
 '@T6G_MB_LIB.T6G(SCH_1):PAGE87_I350@PURE_QUANTA.SCONN288_DDR506112002KQ(CHIPS)':
 'DQ21_A': CDS_PINID='DQ21_A';
NET_NAME
'M_C_CPU0_SA_DQ<22>'
 '@T6G_MB_LIB.T6G(SCH_1):M_C_CPU0_SA_DQ'<22>:
 C_SIGNAL='@t6g_mb_lib.t6g(sch_1):m_c_cpu0_sa_dq(22)';
NODE_NAME     U25 AB56
 '@T6G_MB_LIB.T6G(SCH_1):PAGE12_I159@PURE_QUANTA.GENOA_SP5(CHIPS)':
 'MCA_DATA22': CDS_PINID='MCA_DATA22';
NODE_NAME     J17 181
 '@T6G_MB_LIB.T6G(SCH_1):PAGE87_I350@PURE_QUANTA.SCONN288_DDR506112002KQ(CHIPS)':
 'DQ22_A': CDS_PINID='DQ22_A';
NET_NAME
'M_C_CPU0_SA_DQ<23>'
 '@T6G_MB_LIB.T6G(SCH_1):M_C_CPU0_SA_DQ'<23>:
 C_SIGNAL='@t6g_mb_lib.t6g(sch_1):m_c_cpu0_sa_dq(23)';
NODE_NAME     U25 AC55
 '@T6G_MB_LIB.T6G(SCH_1):PAGE12_I159@PURE_QUANTA.GENOA_SP5(CHIPS)':
 'MCA_DATA23': CDS_PINID='MCA_DATA23';
NODE_NAME     J17 183
 '@T6G_MB_LIB.T6G(SCH_1):PAGE87_I350@PURE_QUANTA.SCONN288_DDR506112002KQ(CHIPS)':
 'DQ23_A': CDS_PINID='DQ23_A';
NET_NAME
'M_C_CPU0_SA_DQ<24>'
 '@T6G_MB_LIB.T6G(SCH_1):M_C_CPU0_SA_DQ'<24>:
 C_SIGNAL='@t6g_mb_lib.t6g(sch_1):m_c_cpu0_sa_dq(24)';
NODE_NAME     U25 AC57
 '@T6G_MB_LIB.T6G(SCH_1):PAGE12_I159@PURE_QUANTA.GENOA_SP5(CHIPS)':
 'MCA_DATA24': CDS_PINID='MCA_DATA24';
NODE_NAME     J17 40
 '@T6G_MB_LIB.T6G(SCH_1):PAGE87_I350@PURE_QUANTA.SCONN288_DDR506112002KQ(CHIPS)':
 'DQ24_A': CDS_PINID='DQ24_A';
NET_NAME
'M_C_CPU0_SA_DQ<25>'
 '@T6G_MB_LIB.T6G(SCH_1):M_C_CPU0_SA_DQ'<25>:
 C_SIGNAL='@t6g_mb_lib.t6g(sch_1):m_c_cpu0_sa_dq(25)';
NODE_NAME     U25 AD55
 '@T6G_MB_LIB.T6G(SCH_1):PAGE12_I159@PURE_QUANTA.GENOA_SP5(CHIPS)':
 'MCA_DATA25': CDS_PINID='MCA_DATA25';
NODE_NAME     J17 42
 '@T6G_MB_LIB.T6G(SCH_1):PAGE87_I350@PURE_QUANTA.SCONN288_DDR506112002KQ(CHIPS)':
 'DQ25_A': CDS_PINID='DQ25_A';
NET_NAME
'M_C_CPU0_SA_DQ<26>'
 '@T6G_MB_LIB.T6G(SCH_1):M_C_CPU0_SA_DQ'<26>:
 C_SIGNAL='@t6g_mb_lib.t6g(sch_1):m_c_cpu0_sa_dq(26)';
NODE_NAME     U25 AD56
 '@T6G_MB_LIB.T6G(SCH_1):PAGE12_I159@PURE_QUANTA.GENOA_SP5(CHIPS)':
 'MCA_DATA26': CDS_PINID='MCA_DATA26';
NODE_NAME     J17 185
 '@T6G_MB_LIB.T6G(SCH_1):PAGE87_I350@PURE_QUANTA.SCONN288_DDR506112002KQ(CHIPS)':
 'DQ26_A': CDS_PINID='DQ26_A';
NET_NAME
'M_C_CPU0_SA_DQ<27>'
 '@T6G_MB_LIB.T6G(SCH_1):M_C_CPU0_SA_DQ'<27>:
 C_SIGNAL='@t6g_mb_lib.t6g(sch_1):m_c_cpu0_sa_dq(27)';
NODE_NAME     U25 AE55
 '@T6G_MB_LIB.T6G(SCH_1):PAGE12_I159@PURE_QUANTA.GENOA_SP5(CHIPS)':
 'MCA_DATA27': CDS_PINID='MCA_DATA27';
NODE_NAME     J17 187
 '@T6G_MB_LIB.T6G(SCH_1):PAGE87_I350@PURE_QUANTA.SCONN288_DDR506112002KQ(CHIPS)':
 'DQ27_A': CDS_PINID='DQ27_A';
NET_NAME
'M_C_CPU0_SA_DQ<28>'
 '@T6G_MB_LIB.T6G(SCH_1):M_C_CPU0_SA_DQ'<28>:
 C_SIGNAL='@t6g_mb_lib.t6g(sch_1):m_c_cpu0_sa_dq(28)';
NODE_NAME     U25 AG57
 '@T6G_MB_LIB.T6G(SCH_1):PAGE12_I159@PURE_QUANTA.GENOA_SP5(CHIPS)':
 'MCA_DATA28': CDS_PINID='MCA_DATA28';
NODE_NAME     J17 47
 '@T6G_MB_LIB.T6G(SCH_1):PAGE87_I350@PURE_QUANTA.SCONN288_DDR506112002KQ(CHIPS)':
 'DQ28_A': CDS_PINID='DQ28_A';
NET_NAME
'M_C_CPU0_SA_DQ<29>'
 '@T6G_MB_LIB.T6G(SCH_1):M_C_CPU0_SA_DQ'<29>:
 C_SIGNAL='@t6g_mb_lib.t6g(sch_1):m_c_cpu0_sa_dq(29)';
NODE_NAME     U25 AH55
 '@T6G_MB_LIB.T6G(SCH_1):PAGE12_I159@PURE_QUANTA.GENOA_SP5(CHIPS)':
 'MCA_DATA29': CDS_PINID='MCA_DATA29';
NODE_NAME     J17 49
 '@T6G_MB_LIB.T6G(SCH_1):PAGE87_I350@PURE_QUANTA.SCONN288_DDR506112002KQ(CHIPS)':
 'DQ29_A': CDS_PINID='DQ29_A';
NET_NAME
'M_C_CPU0_SA_DQ<2>'
 '@T6G_MB_LIB.T6G(SCH_1):M_C_CPU0_SA_DQ'<2>:
 C_SIGNAL='@t6g_mb_lib.t6g(sch_1):m_c_cpu0_sa_dq(2)';
NODE_NAME     U25 F56
 '@T6G_MB_LIB.T6G(SCH_1):PAGE12_I159@PURE_QUANTA.GENOA_SP5(CHIPS)':
 'MCA_DATA2': CDS_PINID='MCA_DATA2';
NODE_NAME     J17 152
 '@T6G_MB_LIB.T6G(SCH_1):PAGE87_I350@PURE_QUANTA.SCONN288_DDR506112002KQ(CHIPS)':
 'DQ2_A': CDS_PINID='DQ2_A';
NET_NAME
'M_C_CPU0_SA_DQ<30>'
 '@T6G_MB_LIB.T6G(SCH_1):M_C_CPU0_SA_DQ'<30>:
 C_SIGNAL='@t6g_mb_lib.t6g(sch_1):m_c_cpu0_sa_dq(30)';
NODE_NAME     U25 AH56
 '@T6G_MB_LIB.T6G(SCH_1):PAGE12_I159@PURE_QUANTA.GENOA_SP5(CHIPS)':
 'MCA_DATA30': CDS_PINID='MCA_DATA30';
NODE_NAME     J17 192
 '@T6G_MB_LIB.T6G(SCH_1):PAGE87_I350@PURE_QUANTA.SCONN288_DDR506112002KQ(CHIPS)':
 'DQ30_A': CDS_PINID='DQ30_A';
NET_NAME
'M_C_CPU0_SA_DQ<31>'
 '@T6G_MB_LIB.T6G(SCH_1):M_C_CPU0_SA_DQ'<31>:
 C_SIGNAL='@t6g_mb_lib.t6g(sch_1):m_c_cpu0_sa_dq(31)';
NODE_NAME     U25 AJ55
 '@T6G_MB_LIB.T6G(SCH_1):PAGE12_I159@PURE_QUANTA.GENOA_SP5(CHIPS)':
 'MCA_DATA31': CDS_PINID='MCA_DATA31';
NODE_NAME     J17 194
 '@T6G_MB_LIB.T6G(SCH_1):PAGE87_I350@PURE_QUANTA.SCONN288_DDR506112002KQ(CHIPS)':
 'DQ31_A': CDS_PINID='DQ31_A';
NET_NAME
'M_C_CPU0_SA_DQ<3>'
 '@T6G_MB_LIB.T6G(SCH_1):M_C_CPU0_SA_DQ'<3>:
 C_SIGNAL='@t6g_mb_lib.t6g(sch_1):m_c_cpu0_sa_dq(3)';
NODE_NAME     U25 G55
 '@T6G_MB_LIB.T6G(SCH_1):PAGE12_I159@PURE_QUANTA.GENOA_SP5(CHIPS)':
 'MCA_DATA3': CDS_PINID='MCA_DATA3';
NODE_NAME     J17 154
 '@T6G_MB_LIB.T6G(SCH_1):PAGE87_I350@PURE_QUANTA.SCONN288_DDR506112002KQ(CHIPS)':
 'DQ3_A': CDS_PINID='DQ3_A';
NET_NAME
'M_C_CPU0_SA_DQ<4>'
 '@T6G_MB_LIB.T6G(SCH_1):M_C_CPU0_SA_DQ'<4>:
 C_SIGNAL='@t6g_mb_lib.t6g(sch_1):m_c_cpu0_sa_dq(4)';
NODE_NAME     U25 J57
 '@T6G_MB_LIB.T6G(SCH_1):PAGE12_I159@PURE_QUANTA.GENOA_SP5(CHIPS)':
 'MCA_DATA4': CDS_PINID='MCA_DATA4';
NODE_NAME     J17 14
 '@T6G_MB_LIB.T6G(SCH_1):PAGE87_I350@PURE_QUANTA.SCONN288_DDR506112002KQ(CHIPS)':
 'DQ4_A': CDS_PINID='DQ4_A';
NET_NAME
'M_C_CPU0_SA_DQ<5>'
 '@T6G_MB_LIB.T6G(SCH_1):M_C_CPU0_SA_DQ'<5>:
 C_SIGNAL='@t6g_mb_lib.t6g(sch_1):m_c_cpu0_sa_dq(5)';
NODE_NAME     U25 K55
 '@T6G_MB_LIB.T6G(SCH_1):PAGE12_I159@PURE_QUANTA.GENOA_SP5(CHIPS)':
 'MCA_DATA5': CDS_PINID='MCA_DATA5';
NODE_NAME     J17 16
 '@T6G_MB_LIB.T6G(SCH_1):PAGE87_I350@PURE_QUANTA.SCONN288_DDR506112002KQ(CHIPS)':
 'DQ5_A': CDS_PINID='DQ5_A';
NET_NAME
'M_C_CPU0_SA_DQ<6>'
 '@T6G_MB_LIB.T6G(SCH_1):M_C_CPU0_SA_DQ'<6>:
 C_SIGNAL='@t6g_mb_lib.t6g(sch_1):m_c_cpu0_sa_dq(6)';
NODE_NAME     U25 K56
 '@T6G_MB_LIB.T6G(SCH_1):PAGE12_I159@PURE_QUANTA.GENOA_SP5(CHIPS)':
 'MCA_DATA6': CDS_PINID='MCA_DATA6';
NODE_NAME     J17 159
 '@T6G_MB_LIB.T6G(SCH_1):PAGE87_I350@PURE_QUANTA.SCONN288_DDR506112002KQ(CHIPS)':
 'DQ6_A': CDS_PINID='DQ6_A';
NET_NAME
'M_C_CPU0_SA_DQ<7>'
 '@T6G_MB_LIB.T6G(SCH_1):M_C_CPU0_SA_DQ'<7>:
 C_SIGNAL='@t6g_mb_lib.t6g(sch_1):m_c_cpu0_sa_dq(7)';
NODE_NAME     U25 L55
 '@T6G_MB_LIB.T6G(SCH_1):PAGE12_I159@PURE_QUANTA.GENOA_SP5(CHIPS)':
 'MCA_DATA7': CDS_PINID='MCA_DATA7';
NODE_NAME     J17 161
 '@T6G_MB_LIB.T6G(SCH_1):PAGE87_I350@PURE_QUANTA.SCONN288_DDR506112002KQ(CHIPS)':
 'DQ7_A': CDS_PINID='DQ7_A';
NET_NAME
'M_C_CPU0_SA_DQ<8>'
 '@T6G_MB_LIB.T6G(SCH_1):M_C_CPU0_SA_DQ'<8>:
 C_SIGNAL='@t6g_mb_lib.t6g(sch_1):m_c_cpu0_sa_dq(8)';
NODE_NAME     U25 L57
 '@T6G_MB_LIB.T6G(SCH_1):PAGE12_I159@PURE_QUANTA.GENOA_SP5(CHIPS)':
 'MCA_DATA8': CDS_PINID='MCA_DATA8';
NODE_NAME     J17 18
 '@T6G_MB_LIB.T6G(SCH_1):PAGE87_I350@PURE_QUANTA.SCONN288_DDR506112002KQ(CHIPS)':
 'DQ8_A': CDS_PINID='DQ8_A';
NET_NAME
'M_C_CPU0_SA_DQ<9>'
 '@T6G_MB_LIB.T6G(SCH_1):M_C_CPU0_SA_DQ'<9>:
 C_SIGNAL='@t6g_mb_lib.t6g(sch_1):m_c_cpu0_sa_dq(9)';
NODE_NAME     U25 M55
 '@T6G_MB_LIB.T6G(SCH_1):PAGE12_I159@PURE_QUANTA.GENOA_SP5(CHIPS)':
 'MCA_DATA9': CDS_PINID='MCA_DATA9';
NODE_NAME     J17 20
 '@T6G_MB_LIB.T6G(SCH_1):PAGE87_I350@PURE_QUANTA.SCONN288_DDR506112002KQ(CHIPS)':
 'DQ9_A': CDS_PINID='DQ9_A';
NET_NAME
'M_C_CPU0_SA_DQS_DN<0>'
 '@T6G_MB_LIB.T6G(SCH_1):M_C_CPU0_SA_DQS_DN'<0>:
 C_SIGNAL='@t6g_mb_lib.t6g(sch_1):m_c_cpu0_sa_dqs_dn(0)';
NODE_NAME     U25 H56
 '@T6G_MB_LIB.T6G(SCH_1):PAGE12_I159@PURE_QUANTA.GENOA_SP5(CHIPS)':
 'MCA_DQS_L0': CDS_PINID='MCA_DQS_L0';
NODE_NAME     J17 12
 '@T6G_MB_LIB.T6G(SCH_1):PAGE87_I411@PURE_QUANTA.SCONN288_DDR506112002KQ(CHIPS)':
 'DQS0_A_C': CDS_PINID='DQS0_A_C';
NET_NAME
'M_C_CPU0_SA_DQS_DN<1>'
 '@T6G_MB_LIB.T6G(SCH_1):M_C_CPU0_SA_DQS_DN'<1>:
 C_SIGNAL='@t6g_mb_lib.t6g(sch_1):m_c_cpu0_sa_dqs_dn(1)';
NODE_NAME     U25 P56
 '@T6G_MB_LIB.T6G(SCH_1):PAGE12_I159@PURE_QUANTA.GENOA_SP5(CHIPS)':
 'MCA_DQS_L1': CDS_PINID='MCA_DQS_L1';
NODE_NAME     J17 23
 '@T6G_MB_LIB.T6G(SCH_1):PAGE87_I411@PURE_QUANTA.SCONN288_DDR506112002KQ(CHIPS)':
 'DQS1_A_C': CDS_PINID='DQS1_A_C';
NET_NAME
'M_C_CPU0_SA_DQS_DN<2>'
 '@T6G_MB_LIB.T6G(SCH_1):M_C_CPU0_SA_DQS_DN'<2>:
 C_SIGNAL='@t6g_mb_lib.t6g(sch_1):m_c_cpu0_sa_dqs_dn(2)';
NODE_NAME     U25 Y56
 '@T6G_MB_LIB.T6G(SCH_1):PAGE12_I159@PURE_QUANTA.GENOA_SP5(CHIPS)':
 'MCA_DQS_L2': CDS_PINID='MCA_DQS_L2';
NODE_NAME     J17 34
 '@T6G_MB_LIB.T6G(SCH_1):PAGE87_I411@PURE_QUANTA.SCONN288_DDR506112002KQ(CHIPS)':
 'DQS2_A_C': CDS_PINID='DQS2_A_C';
NET_NAME
'M_C_CPU0_SA_DQS_DN<3>'
 '@T6G_MB_LIB.T6G(SCH_1):M_C_CPU0_SA_DQS_DN'<3>:
 C_SIGNAL='@t6g_mb_lib.t6g(sch_1):m_c_cpu0_sa_dqs_dn(3)';
NODE_NAME     U25 AF56
 '@T6G_MB_LIB.T6G(SCH_1):PAGE12_I159@PURE_QUANTA.GENOA_SP5(CHIPS)':
 'MCA_DQS_L3': CDS_PINID='MCA_DQS_L3';
NODE_NAME     J17 45
 '@T6G_MB_LIB.T6G(SCH_1):PAGE87_I411@PURE_QUANTA.SCONN288_DDR506112002KQ(CHIPS)':
 'DQS3_A_C': CDS_PINID='DQS3_A_C';
NET_NAME
'M_C_CPU0_SA_DQS_DN<4>'
 '@T6G_MB_LIB.T6G(SCH_1):M_C_CPU0_SA_DQS_DN'<4>:
 C_SIGNAL='@t6g_mb_lib.t6g(sch_1):m_c_cpu0_sa_dqs_dn(4)';
NODE_NAME     U25 AM56
 '@T6G_MB_LIB.T6G(SCH_1):PAGE12_I159@PURE_QUANTA.GENOA_SP5(CHIPS)':
 'MCA_DQS_L4': CDS_PINID='MCA_DQS_L4';
NODE_NAME     J17 56
 '@T6G_MB_LIB.T6G(SCH_1):PAGE87_I411@PURE_QUANTA.SCONN288_DDR506112002KQ(CHIPS)':
 'DQS4_A_C': CDS_PINID='DQS4_A_C';
NET_NAME
'M_C_CPU0_SA_DQS_DN<5>'
 '@T6G_MB_LIB.T6G(SCH_1):M_C_CPU0_SA_DQS_DN'<5>:
 C_SIGNAL='@t6g_mb_lib.t6g(sch_1):m_c_cpu0_sa_dqs_dn(5)';
NODE_NAME     U25 H55
 '@T6G_MB_LIB.T6G(SCH_1):PAGE12_I159@PURE_QUANTA.GENOA_SP5(CHIPS)':
 'MCA_DQS_L5': CDS_PINID='MCA_DQS_L5';
NODE_NAME     J17 156
 '@T6G_MB_LIB.T6G(SCH_1):PAGE87_I411@PURE_QUANTA.SCONN288_DDR506112002KQ(CHIPS)':
 'DQS5_A_C||TDQS5_A_C||DQS5_A_T||TDQS5_A_T': CDS_PINID='\dqs5_a_c||tdqs5_a_c||dqs5_a_t||tdqs5_a_t\';
NET_NAME
'M_C_CPU0_SA_DQS_DN<6>'
 '@T6G_MB_LIB.T6G(SCH_1):M_C_CPU0_SA_DQS_DN'<6>:
 C_SIGNAL='@t6g_mb_lib.t6g(sch_1):m_c_cpu0_sa_dqs_dn(6)';
NODE_NAME     U25 P55
 '@T6G_MB_LIB.T6G(SCH_1):PAGE12_I159@PURE_QUANTA.GENOA_SP5(CHIPS)':
 'MCA_DQS_L6': CDS_PINID='MCA_DQS_L6';
NODE_NAME     J17 167
 '@T6G_MB_LIB.T6G(SCH_1):PAGE87_I411@PURE_QUANTA.SCONN288_DDR506112002KQ(CHIPS)':
 'DQS6_A_C||TDQS6_A_C||DQS6_A_T||TDQS6_A_T': CDS_PINID='\dqs6_a_c||tdqs6_a_c||dqs6_a_t||tdqs6_a_t\';
NET_NAME
'M_C_CPU0_SA_DQS_DN<7>'
 '@T6G_MB_LIB.T6G(SCH_1):M_C_CPU0_SA_DQS_DN'<7>:
 C_SIGNAL='@t6g_mb_lib.t6g(sch_1):m_c_cpu0_sa_dqs_dn(7)';
NODE_NAME     U25 Y55
 '@T6G_MB_LIB.T6G(SCH_1):PAGE12_I159@PURE_QUANTA.GENOA_SP5(CHIPS)':
 'MCA_DQS_L7': CDS_PINID='MCA_DQS_L7';
NODE_NAME     J17 178
 '@T6G_MB_LIB.T6G(SCH_1):PAGE87_I411@PURE_QUANTA.SCONN288_DDR506112002KQ(CHIPS)':
 'DQS7_A_C||TDQS7_A_C': CDS_PINID='\dqs7_a_c||tdqs7_a_c\';
NET_NAME
'M_C_CPU0_SA_DQS_DN<8>'
 '@T6G_MB_LIB.T6G(SCH_1):M_C_CPU0_SA_DQS_DN'<8>:
 C_SIGNAL='@t6g_mb_lib.t6g(sch_1):m_c_cpu0_sa_dqs_dn(8)';
NODE_NAME     U25 AF55
 '@T6G_MB_LIB.T6G(SCH_1):PAGE12_I159@PURE_QUANTA.GENOA_SP5(CHIPS)':
 'MCA_DQS_L8': CDS_PINID='MCA_DQS_L8';
NODE_NAME     J17 189
 '@T6G_MB_LIB.T6G(SCH_1):PAGE87_I411@PURE_QUANTA.SCONN288_DDR506112002KQ(CHIPS)':
 'DQS8_A_C||TDQS8_A_C': CDS_PINID='\dqs8_a_c||tdqs8_a_c\';
NET_NAME
'M_C_CPU0_SA_DQS_DN<9>'
 '@T6G_MB_LIB.T6G(SCH_1):M_C_CPU0_SA_DQS_DN'<9>:
 C_SIGNAL='@t6g_mb_lib.t6g(sch_1):m_c_cpu0_sa_dqs_dn(9)';
NODE_NAME     U25 AM55
 '@T6G_MB_LIB.T6G(SCH_1):PAGE12_I159@PURE_QUANTA.GENOA_SP5(CHIPS)':
 'MCA_DQS_L9': CDS_PINID='MCA_DQS_L9';
NODE_NAME     J17 200
 '@T6G_MB_LIB.T6G(SCH_1):PAGE87_I411@PURE_QUANTA.SCONN288_DDR506112002KQ(CHIPS)':
 'DQS9_A_C||TDQS9_A_C': CDS_PINID='\dqs9_a_c||tdqs9_a_c\';
NET_NAME
'M_C_CPU0_SA_DQS_DP<0>'
 '@T6G_MB_LIB.T6G(SCH_1):M_C_CPU0_SA_DQS_DP'<0>:
 C_SIGNAL='@t6g_mb_lib.t6g(sch_1):m_c_cpu0_sa_dqs_dp(0)';
NODE_NAME     U25 G57
 '@T6G_MB_LIB.T6G(SCH_1):PAGE12_I159@PURE_QUANTA.GENOA_SP5(CHIPS)':
 'MCA_DQS_H0': CDS_PINID='MCA_DQS_H0';
NODE_NAME     J17 11
 '@T6G_MB_LIB.T6G(SCH_1):PAGE87_I411@PURE_QUANTA.SCONN288_DDR506112002KQ(CHIPS)':
 'DQS0_A_T': CDS_PINID='DQS0_A_T';
NET_NAME
'M_C_CPU0_SA_DQS_DP<1>'
 '@T6G_MB_LIB.T6G(SCH_1):M_C_CPU0_SA_DQS_DP'<1>:
 C_SIGNAL='@t6g_mb_lib.t6g(sch_1):m_c_cpu0_sa_dqs_dp(1)';
NODE_NAME     U25 N57
 '@T6G_MB_LIB.T6G(SCH_1):PAGE12_I159@PURE_QUANTA.GENOA_SP5(CHIPS)':
 'MCA_DQS_H1': CDS_PINID='MCA_DQS_H1';
NODE_NAME     J17 22
 '@T6G_MB_LIB.T6G(SCH_1):PAGE87_I411@PURE_QUANTA.SCONN288_DDR506112002KQ(CHIPS)':
 'DQS1_A_T': CDS_PINID='DQS1_A_T';
NET_NAME
'M_C_CPU0_SA_DQS_DP<2>'
 '@T6G_MB_LIB.T6G(SCH_1):M_C_CPU0_SA_DQS_DP'<2>:
 C_SIGNAL='@t6g_mb_lib.t6g(sch_1):m_c_cpu0_sa_dqs_dp(2)';
NODE_NAME     U25 W57
 '@T6G_MB_LIB.T6G(SCH_1):PAGE12_I159@PURE_QUANTA.GENOA_SP5(CHIPS)':
 'MCA_DQS_H2': CDS_PINID='MCA_DQS_H2';
NODE_NAME     J17 33
 '@T6G_MB_LIB.T6G(SCH_1):PAGE87_I411@PURE_QUANTA.SCONN288_DDR506112002KQ(CHIPS)':
 'DQS2_A_T': CDS_PINID='DQS2_A_T';
NET_NAME
'M_C_CPU0_SA_DQS_DP<3>'
 '@T6G_MB_LIB.T6G(SCH_1):M_C_CPU0_SA_DQS_DP'<3>:
 C_SIGNAL='@t6g_mb_lib.t6g(sch_1):m_c_cpu0_sa_dqs_dp(3)';
NODE_NAME     U25 AE57
 '@T6G_MB_LIB.T6G(SCH_1):PAGE12_I159@PURE_QUANTA.GENOA_SP5(CHIPS)':
 'MCA_DQS_H3': CDS_PINID='MCA_DQS_H3';
NODE_NAME     J17 44
 '@T6G_MB_LIB.T6G(SCH_1):PAGE87_I411@PURE_QUANTA.SCONN288_DDR506112002KQ(CHIPS)':
 'DQS3_A_T': CDS_PINID='DQS3_A_T';
NET_NAME
'M_C_CPU0_SA_DQS_DP<4>'
 '@T6G_MB_LIB.T6G(SCH_1):M_C_CPU0_SA_DQS_DP'<4>:
 C_SIGNAL='@t6g_mb_lib.t6g(sch_1):m_c_cpu0_sa_dqs_dp(4)';
NODE_NAME     U25 AL57
 '@T6G_MB_LIB.T6G(SCH_1):PAGE12_I159@PURE_QUANTA.GENOA_SP5(CHIPS)':
 'MCA_DQS_H4': CDS_PINID='MCA_DQS_H4';
NODE_NAME     J17 55
 '@T6G_MB_LIB.T6G(SCH_1):PAGE87_I411@PURE_QUANTA.SCONN288_DDR506112002KQ(CHIPS)':
 'DQS4_A_T': CDS_PINID='DQS4_A_T';
NET_NAME
'M_C_CPU0_SA_DQS_DP<5>'
 '@T6G_MB_LIB.T6G(SCH_1):M_C_CPU0_SA_DQS_DP'<5>:
 C_SIGNAL='@t6g_mb_lib.t6g(sch_1):m_c_cpu0_sa_dqs_dp(5)';
NODE_NAME     U25 J55
 '@T6G_MB_LIB.T6G(SCH_1):PAGE12_I159@PURE_QUANTA.GENOA_SP5(CHIPS)':
 'MCA_DQS_H5': CDS_PINID='MCA_DQS_H5';
NODE_NAME     J17 157
 '@T6G_MB_LIB.T6G(SCH_1):PAGE87_I411@PURE_QUANTA.SCONN288_DDR506112002KQ(CHIPS)':
 'DQS5_A_T||TDQS5_A_T': CDS_PINID='\dqs5_a_t||tdqs5_a_t\';
NET_NAME
'M_C_CPU0_SA_DQS_DP<6>'
 '@T6G_MB_LIB.T6G(SCH_1):M_C_CPU0_SA_DQS_DP'<6>:
 C_SIGNAL='@t6g_mb_lib.t6g(sch_1):m_c_cpu0_sa_dqs_dp(6)';
NODE_NAME     U25 R55
 '@T6G_MB_LIB.T6G(SCH_1):PAGE12_I159@PURE_QUANTA.GENOA_SP5(CHIPS)':
 'MCA_DQS_H6': CDS_PINID='MCA_DQS_H6';
NODE_NAME     J17 168
 '@T6G_MB_LIB.T6G(SCH_1):PAGE87_I411@PURE_QUANTA.SCONN288_DDR506112002KQ(CHIPS)':
 'DQS6_A_T||TDQS6_A_T': CDS_PINID='\dqs6_a_t||tdqs6_a_t\';
NET_NAME
'M_C_CPU0_SA_DQS_DP<7>'
 '@T6G_MB_LIB.T6G(SCH_1):M_C_CPU0_SA_DQS_DP'<7>:
 C_SIGNAL='@t6g_mb_lib.t6g(sch_1):m_c_cpu0_sa_dqs_dp(7)';
NODE_NAME     U25 AA55
 '@T6G_MB_LIB.T6G(SCH_1):PAGE12_I159@PURE_QUANTA.GENOA_SP5(CHIPS)':
 'MCA_DQS_H7': CDS_PINID='MCA_DQS_H7';
NODE_NAME     J17 179
 '@T6G_MB_LIB.T6G(SCH_1):PAGE87_I411@PURE_QUANTA.SCONN288_DDR506112002KQ(CHIPS)':
 'DQS7_A_T||TDQS7_A_T': CDS_PINID='\dqs7_a_t||tdqs7_a_t\';
NET_NAME
'M_C_CPU0_SA_DQS_DP<8>'
 '@T6G_MB_LIB.T6G(SCH_1):M_C_CPU0_SA_DQS_DP'<8>:
 C_SIGNAL='@t6g_mb_lib.t6g(sch_1):m_c_cpu0_sa_dqs_dp(8)';
NODE_NAME     U25 AG55
 '@T6G_MB_LIB.T6G(SCH_1):PAGE12_I159@PURE_QUANTA.GENOA_SP5(CHIPS)':
 'MCA_DQS_H8': CDS_PINID='MCA_DQS_H8';
NODE_NAME     J17 190
 '@T6G_MB_LIB.T6G(SCH_1):PAGE87_I411@PURE_QUANTA.SCONN288_DDR506112002KQ(CHIPS)':
 'DQS8_A_T||TDQS8_A_T': CDS_PINID='\dqs8_a_t||tdqs8_a_t\';
NET_NAME
'M_C_CPU0_SA_DQS_DP<9>'
 '@T6G_MB_LIB.T6G(SCH_1):M_C_CPU0_SA_DQS_DP'<9>:
 C_SIGNAL='@t6g_mb_lib.t6g(sch_1):m_c_cpu0_sa_dqs_dp(9)';
NODE_NAME     U25 AN55
 '@T6G_MB_LIB.T6G(SCH_1):PAGE12_I159@PURE_QUANTA.GENOA_SP5(CHIPS)':
 'MCA_DQS_H9': CDS_PINID='MCA_DQS_H9';
NODE_NAME     J17 201
 '@T6G_MB_LIB.T6G(SCH_1):PAGE87_I411@PURE_QUANTA.SCONN288_DDR506112002KQ(CHIPS)':
 'DQS9_A_T||TDQS9_A_T': CDS_PINID='\dqs9_a_t||tdqs9_a_t\';
NET_NAME
'M_C_CPU0_SA_PAR'
 '@T6G_MB_LIB.T6G(SCH_1):M_C_CPU0_SA_PAR':
 C_SIGNAL='@t6g_mb_lib.t6g(sch_1):m_c_cpu0_sa_par';
NODE_NAME     U25 BC55
 '@T6G_MB_LIB.T6G(SCH_1):PAGE12_I159@PURE_QUANTA.GENOA_SP5(CHIPS)':
 'MCA_PAR': CDS_PINID='MCA_PAR';
NODE_NAME     J17 74
 '@T6G_MB_LIB.T6G(SCH_1):PAGE87_I350@PURE_QUANTA.SCONN288_DDR506112002KQ(CHIPS)':
 'PAR_A': CDS_PINID='PAR_A';
NET_NAME
'M_C_CPU0_SA_RSP<0>'
 '@T6G_MB_LIB.T6G(SCH_1):M_C_CPU0_SA_RSP'<0>:
 C_SIGNAL='@t6g_mb_lib.t6g(sch_1):m_c_cpu0_sa_rsp(0)';
NODE_NAME     U25 BN55
 '@T6G_MB_LIB.T6G(SCH_1):PAGE12_I159@PURE_QUANTA.GENOA_SP5(CHIPS)':
 'MCA0_RSP_L': CDS_PINID='MCA0_RSP_L';
NODE_NAME     J17 86
 '@T6G_MB_LIB.T6G(SCH_1):PAGE87_I350@PURE_QUANTA.SCONN288_DDR506112002KQ(CHIPS)':
 'LBD||RSP_A_N': CDS_PINID='\lbd||rsp_a_n\';
NET_NAME
'M_C_CPU0_SB_CA<0>'
 '@T6G_MB_LIB.T6G(SCH_1):M_C_CPU0_SB_CA'<0>:
 C_SIGNAL='@t6g_mb_lib.t6g(sch_1):m_c_cpu0_sb_ca(0)';
NODE_NAME     U25 BG55
 '@T6G_MB_LIB.T6G(SCH_1):PAGE12_I159@PURE_QUANTA.GENOA_SP5(CHIPS)':
 'MCB_CA0': CDS_PINID='MCB_CA0';
NODE_NAME     J17 76
 '@T6G_MB_LIB.T6G(SCH_1):PAGE87_I350@PURE_QUANTA.SCONN288_DDR506112002KQ(CHIPS)':
 'CA0_B': CDS_PINID='CA0_B';
NET_NAME
'M_C_CPU0_SB_CA<1>'
 '@T6G_MB_LIB.T6G(SCH_1):M_C_CPU0_SB_CA'<1>:
 C_SIGNAL='@t6g_mb_lib.t6g(sch_1):m_c_cpu0_sb_ca(1)';
NODE_NAME     U25 BH55
 '@T6G_MB_LIB.T6G(SCH_1):PAGE12_I159@PURE_QUANTA.GENOA_SP5(CHIPS)':
 'MCB_CA1': CDS_PINID='MCB_CA1';
NODE_NAME     J17 221
 '@T6G_MB_LIB.T6G(SCH_1):PAGE87_I350@PURE_QUANTA.SCONN288_DDR506112002KQ(CHIPS)':
 'CA1_B': CDS_PINID='CA1_B';
NET_NAME
'M_C_CPU0_SB_CA<2>'
 '@T6G_MB_LIB.T6G(SCH_1):M_C_CPU0_SB_CA'<2>:
 C_SIGNAL='@t6g_mb_lib.t6g(sch_1):m_c_cpu0_sb_ca(2)';
NODE_NAME     U25 BH56
 '@T6G_MB_LIB.T6G(SCH_1):PAGE12_I159@PURE_QUANTA.GENOA_SP5(CHIPS)':
 'MCB_CA2': CDS_PINID='MCB_CA2';
NODE_NAME     J17 78
 '@T6G_MB_LIB.T6G(SCH_1):PAGE87_I350@PURE_QUANTA.SCONN288_DDR506112002KQ(CHIPS)':
 'CA2_B': CDS_PINID='CA2_B';
NET_NAME
'M_C_CPU0_SB_CA<3>'
 '@T6G_MB_LIB.T6G(SCH_1):M_C_CPU0_SB_CA'<3>:
 C_SIGNAL='@t6g_mb_lib.t6g(sch_1):m_c_cpu0_sb_ca(3)';
NODE_NAME     U25 BJ57
 '@T6G_MB_LIB.T6G(SCH_1):PAGE12_I159@PURE_QUANTA.GENOA_SP5(CHIPS)':
 'MCB_CA3': CDS_PINID='MCB_CA3';
NODE_NAME     J17 223
 '@T6G_MB_LIB.T6G(SCH_1):PAGE87_I350@PURE_QUANTA.SCONN288_DDR506112002KQ(CHIPS)':
 'CA3_B': CDS_PINID='CA3_B';
NET_NAME
'M_C_CPU0_SB_CA<4>'
 '@T6G_MB_LIB.T6G(SCH_1):M_C_CPU0_SB_CA'<4>:
 C_SIGNAL='@t6g_mb_lib.t6g(sch_1):m_c_cpu0_sb_ca(4)';
NODE_NAME     U25 BJ55
 '@T6G_MB_LIB.T6G(SCH_1):PAGE12_I159@PURE_QUANTA.GENOA_SP5(CHIPS)':
 'MCB_CA4': CDS_PINID='MCB_CA4';
NODE_NAME     J17 80
 '@T6G_MB_LIB.T6G(SCH_1):PAGE87_I350@PURE_QUANTA.SCONN288_DDR506112002KQ(CHIPS)':
 'CA4_B': CDS_PINID='CA4_B';
NET_NAME
'M_C_CPU0_SB_CA<5>'
 '@T6G_MB_LIB.T6G(SCH_1):M_C_CPU0_SB_CA'<5>:
 C_SIGNAL='@t6g_mb_lib.t6g(sch_1):m_c_cpu0_sb_ca(5)';
NODE_NAME     U25 BK55
 '@T6G_MB_LIB.T6G(SCH_1):PAGE12_I159@PURE_QUANTA.GENOA_SP5(CHIPS)':
 'MCB_CA5': CDS_PINID='MCB_CA5';
NODE_NAME     J17 225
 '@T6G_MB_LIB.T6G(SCH_1):PAGE87_I350@PURE_QUANTA.SCONN288_DDR506112002KQ(CHIPS)':
 'CA5_B': CDS_PINID='CA5_B';
NET_NAME
'M_C_CPU0_SB_CA<6>'
 '@T6G_MB_LIB.T6G(SCH_1):M_C_CPU0_SB_CA'<6>:
 C_SIGNAL='@t6g_mb_lib.t6g(sch_1):m_c_cpu0_sb_ca(6)';
NODE_NAME     U25 BK56
 '@T6G_MB_LIB.T6G(SCH_1):PAGE12_I159@PURE_QUANTA.GENOA_SP5(CHIPS)':
 'MCB_CA6': CDS_PINID='MCB_CA6';
NODE_NAME     J17 82
 '@T6G_MB_LIB.T6G(SCH_1):PAGE87_I350@PURE_QUANTA.SCONN288_DDR506112002KQ(CHIPS)':
 'CA6_B': CDS_PINID='CA6_B';
NET_NAME
'M_C_CPU0_SB_CB<0>'
 '@T6G_MB_LIB.T6G(SCH_1):M_C_CPU0_SB_CB'<0>:
 C_SIGNAL='@t6g_mb_lib.t6g(sch_1):m_c_cpu0_sb_cb(0)';
NODE_NAME     U25 BY56
 '@T6G_MB_LIB.T6G(SCH_1):PAGE12_I159@PURE_QUANTA.GENOA_SP5(CHIPS)':
 'MCB_CHECK0': CDS_PINID='MCB_CHECK0';
NODE_NAME     J17 96
 '@T6G_MB_LIB.T6G(SCH_1):PAGE87_I350@PURE_QUANTA.SCONN288_DDR506112002KQ(CHIPS)':
 'CB0_B': CDS_PINID='CB0_B';
NET_NAME
'M_C_CPU0_SB_CB<1>'
 '@T6G_MB_LIB.T6G(SCH_1):M_C_CPU0_SB_CB'<1>:
 C_SIGNAL='@t6g_mb_lib.t6g(sch_1):m_c_cpu0_sb_cb(1)';
NODE_NAME     U25 CA55
 '@T6G_MB_LIB.T6G(SCH_1):PAGE12_I159@PURE_QUANTA.GENOA_SP5(CHIPS)':
 'MCB_CHECK1': CDS_PINID='MCB_CHECK1';
NODE_NAME     J17 98
 '@T6G_MB_LIB.T6G(SCH_1):PAGE87_I350@PURE_QUANTA.SCONN288_DDR506112002KQ(CHIPS)':
 'CB1_B': CDS_PINID='CB1_B';
NET_NAME
'M_C_CPU0_SB_CB<2>'
 '@T6G_MB_LIB.T6G(SCH_1):M_C_CPU0_SB_CB'<2>:
 C_SIGNAL='@t6g_mb_lib.t6g(sch_1):m_c_cpu0_sb_cb(2)';
NODE_NAME     U25 CA57
 '@T6G_MB_LIB.T6G(SCH_1):PAGE12_I159@PURE_QUANTA.GENOA_SP5(CHIPS)':
 'MCB_CHECK2': CDS_PINID='MCB_CHECK2';
NODE_NAME     J17 241
 '@T6G_MB_LIB.T6G(SCH_1):PAGE87_I350@PURE_QUANTA.SCONN288_DDR506112002KQ(CHIPS)':
 'CB2_B': CDS_PINID='CB2_B';
NET_NAME
'M_C_CPU0_SB_CB<3>'
 '@T6G_MB_LIB.T6G(SCH_1):M_C_CPU0_SB_CB'<3>:
 C_SIGNAL='@t6g_mb_lib.t6g(sch_1):m_c_cpu0_sb_cb(3)';
NODE_NAME     U25 CB55
 '@T6G_MB_LIB.T6G(SCH_1):PAGE12_I159@PURE_QUANTA.GENOA_SP5(CHIPS)':
 'MCB_CHECK3': CDS_PINID='MCB_CHECK3';
NODE_NAME     J17 243
 '@T6G_MB_LIB.T6G(SCH_1):PAGE87_I350@PURE_QUANTA.SCONN288_DDR506112002KQ(CHIPS)':
 'CB3_B': CDS_PINID='CB3_B';
NET_NAME
'M_C_CPU0_SB_CB<4>'
 '@T6G_MB_LIB.T6G(SCH_1):M_C_CPU0_SB_CB'<4>:
 C_SIGNAL='@t6g_mb_lib.t6g(sch_1):m_c_cpu0_sb_cb(4)';
NODE_NAME     U25 BT56
 '@T6G_MB_LIB.T6G(SCH_1):PAGE12_I159@PURE_QUANTA.GENOA_SP5(CHIPS)':
 'MCB_CHECK4': CDS_PINID='MCB_CHECK4';
NODE_NAME     J17 89
 '@T6G_MB_LIB.T6G(SCH_1):PAGE87_I350@PURE_QUANTA.SCONN288_DDR506112002KQ(CHIPS)':
 'CB4_B': CDS_PINID='CB4_B';
NET_NAME
'M_C_CPU0_SB_CB<5>'
 '@T6G_MB_LIB.T6G(SCH_1):M_C_CPU0_SB_CB'<5>:
 C_SIGNAL='@t6g_mb_lib.t6g(sch_1):m_c_cpu0_sb_cb(5)';
NODE_NAME     U25 BU55
 '@T6G_MB_LIB.T6G(SCH_1):PAGE12_I159@PURE_QUANTA.GENOA_SP5(CHIPS)':
 'MCB_CHECK5': CDS_PINID='MCB_CHECK5';
NODE_NAME     J17 91
 '@T6G_MB_LIB.T6G(SCH_1):PAGE87_I350@PURE_QUANTA.SCONN288_DDR506112002KQ(CHIPS)':
 'CB5_B': CDS_PINID='CB5_B';
NET_NAME
'M_C_CPU0_SB_CB<6>'
 '@T6G_MB_LIB.T6G(SCH_1):M_C_CPU0_SB_CB'<6>:
 C_SIGNAL='@t6g_mb_lib.t6g(sch_1):m_c_cpu0_sb_cb(6)';
NODE_NAME     U25 BU57
 '@T6G_MB_LIB.T6G(SCH_1):PAGE12_I159@PURE_QUANTA.GENOA_SP5(CHIPS)':
 'MCB_CHECK6': CDS_PINID='MCB_CHECK6';
NODE_NAME     J17 234
 '@T6G_MB_LIB.T6G(SCH_1):PAGE87_I350@PURE_QUANTA.SCONN288_DDR506112002KQ(CHIPS)':
 'CB6_B': CDS_PINID='CB6_B';
NET_NAME
'M_C_CPU0_SB_CB<7>'
 '@T6G_MB_LIB.T6G(SCH_1):M_C_CPU0_SB_CB'<7>:
 C_SIGNAL='@t6g_mb_lib.t6g(sch_1):m_c_cpu0_sb_cb(7)';
NODE_NAME     U25 BV55
 '@T6G_MB_LIB.T6G(SCH_1):PAGE12_I159@PURE_QUANTA.GENOA_SP5(CHIPS)':
 'MCB_CHECK7': CDS_PINID='MCB_CHECK7';
NODE_NAME     J17 236
 '@T6G_MB_LIB.T6G(SCH_1):PAGE87_I350@PURE_QUANTA.SCONN288_DDR506112002KQ(CHIPS)':
 'CB7_B': CDS_PINID='CB7_B';
NET_NAME
'M_C_CPU0_SB_CS_N<0>'
 '@T6G_MB_LIB.T6G(SCH_1):M_C_CPU0_SB_CS_N'<0>:
 C_SIGNAL='@t6g_mb_lib.t6g(sch_1):m_c_cpu0_sb_cs_n(0)';
NODE_NAME     U25 BM55
 '@T6G_MB_LIB.T6G(SCH_1):PAGE12_I159@PURE_QUANTA.GENOA_SP5(CHIPS)':
 'MCB0_CS_L0': CDS_PINID='MCB0_CS_L0';
NODE_NAME     J17 84
 '@T6G_MB_LIB.T6G(SCH_1):PAGE87_I350@PURE_QUANTA.SCONN288_DDR506112002KQ(CHIPS)':
 'CS0_B_N': CDS_PINID='CS0_B_N';
NET_NAME
'M_C_CPU0_SB_CS_N<1>'
 '@T6G_MB_LIB.T6G(SCH_1):M_C_CPU0_SB_CS_N'<1>:
 C_SIGNAL='@t6g_mb_lib.t6g(sch_1):m_c_cpu0_sb_cs_n(1)';
NODE_NAME     U25 BN57
 '@T6G_MB_LIB.T6G(SCH_1):PAGE12_I159@PURE_QUANTA.GENOA_SP5(CHIPS)':
 'MCB0_CS_L1': CDS_PINID='MCB0_CS_L1';
NODE_NAME     J17 229
 '@T6G_MB_LIB.T6G(SCH_1):PAGE87_I350@PURE_QUANTA.SCONN288_DDR506112002KQ(CHIPS)':
 'CS1_B_N': CDS_PINID='CS1_B_N';
NET_NAME
'M_C_CPU0_SB_DQ<0>'
 '@T6G_MB_LIB.T6G(SCH_1):M_C_CPU0_SB_DQ'<0>:
 C_SIGNAL='@t6g_mb_lib.t6g(sch_1):m_c_cpu0_sb_dq(0)';
NODE_NAME     U25 CB56
 '@T6G_MB_LIB.T6G(SCH_1):PAGE12_I159@PURE_QUANTA.GENOA_SP5(CHIPS)':
 'MCB_DATA0': CDS_PINID='MCB_DATA0';
NODE_NAME     J17 100
 '@T6G_MB_LIB.T6G(SCH_1):PAGE87_I350@PURE_QUANTA.SCONN288_DDR506112002KQ(CHIPS)':
 'DQ0_B': CDS_PINID='DQ0_B';
NET_NAME
'M_C_CPU0_SB_DQ<10>'
 '@T6G_MB_LIB.T6G(SCH_1):M_C_CPU0_SB_DQ'<10>:
 C_SIGNAL='@t6g_mb_lib.t6g(sch_1):m_c_cpu0_sb_dq(10)';
NODE_NAME     U25 CJ57
 '@T6G_MB_LIB.T6G(SCH_1):PAGE12_I159@PURE_QUANTA.GENOA_SP5(CHIPS)':
 'MCB_DATA10': CDS_PINID='MCB_DATA10';
NODE_NAME     J17 256
 '@T6G_MB_LIB.T6G(SCH_1):PAGE87_I350@PURE_QUANTA.SCONN288_DDR506112002KQ(CHIPS)':
 'DQ10_B': CDS_PINID='DQ10_B';
NET_NAME
'M_C_CPU0_SB_DQ<11>'
 '@T6G_MB_LIB.T6G(SCH_1):M_C_CPU0_SB_DQ'<11>:
 C_SIGNAL='@t6g_mb_lib.t6g(sch_1):m_c_cpu0_sb_dq(11)';
NODE_NAME     U25 CK55
 '@T6G_MB_LIB.T6G(SCH_1):PAGE12_I159@PURE_QUANTA.GENOA_SP5(CHIPS)':
 'MCB_DATA11': CDS_PINID='MCB_DATA11';
NODE_NAME     J17 258
 '@T6G_MB_LIB.T6G(SCH_1):PAGE87_I350@PURE_QUANTA.SCONN288_DDR506112002KQ(CHIPS)':
 'DQ11_B': CDS_PINID='DQ11_B';
NET_NAME
'M_C_CPU0_SB_DQ<12>'
 '@T6G_MB_LIB.T6G(SCH_1):M_C_CPU0_SB_DQ'<12>:
 C_SIGNAL='@t6g_mb_lib.t6g(sch_1):m_c_cpu0_sb_dq(12)';
NODE_NAME     U25 CM56
 '@T6G_MB_LIB.T6G(SCH_1):PAGE12_I159@PURE_QUANTA.GENOA_SP5(CHIPS)':
 'MCB_DATA12': CDS_PINID='MCB_DATA12';
NODE_NAME     J17 118
 '@T6G_MB_LIB.T6G(SCH_1):PAGE87_I350@PURE_QUANTA.SCONN288_DDR506112002KQ(CHIPS)':
 'DQ12_B': CDS_PINID='DQ12_B';
NET_NAME
'M_C_CPU0_SB_DQ<13>'
 '@T6G_MB_LIB.T6G(SCH_1):M_C_CPU0_SB_DQ'<13>:
 C_SIGNAL='@t6g_mb_lib.t6g(sch_1):m_c_cpu0_sb_dq(13)';
NODE_NAME     U25 CN55
 '@T6G_MB_LIB.T6G(SCH_1):PAGE12_I159@PURE_QUANTA.GENOA_SP5(CHIPS)':
 'MCB_DATA13': CDS_PINID='MCB_DATA13';
NODE_NAME     J17 120
 '@T6G_MB_LIB.T6G(SCH_1):PAGE87_I350@PURE_QUANTA.SCONN288_DDR506112002KQ(CHIPS)':
 'DQ13_B': CDS_PINID='DQ13_B';
NET_NAME
'M_C_CPU0_SB_DQ<14>'
 '@T6G_MB_LIB.T6G(SCH_1):M_C_CPU0_SB_DQ'<14>:
 C_SIGNAL='@t6g_mb_lib.t6g(sch_1):m_c_cpu0_sb_dq(14)';
NODE_NAME     U25 CN57
 '@T6G_MB_LIB.T6G(SCH_1):PAGE12_I159@PURE_QUANTA.GENOA_SP5(CHIPS)':
 'MCB_DATA14': CDS_PINID='MCB_DATA14';
NODE_NAME     J17 263
 '@T6G_MB_LIB.T6G(SCH_1):PAGE87_I350@PURE_QUANTA.SCONN288_DDR506112002KQ(CHIPS)':
 'DQ14_B': CDS_PINID='DQ14_B';
NET_NAME
'M_C_CPU0_SB_DQ<15>'
 '@T6G_MB_LIB.T6G(SCH_1):M_C_CPU0_SB_DQ'<15>:
 C_SIGNAL='@t6g_mb_lib.t6g(sch_1):m_c_cpu0_sb_dq(15)';
NODE_NAME     U25 CP55
 '@T6G_MB_LIB.T6G(SCH_1):PAGE12_I159@PURE_QUANTA.GENOA_SP5(CHIPS)':
 'MCB_DATA15': CDS_PINID='MCB_DATA15';
NODE_NAME     J17 265
 '@T6G_MB_LIB.T6G(SCH_1):PAGE87_I350@PURE_QUANTA.SCONN288_DDR506112002KQ(CHIPS)':
 'DQ15_B': CDS_PINID='DQ15_B';
NET_NAME
'M_C_CPU0_SB_DQ<16>'
 '@T6G_MB_LIB.T6G(SCH_1):M_C_CPU0_SB_DQ'<16>:
 C_SIGNAL='@t6g_mb_lib.t6g(sch_1):m_c_cpu0_sb_dq(16)';
NODE_NAME     U25 CP56
 '@T6G_MB_LIB.T6G(SCH_1):PAGE12_I159@PURE_QUANTA.GENOA_SP5(CHIPS)':
 'MCB_DATA16': CDS_PINID='MCB_DATA16';
NODE_NAME     J17 122
 '@T6G_MB_LIB.T6G(SCH_1):PAGE87_I350@PURE_QUANTA.SCONN288_DDR506112002KQ(CHIPS)':
 'DQ16_B': CDS_PINID='DQ16_B';
NET_NAME
'M_C_CPU0_SB_DQ<17>'
 '@T6G_MB_LIB.T6G(SCH_1):M_C_CPU0_SB_DQ'<17>:
 C_SIGNAL='@t6g_mb_lib.t6g(sch_1):m_c_cpu0_sb_dq(17)';
NODE_NAME     U25 CR55
 '@T6G_MB_LIB.T6G(SCH_1):PAGE12_I159@PURE_QUANTA.GENOA_SP5(CHIPS)':
 'MCB_DATA17': CDS_PINID='MCB_DATA17';
NODE_NAME     J17 124
 '@T6G_MB_LIB.T6G(SCH_1):PAGE87_I350@PURE_QUANTA.SCONN288_DDR506112002KQ(CHIPS)':
 'DQ17_B': CDS_PINID='DQ17_B';
NET_NAME
'M_C_CPU0_SB_DQ<18>'
 '@T6G_MB_LIB.T6G(SCH_1):M_C_CPU0_SB_DQ'<18>:
 C_SIGNAL='@t6g_mb_lib.t6g(sch_1):m_c_cpu0_sb_dq(18)';
NODE_NAME     U25 CR57
 '@T6G_MB_LIB.T6G(SCH_1):PAGE12_I159@PURE_QUANTA.GENOA_SP5(CHIPS)':
 'MCB_DATA18': CDS_PINID='MCB_DATA18';
NODE_NAME     J17 267
 '@T6G_MB_LIB.T6G(SCH_1):PAGE87_I350@PURE_QUANTA.SCONN288_DDR506112002KQ(CHIPS)':
 'DQ18_B': CDS_PINID='DQ18_B';
NET_NAME
'M_C_CPU0_SB_DQ<19>'
 '@T6G_MB_LIB.T6G(SCH_1):M_C_CPU0_SB_DQ'<19>:
 C_SIGNAL='@t6g_mb_lib.t6g(sch_1):m_c_cpu0_sb_dq(19)';
NODE_NAME     U25 CT55
 '@T6G_MB_LIB.T6G(SCH_1):PAGE12_I159@PURE_QUANTA.GENOA_SP5(CHIPS)':
 'MCB_DATA19': CDS_PINID='MCB_DATA19';
NODE_NAME     J17 269
 '@T6G_MB_LIB.T6G(SCH_1):PAGE87_I350@PURE_QUANTA.SCONN288_DDR506112002KQ(CHIPS)':
 'DQ19_B': CDS_PINID='DQ19_B';
NET_NAME
'M_C_CPU0_SB_DQ<1>'
 '@T6G_MB_LIB.T6G(SCH_1):M_C_CPU0_SB_DQ'<1>:
 C_SIGNAL='@t6g_mb_lib.t6g(sch_1):m_c_cpu0_sb_dq(1)';
NODE_NAME     U25 CC55
 '@T6G_MB_LIB.T6G(SCH_1):PAGE12_I159@PURE_QUANTA.GENOA_SP5(CHIPS)':
 'MCB_DATA1': CDS_PINID='MCB_DATA1';
NODE_NAME     J17 102
 '@T6G_MB_LIB.T6G(SCH_1):PAGE87_I350@PURE_QUANTA.SCONN288_DDR506112002KQ(CHIPS)':
 'DQ1_B': CDS_PINID='DQ1_B';
NET_NAME
'M_C_CPU0_SB_DQ<20>'
 '@T6G_MB_LIB.T6G(SCH_1):M_C_CPU0_SB_DQ'<20>:
 C_SIGNAL='@t6g_mb_lib.t6g(sch_1):m_c_cpu0_sb_dq(20)';
NODE_NAME     U25 CV56
 '@T6G_MB_LIB.T6G(SCH_1):PAGE12_I159@PURE_QUANTA.GENOA_SP5(CHIPS)':
 'MCB_DATA20': CDS_PINID='MCB_DATA20';
NODE_NAME     J17 129
 '@T6G_MB_LIB.T6G(SCH_1):PAGE87_I350@PURE_QUANTA.SCONN288_DDR506112002KQ(CHIPS)':
 'DQ20_B': CDS_PINID='DQ20_B';
NET_NAME
'M_C_CPU0_SB_DQ<21>'
 '@T6G_MB_LIB.T6G(SCH_1):M_C_CPU0_SB_DQ'<21>:
 C_SIGNAL='@t6g_mb_lib.t6g(sch_1):m_c_cpu0_sb_dq(21)';
NODE_NAME     U25 CW55
 '@T6G_MB_LIB.T6G(SCH_1):PAGE12_I159@PURE_QUANTA.GENOA_SP5(CHIPS)':
 'MCB_DATA21': CDS_PINID='MCB_DATA21';
NODE_NAME     J17 131
 '@T6G_MB_LIB.T6G(SCH_1):PAGE87_I350@PURE_QUANTA.SCONN288_DDR506112002KQ(CHIPS)':
 'DQ21_B': CDS_PINID='DQ21_B';
NET_NAME
'M_C_CPU0_SB_DQ<22>'
 '@T6G_MB_LIB.T6G(SCH_1):M_C_CPU0_SB_DQ'<22>:
 C_SIGNAL='@t6g_mb_lib.t6g(sch_1):m_c_cpu0_sb_dq(22)';
NODE_NAME     U25 CW57
 '@T6G_MB_LIB.T6G(SCH_1):PAGE12_I159@PURE_QUANTA.GENOA_SP5(CHIPS)':
 'MCB_DATA22': CDS_PINID='MCB_DATA22';
NODE_NAME     J17 274
 '@T6G_MB_LIB.T6G(SCH_1):PAGE87_I350@PURE_QUANTA.SCONN288_DDR506112002KQ(CHIPS)':
 'DQ22_B': CDS_PINID='DQ22_B';
NET_NAME
'M_C_CPU0_SB_DQ<23>'
 '@T6G_MB_LIB.T6G(SCH_1):M_C_CPU0_SB_DQ'<23>:
 C_SIGNAL='@t6g_mb_lib.t6g(sch_1):m_c_cpu0_sb_dq(23)';
NODE_NAME     U25 CY55
 '@T6G_MB_LIB.T6G(SCH_1):PAGE12_I159@PURE_QUANTA.GENOA_SP5(CHIPS)':
 'MCB_DATA23': CDS_PINID='MCB_DATA23';
NODE_NAME     J17 276
 '@T6G_MB_LIB.T6G(SCH_1):PAGE87_I350@PURE_QUANTA.SCONN288_DDR506112002KQ(CHIPS)':
 'DQ23_B': CDS_PINID='DQ23_B';
NET_NAME
'M_C_CPU0_SB_DQ<24>'
 '@T6G_MB_LIB.T6G(SCH_1):M_C_CPU0_SB_DQ'<24>:
 C_SIGNAL='@t6g_mb_lib.t6g(sch_1):m_c_cpu0_sb_dq(24)';
NODE_NAME     U25 CY56
 '@T6G_MB_LIB.T6G(SCH_1):PAGE12_I159@PURE_QUANTA.GENOA_SP5(CHIPS)':
 'MCB_DATA24': CDS_PINID='MCB_DATA24';
NODE_NAME     J17 133
 '@T6G_MB_LIB.T6G(SCH_1):PAGE87_I350@PURE_QUANTA.SCONN288_DDR506112002KQ(CHIPS)':
 'DQ24_B': CDS_PINID='DQ24_B';
NET_NAME
'M_C_CPU0_SB_DQ<25>'
 '@T6G_MB_LIB.T6G(SCH_1):M_C_CPU0_SB_DQ'<25>:
 C_SIGNAL='@t6g_mb_lib.t6g(sch_1):m_c_cpu0_sb_dq(25)';
NODE_NAME     U25 DA55
 '@T6G_MB_LIB.T6G(SCH_1):PAGE12_I159@PURE_QUANTA.GENOA_SP5(CHIPS)':
 'MCB_DATA25': CDS_PINID='MCB_DATA25';
NODE_NAME     J17 135
 '@T6G_MB_LIB.T6G(SCH_1):PAGE87_I350@PURE_QUANTA.SCONN288_DDR506112002KQ(CHIPS)':
 'DQ25_B': CDS_PINID='DQ25_B';
NET_NAME
'M_C_CPU0_SB_DQ<26>'
 '@T6G_MB_LIB.T6G(SCH_1):M_C_CPU0_SB_DQ'<26>:
 C_SIGNAL='@t6g_mb_lib.t6g(sch_1):m_c_cpu0_sb_dq(26)';
NODE_NAME     U25 DA57
 '@T6G_MB_LIB.T6G(SCH_1):PAGE12_I159@PURE_QUANTA.GENOA_SP5(CHIPS)':
 'MCB_DATA26': CDS_PINID='MCB_DATA26';
NODE_NAME     J17 278
 '@T6G_MB_LIB.T6G(SCH_1):PAGE87_I350@PURE_QUANTA.SCONN288_DDR506112002KQ(CHIPS)':
 'DQ26_B': CDS_PINID='DQ26_B';
NET_NAME
'M_C_CPU0_SB_DQ<27>'
 '@T6G_MB_LIB.T6G(SCH_1):M_C_CPU0_SB_DQ'<27>:
 C_SIGNAL='@t6g_mb_lib.t6g(sch_1):m_c_cpu0_sb_dq(27)';
NODE_NAME     U25 DB55
 '@T6G_MB_LIB.T6G(SCH_1):PAGE12_I159@PURE_QUANTA.GENOA_SP5(CHIPS)':
 'MCB_DATA27': CDS_PINID='MCB_DATA27';
NODE_NAME     J17 280
 '@T6G_MB_LIB.T6G(SCH_1):PAGE87_I350@PURE_QUANTA.SCONN288_DDR506112002KQ(CHIPS)':
 'DQ27_B': CDS_PINID='DQ27_B';
NET_NAME
'M_C_CPU0_SB_DQ<28>'
 '@T6G_MB_LIB.T6G(SCH_1):M_C_CPU0_SB_DQ'<28>:
 C_SIGNAL='@t6g_mb_lib.t6g(sch_1):m_c_cpu0_sb_dq(28)';
NODE_NAME     U25 DD56
 '@T6G_MB_LIB.T6G(SCH_1):PAGE12_I159@PURE_QUANTA.GENOA_SP5(CHIPS)':
 'MCB_DATA28': CDS_PINID='MCB_DATA28';
NODE_NAME     J17 140
 '@T6G_MB_LIB.T6G(SCH_1):PAGE87_I350@PURE_QUANTA.SCONN288_DDR506112002KQ(CHIPS)':
 'DQ28_B': CDS_PINID='DQ28_B';
NET_NAME
'M_C_CPU0_SB_DQ<29>'
 '@T6G_MB_LIB.T6G(SCH_1):M_C_CPU0_SB_DQ'<29>:
 C_SIGNAL='@t6g_mb_lib.t6g(sch_1):m_c_cpu0_sb_dq(29)';
NODE_NAME     U25 DE55
 '@T6G_MB_LIB.T6G(SCH_1):PAGE12_I159@PURE_QUANTA.GENOA_SP5(CHIPS)':
 'MCB_DATA29': CDS_PINID='MCB_DATA29';
NODE_NAME     J17 142
 '@T6G_MB_LIB.T6G(SCH_1):PAGE87_I350@PURE_QUANTA.SCONN288_DDR506112002KQ(CHIPS)':
 'DQ29_B': CDS_PINID='DQ29_B';
NET_NAME
'M_C_CPU0_SB_DQ<2>'
 '@T6G_MB_LIB.T6G(SCH_1):M_C_CPU0_SB_DQ'<2>:
 C_SIGNAL='@t6g_mb_lib.t6g(sch_1):m_c_cpu0_sb_dq(2)';
NODE_NAME     U25 CC57
 '@T6G_MB_LIB.T6G(SCH_1):PAGE12_I159@PURE_QUANTA.GENOA_SP5(CHIPS)':
 'MCB_DATA2': CDS_PINID='MCB_DATA2';
NODE_NAME     J17 245
 '@T6G_MB_LIB.T6G(SCH_1):PAGE87_I350@PURE_QUANTA.SCONN288_DDR506112002KQ(CHIPS)':
 'DQ2_B': CDS_PINID='DQ2_B';
NET_NAME
'M_C_CPU0_SB_DQ<30>'
 '@T6G_MB_LIB.T6G(SCH_1):M_C_CPU0_SB_DQ'<30>:
 C_SIGNAL='@t6g_mb_lib.t6g(sch_1):m_c_cpu0_sb_dq(30)';
NODE_NAME     U25 DE57
 '@T6G_MB_LIB.T6G(SCH_1):PAGE12_I159@PURE_QUANTA.GENOA_SP5(CHIPS)':
 'MCB_DATA30': CDS_PINID='MCB_DATA30';
NODE_NAME     J17 285
 '@T6G_MB_LIB.T6G(SCH_1):PAGE87_I350@PURE_QUANTA.SCONN288_DDR506112002KQ(CHIPS)':
 'DQ30_B': CDS_PINID='DQ30_B';
NET_NAME
'M_C_CPU0_SB_DQ<31>'
 '@T6G_MB_LIB.T6G(SCH_1):M_C_CPU0_SB_DQ'<31>:
 C_SIGNAL='@t6g_mb_lib.t6g(sch_1):m_c_cpu0_sb_dq(31)';
NODE_NAME     U25 DF55
 '@T6G_MB_LIB.T6G(SCH_1):PAGE12_I159@PURE_QUANTA.GENOA_SP5(CHIPS)':
 'MCB_DATA31': CDS_PINID='MCB_DATA31';
NODE_NAME     J17 287
 '@T6G_MB_LIB.T6G(SCH_1):PAGE87_I350@PURE_QUANTA.SCONN288_DDR506112002KQ(CHIPS)':
 'DQ31_B': CDS_PINID='DQ31_B';
NET_NAME
'M_C_CPU0_SB_DQ<3>'
 '@T6G_MB_LIB.T6G(SCH_1):M_C_CPU0_SB_DQ'<3>:
 C_SIGNAL='@t6g_mb_lib.t6g(sch_1):m_c_cpu0_sb_dq(3)';
NODE_NAME     U25 CD55
 '@T6G_MB_LIB.T6G(SCH_1):PAGE12_I159@PURE_QUANTA.GENOA_SP5(CHIPS)':
 'MCB_DATA3': CDS_PINID='MCB_DATA3';
NODE_NAME     J17 247
 '@T6G_MB_LIB.T6G(SCH_1):PAGE87_I350@PURE_QUANTA.SCONN288_DDR506112002KQ(CHIPS)':
 'DQ3_B': CDS_PINID='DQ3_B';
NET_NAME
'M_C_CPU0_SB_DQ<4>'
 '@T6G_MB_LIB.T6G(SCH_1):M_C_CPU0_SB_DQ'<4>:
 C_SIGNAL='@t6g_mb_lib.t6g(sch_1):m_c_cpu0_sb_dq(4)';
NODE_NAME     U25 CF56
 '@T6G_MB_LIB.T6G(SCH_1):PAGE12_I159@PURE_QUANTA.GENOA_SP5(CHIPS)':
 'MCB_DATA4': CDS_PINID='MCB_DATA4';
NODE_NAME     J17 107
 '@T6G_MB_LIB.T6G(SCH_1):PAGE87_I350@PURE_QUANTA.SCONN288_DDR506112002KQ(CHIPS)':
 'DQ4_B': CDS_PINID='DQ4_B';
NET_NAME
'M_C_CPU0_SB_DQ<5>'
 '@T6G_MB_LIB.T6G(SCH_1):M_C_CPU0_SB_DQ'<5>:
 C_SIGNAL='@t6g_mb_lib.t6g(sch_1):m_c_cpu0_sb_dq(5)';
NODE_NAME     U25 CG55
 '@T6G_MB_LIB.T6G(SCH_1):PAGE12_I159@PURE_QUANTA.GENOA_SP5(CHIPS)':
 'MCB_DATA5': CDS_PINID='MCB_DATA5';
NODE_NAME     J17 109
 '@T6G_MB_LIB.T6G(SCH_1):PAGE87_I350@PURE_QUANTA.SCONN288_DDR506112002KQ(CHIPS)':
 'DQ5_B': CDS_PINID='DQ5_B';
NET_NAME
'M_C_CPU0_SB_DQ<6>'
 '@T6G_MB_LIB.T6G(SCH_1):M_C_CPU0_SB_DQ'<6>:
 C_SIGNAL='@t6g_mb_lib.t6g(sch_1):m_c_cpu0_sb_dq(6)';
NODE_NAME     U25 CG57
 '@T6G_MB_LIB.T6G(SCH_1):PAGE12_I159@PURE_QUANTA.GENOA_SP5(CHIPS)':
 'MCB_DATA6': CDS_PINID='MCB_DATA6';
NODE_NAME     J17 252
 '@T6G_MB_LIB.T6G(SCH_1):PAGE87_I350@PURE_QUANTA.SCONN288_DDR506112002KQ(CHIPS)':
 'DQ6_B': CDS_PINID='DQ6_B';
NET_NAME
'M_C_CPU0_SB_DQ<7>'
 '@T6G_MB_LIB.T6G(SCH_1):M_C_CPU0_SB_DQ'<7>:
 C_SIGNAL='@t6g_mb_lib.t6g(sch_1):m_c_cpu0_sb_dq(7)';
NODE_NAME     U25 CH55
 '@T6G_MB_LIB.T6G(SCH_1):PAGE12_I159@PURE_QUANTA.GENOA_SP5(CHIPS)':
 'MCB_DATA7': CDS_PINID='MCB_DATA7';
NODE_NAME     J17 254
 '@T6G_MB_LIB.T6G(SCH_1):PAGE87_I350@PURE_QUANTA.SCONN288_DDR506112002KQ(CHIPS)':
 'DQ7_B': CDS_PINID='DQ7_B';
NET_NAME
'M_C_CPU0_SB_DQ<8>'
 '@T6G_MB_LIB.T6G(SCH_1):M_C_CPU0_SB_DQ'<8>:
 C_SIGNAL='@t6g_mb_lib.t6g(sch_1):m_c_cpu0_sb_dq(8)';
NODE_NAME     U25 CH56
 '@T6G_MB_LIB.T6G(SCH_1):PAGE12_I159@PURE_QUANTA.GENOA_SP5(CHIPS)':
 'MCB_DATA8': CDS_PINID='MCB_DATA8';
NODE_NAME     J17 111
 '@T6G_MB_LIB.T6G(SCH_1):PAGE87_I350@PURE_QUANTA.SCONN288_DDR506112002KQ(CHIPS)':
 'DQ8_B': CDS_PINID='DQ8_B';
NET_NAME
'M_C_CPU0_SB_DQ<9>'
 '@T6G_MB_LIB.T6G(SCH_1):M_C_CPU0_SB_DQ'<9>:
 C_SIGNAL='@t6g_mb_lib.t6g(sch_1):m_c_cpu0_sb_dq(9)';
NODE_NAME     U25 CJ55
 '@T6G_MB_LIB.T6G(SCH_1):PAGE12_I159@PURE_QUANTA.GENOA_SP5(CHIPS)':
 'MCB_DATA9': CDS_PINID='MCB_DATA9';
NODE_NAME     J17 113
 '@T6G_MB_LIB.T6G(SCH_1):PAGE87_I350@PURE_QUANTA.SCONN288_DDR506112002KQ(CHIPS)':
 'DQ9_B': CDS_PINID='DQ9_B';
NET_NAME
'M_C_CPU0_SB_DQS_DN<0>'
 '@T6G_MB_LIB.T6G(SCH_1):M_C_CPU0_SB_DQS_DN'<0>:
 C_SIGNAL='@t6g_mb_lib.t6g(sch_1):m_c_cpu0_sb_dqs_dn(0)';
NODE_NAME     U25 CE57
 '@T6G_MB_LIB.T6G(SCH_1):PAGE12_I159@PURE_QUANTA.GENOA_SP5(CHIPS)':
 'MCB_DQS_L0': CDS_PINID='MCB_DQS_L0';
NODE_NAME     J17 105
 '@T6G_MB_LIB.T6G(SCH_1):PAGE87_I411@PURE_QUANTA.SCONN288_DDR506112002KQ(CHIPS)':
 'DQS0_B_C': CDS_PINID='DQS0_B_C';
NET_NAME
'M_C_CPU0_SB_DQS_DN<1>'
 '@T6G_MB_LIB.T6G(SCH_1):M_C_CPU0_SB_DQS_DN'<1>:
 C_SIGNAL='@t6g_mb_lib.t6g(sch_1):m_c_cpu0_sb_dqs_dn(1)';
NODE_NAME     U25 CL57
 '@T6G_MB_LIB.T6G(SCH_1):PAGE12_I159@PURE_QUANTA.GENOA_SP5(CHIPS)':
 'MCB_DQS_L1': CDS_PINID='MCB_DQS_L1';
NODE_NAME     J17 116
 '@T6G_MB_LIB.T6G(SCH_1):PAGE87_I411@PURE_QUANTA.SCONN288_DDR506112002KQ(CHIPS)':
 'DQS1_B_C': CDS_PINID='DQS1_B_C';
NET_NAME
'M_C_CPU0_SB_DQS_DN<2>'
 '@T6G_MB_LIB.T6G(SCH_1):M_C_CPU0_SB_DQS_DN'<2>:
 C_SIGNAL='@t6g_mb_lib.t6g(sch_1):m_c_cpu0_sb_dqs_dn(2)';
NODE_NAME     U25 CU57
 '@T6G_MB_LIB.T6G(SCH_1):PAGE12_I159@PURE_QUANTA.GENOA_SP5(CHIPS)':
 'MCB_DQS_L2': CDS_PINID='MCB_DQS_L2';
NODE_NAME     J17 127
 '@T6G_MB_LIB.T6G(SCH_1):PAGE87_I411@PURE_QUANTA.SCONN288_DDR506112002KQ(CHIPS)':
 'DQS2_B_C': CDS_PINID='DQS2_B_C';
NET_NAME
'M_C_CPU0_SB_DQS_DN<3>'
 '@T6G_MB_LIB.T6G(SCH_1):M_C_CPU0_SB_DQS_DN'<3>:
 C_SIGNAL='@t6g_mb_lib.t6g(sch_1):m_c_cpu0_sb_dqs_dn(3)';
NODE_NAME     U25 DC57
 '@T6G_MB_LIB.T6G(SCH_1):PAGE12_I159@PURE_QUANTA.GENOA_SP5(CHIPS)':
 'MCB_DQS_L3': CDS_PINID='MCB_DQS_L3';
NODE_NAME     J17 138
 '@T6G_MB_LIB.T6G(SCH_1):PAGE87_I411@PURE_QUANTA.SCONN288_DDR506112002KQ(CHIPS)':
 'DQS3_B_C': CDS_PINID='DQS3_B_C';
NET_NAME
'M_C_CPU0_SB_DQS_DN<4>'
 '@T6G_MB_LIB.T6G(SCH_1):M_C_CPU0_SB_DQS_DN'<4>:
 C_SIGNAL='@t6g_mb_lib.t6g(sch_1):m_c_cpu0_sb_dqs_dn(4)';
NODE_NAME     U25 BW55
 '@T6G_MB_LIB.T6G(SCH_1):PAGE12_I159@PURE_QUANTA.GENOA_SP5(CHIPS)':
 'MCB_DQS_L4': CDS_PINID='MCB_DQS_L4';
NODE_NAME     J17 238
 '@T6G_MB_LIB.T6G(SCH_1):PAGE87_I411@PURE_QUANTA.SCONN288_DDR506112002KQ(CHIPS)':
 'DQS4_B_C': CDS_PINID='DQS4_B_C';
NET_NAME
'M_C_CPU0_SB_DQS_DN<5>'
 '@T6G_MB_LIB.T6G(SCH_1):M_C_CPU0_SB_DQS_DN'<5>:
 C_SIGNAL='@t6g_mb_lib.t6g(sch_1):m_c_cpu0_sb_dqs_dn(5)';
NODE_NAME     U25 CE55
 '@T6G_MB_LIB.T6G(SCH_1):PAGE12_I159@PURE_QUANTA.GENOA_SP5(CHIPS)':
 'MCB_DQS_L5': CDS_PINID='MCB_DQS_L5';
NODE_NAME     J17 249
 '@T6G_MB_LIB.T6G(SCH_1):PAGE87_I411@PURE_QUANTA.SCONN288_DDR506112002KQ(CHIPS)':
 'DQS5_B_C||TDQS5_B_C': CDS_PINID='\dqs5_b_c||tdqs5_b_c\';
NET_NAME
'M_C_CPU0_SB_DQS_DN<6>'
 '@T6G_MB_LIB.T6G(SCH_1):M_C_CPU0_SB_DQS_DN'<6>:
 C_SIGNAL='@t6g_mb_lib.t6g(sch_1):m_c_cpu0_sb_dqs_dn(6)';
NODE_NAME     U25 CL55
 '@T6G_MB_LIB.T6G(SCH_1):PAGE12_I159@PURE_QUANTA.GENOA_SP5(CHIPS)':
 'MCB_DQS_L6': CDS_PINID='MCB_DQS_L6';
NODE_NAME     J17 260
 '@T6G_MB_LIB.T6G(SCH_1):PAGE87_I411@PURE_QUANTA.SCONN288_DDR506112002KQ(CHIPS)':
 'DQS6_B_C||TDQS6_B_C': CDS_PINID='\dqs6_b_c||tdqs6_b_c\';
NET_NAME
'M_C_CPU0_SB_DQS_DN<7>'
 '@T6G_MB_LIB.T6G(SCH_1):M_C_CPU0_SB_DQS_DN'<7>:
 C_SIGNAL='@t6g_mb_lib.t6g(sch_1):m_c_cpu0_sb_dqs_dn(7)';
NODE_NAME     U25 CU55
 '@T6G_MB_LIB.T6G(SCH_1):PAGE12_I159@PURE_QUANTA.GENOA_SP5(CHIPS)':
 'MCB_DQS_L7': CDS_PINID='MCB_DQS_L7';
NODE_NAME     J17 271
 '@T6G_MB_LIB.T6G(SCH_1):PAGE87_I411@PURE_QUANTA.SCONN288_DDR506112002KQ(CHIPS)':
 'DQS7_B_C||TDQS7_B_C': CDS_PINID='\dqs7_b_c||tdqs7_b_c\';
NET_NAME
'M_C_CPU0_SB_DQS_DN<8>'
 '@T6G_MB_LIB.T6G(SCH_1):M_C_CPU0_SB_DQS_DN'<8>:
 C_SIGNAL='@t6g_mb_lib.t6g(sch_1):m_c_cpu0_sb_dqs_dn(8)';
NODE_NAME     U25 DC55
 '@T6G_MB_LIB.T6G(SCH_1):PAGE12_I159@PURE_QUANTA.GENOA_SP5(CHIPS)':
 'MCB_DQS_L8': CDS_PINID='MCB_DQS_L8';
NODE_NAME     J17 282
 '@T6G_MB_LIB.T6G(SCH_1):PAGE87_I411@PURE_QUANTA.SCONN288_DDR506112002KQ(CHIPS)':
 'DQS8_B_C||TDQS8_B_C': CDS_PINID='\dqs8_b_c||tdqs8_b_c\';
NET_NAME
'M_C_CPU0_SB_DQS_DN<9>'
 '@T6G_MB_LIB.T6G(SCH_1):M_C_CPU0_SB_DQS_DN'<9>:
 C_SIGNAL='@t6g_mb_lib.t6g(sch_1):m_c_cpu0_sb_dqs_dn(9)';
NODE_NAME     U25 BW57
 '@T6G_MB_LIB.T6G(SCH_1):PAGE12_I159@PURE_QUANTA.GENOA_SP5(CHIPS)':
 'MCB_DQS_L9': CDS_PINID='MCB_DQS_L9';
NODE_NAME     J17 94
 '@T6G_MB_LIB.T6G(SCH_1):PAGE87_I411@PURE_QUANTA.SCONN288_DDR506112002KQ(CHIPS)':
 'DQS9_B_C||TDQS9_B_C': CDS_PINID='\dqs9_b_c||tdqs9_b_c\';
NET_NAME
'M_C_CPU0_SB_DQS_DP<0>'
 '@T6G_MB_LIB.T6G(SCH_1):M_C_CPU0_SB_DQS_DP'<0>:
 C_SIGNAL='@t6g_mb_lib.t6g(sch_1):m_c_cpu0_sb_dqs_dp(0)';
NODE_NAME     U25 CD56
 '@T6G_MB_LIB.T6G(SCH_1):PAGE12_I159@PURE_QUANTA.GENOA_SP5(CHIPS)':
 'MCB_DQS_H0': CDS_PINID='MCB_DQS_H0';
NODE_NAME     J17 104
 '@T6G_MB_LIB.T6G(SCH_1):PAGE87_I411@PURE_QUANTA.SCONN288_DDR506112002KQ(CHIPS)':
 'DQS0_B_T': CDS_PINID='DQS0_B_T';
NET_NAME
'M_C_CPU0_SB_DQS_DP<1>'
 '@T6G_MB_LIB.T6G(SCH_1):M_C_CPU0_SB_DQS_DP'<1>:
 C_SIGNAL='@t6g_mb_lib.t6g(sch_1):m_c_cpu0_sb_dqs_dp(1)';
NODE_NAME     U25 CK56
 '@T6G_MB_LIB.T6G(SCH_1):PAGE12_I159@PURE_QUANTA.GENOA_SP5(CHIPS)':
 'MCB_DQS_H1': CDS_PINID='MCB_DQS_H1';
NODE_NAME     J17 115
 '@T6G_MB_LIB.T6G(SCH_1):PAGE87_I411@PURE_QUANTA.SCONN288_DDR506112002KQ(CHIPS)':
 'DQS1_B_T': CDS_PINID='DQS1_B_T';
NET_NAME
'M_C_CPU0_SB_DQS_DP<2>'
 '@T6G_MB_LIB.T6G(SCH_1):M_C_CPU0_SB_DQS_DP'<2>:
 C_SIGNAL='@t6g_mb_lib.t6g(sch_1):m_c_cpu0_sb_dqs_dp(2)';
NODE_NAME     U25 CT56
 '@T6G_MB_LIB.T6G(SCH_1):PAGE12_I159@PURE_QUANTA.GENOA_SP5(CHIPS)':
 'MCB_DQS_H2': CDS_PINID='MCB_DQS_H2';
NODE_NAME     J17 126
 '@T6G_MB_LIB.T6G(SCH_1):PAGE87_I411@PURE_QUANTA.SCONN288_DDR506112002KQ(CHIPS)':
 'DQS2_B_T': CDS_PINID='DQS2_B_T';
NET_NAME
'M_C_CPU0_SB_DQS_DP<3>'
 '@T6G_MB_LIB.T6G(SCH_1):M_C_CPU0_SB_DQS_DP'<3>:
 C_SIGNAL='@t6g_mb_lib.t6g(sch_1):m_c_cpu0_sb_dqs_dp(3)';
NODE_NAME     U25 DB56
 '@T6G_MB_LIB.T6G(SCH_1):PAGE12_I159@PURE_QUANTA.GENOA_SP5(CHIPS)':
 'MCB_DQS_H3': CDS_PINID='MCB_DQS_H3';
NODE_NAME     J17 137
 '@T6G_MB_LIB.T6G(SCH_1):PAGE87_I411@PURE_QUANTA.SCONN288_DDR506112002KQ(CHIPS)':
 'DQS3_B_T': CDS_PINID='DQS3_B_T';
NET_NAME
'M_C_CPU0_SB_DQS_DP<4>'
 '@T6G_MB_LIB.T6G(SCH_1):M_C_CPU0_SB_DQS_DP'<4>:
 C_SIGNAL='@t6g_mb_lib.t6g(sch_1):m_c_cpu0_sb_dqs_dp(4)';
NODE_NAME     U25 BY55
 '@T6G_MB_LIB.T6G(SCH_1):PAGE12_I159@PURE_QUANTA.GENOA_SP5(CHIPS)':
 'MCB_DQS_H4': CDS_PINID='MCB_DQS_H4';
NODE_NAME     J17 239
 '@T6G_MB_LIB.T6G(SCH_1):PAGE87_I411@PURE_QUANTA.SCONN288_DDR506112002KQ(CHIPS)':
 'DQS4_B_T': CDS_PINID='DQS4_B_T';
NET_NAME
'M_C_CPU0_SB_DQS_DP<5>'
 '@T6G_MB_LIB.T6G(SCH_1):M_C_CPU0_SB_DQS_DP'<5>:
 C_SIGNAL='@t6g_mb_lib.t6g(sch_1):m_c_cpu0_sb_dqs_dp(5)';
NODE_NAME     U25 CF55
 '@T6G_MB_LIB.T6G(SCH_1):PAGE12_I159@PURE_QUANTA.GENOA_SP5(CHIPS)':
 'MCB_DQS_H5': CDS_PINID='MCB_DQS_H5';
NODE_NAME     J17 250
 '@T6G_MB_LIB.T6G(SCH_1):PAGE87_I411@PURE_QUANTA.SCONN288_DDR506112002KQ(CHIPS)':
 'DQS5_B_T||TDQS5_B_T': CDS_PINID='\dqs5_b_t||tdqs5_b_t\';
NET_NAME
'M_C_CPU0_SB_DQS_DP<6>'
 '@T6G_MB_LIB.T6G(SCH_1):M_C_CPU0_SB_DQS_DP'<6>:
 C_SIGNAL='@t6g_mb_lib.t6g(sch_1):m_c_cpu0_sb_dqs_dp(6)';
NODE_NAME     U25 CM55
 '@T6G_MB_LIB.T6G(SCH_1):PAGE12_I159@PURE_QUANTA.GENOA_SP5(CHIPS)':
 'MCB_DQS_H6': CDS_PINID='MCB_DQS_H6';
NODE_NAME     J17 261
 '@T6G_MB_LIB.T6G(SCH_1):PAGE87_I411@PURE_QUANTA.SCONN288_DDR506112002KQ(CHIPS)':
 'DQS6_B_T||TDQS6_B_T': CDS_PINID='\dqs6_b_t||tdqs6_b_t\';
NET_NAME
'M_C_CPU0_SB_DQS_DP<7>'
 '@T6G_MB_LIB.T6G(SCH_1):M_C_CPU0_SB_DQS_DP'<7>:
 C_SIGNAL='@t6g_mb_lib.t6g(sch_1):m_c_cpu0_sb_dqs_dp(7)';
NODE_NAME     U25 CV55
 '@T6G_MB_LIB.T6G(SCH_1):PAGE12_I159@PURE_QUANTA.GENOA_SP5(CHIPS)':
 'MCB_DQS_H7': CDS_PINID='MCB_DQS_H7';
NODE_NAME     J17 272
 '@T6G_MB_LIB.T6G(SCH_1):PAGE87_I411@PURE_QUANTA.SCONN288_DDR506112002KQ(CHIPS)':
 'DQS7_B_T||TDQS7_B_T': CDS_PINID='\dqs7_b_t||tdqs7_b_t\';
NET_NAME
'M_C_CPU0_SB_DQS_DP<8>'
 '@T6G_MB_LIB.T6G(SCH_1):M_C_CPU0_SB_DQS_DP'<8>:
 C_SIGNAL='@t6g_mb_lib.t6g(sch_1):m_c_cpu0_sb_dqs_dp(8)';
NODE_NAME     U25 DD55
 '@T6G_MB_LIB.T6G(SCH_1):PAGE12_I159@PURE_QUANTA.GENOA_SP5(CHIPS)':
 'MCB_DQS_H8': CDS_PINID='MCB_DQS_H8';
NODE_NAME     J17 283
 '@T6G_MB_LIB.T6G(SCH_1):PAGE87_I411@PURE_QUANTA.SCONN288_DDR506112002KQ(CHIPS)':
 'DQS8_B_T||TDQS8_B_T': CDS_PINID='\dqs8_b_t||tdqs8_b_t\';
NET_NAME
'M_C_CPU0_SB_DQS_DP<9>'
 '@T6G_MB_LIB.T6G(SCH_1):M_C_CPU0_SB_DQS_DP'<9>:
 C_SIGNAL='@t6g_mb_lib.t6g(sch_1):m_c_cpu0_sb_dqs_dp(9)';
NODE_NAME     U25 BV56
 '@T6G_MB_LIB.T6G(SCH_1):PAGE12_I159@PURE_QUANTA.GENOA_SP5(CHIPS)':
 'MCB_DQS_H9': CDS_PINID='MCB_DQS_H9';
NODE_NAME     J17 93
 '@T6G_MB_LIB.T6G(SCH_1):PAGE87_I411@PURE_QUANTA.SCONN288_DDR506112002KQ(CHIPS)':
 'DQS9_B_T||TDQS9_B_T||DBI4_B_N': CDS_PINID='\dqs9_b_t||tdqs9_b_t||dbi4_b_n\';
NET_NAME
'M_C_CPU0_SB_PAR'
 '@T6G_MB_LIB.T6G(SCH_1):M_C_CPU0_SB_PAR':
 C_SIGNAL='@t6g_mb_lib.t6g(sch_1):m_c_cpu0_sb_par';
NODE_NAME     U25 BL57
 '@T6G_MB_LIB.T6G(SCH_1):PAGE12_I159@PURE_QUANTA.GENOA_SP5(CHIPS)':
 'MCB_PAR': CDS_PINID='MCB_PAR';
NODE_NAME     J17 227
 '@T6G_MB_LIB.T6G(SCH_1):PAGE87_I350@PURE_QUANTA.SCONN288_DDR506112002KQ(CHIPS)':
 'PAR_B': CDS_PINID='PAR_B';
NET_NAME
'M_C_CPU0_SB_RSP<0>'
 '@T6G_MB_LIB.T6G(SCH_1):M_C_CPU0_SB_RSP'<0>:
 C_SIGNAL='@t6g_mb_lib.t6g(sch_1):m_c_cpu0_sb_rsp(0)';
NODE_NAME     U25 BP56
 '@T6G_MB_LIB.T6G(SCH_1):PAGE12_I159@PURE_QUANTA.GENOA_SP5(CHIPS)':
 'MCB0_RSP_L': CDS_PINID='MCB0_RSP_L';
NODE_NAME     J17 87
 '@T6G_MB_LIB.T6G(SCH_1):PAGE87_I350@PURE_QUANTA.SCONN288_DDR506112002KQ(CHIPS)':
 'LBS||RSP_B_N': CDS_PINID='\lbs||rsp_b_n\';
NET_NAME
'M_C_CPU1_ALERT_N'
 '@T6G_MB_LIB.T6G(SCH_1):M_C_CPU1_ALERT_N':
 C_SIGNAL='@t6g_mb_lib.t6g(sch_1):m_c_cpu1_alert_n';
NODE_NAME     R502 1
 '@T6G_MB_LIB.T6G(SCH_1):PAGE39_I313@PURE_QUANTA.Q_RES(CHIPS)':
 'A': CDS_PINID='A';
NODE_NAME     J28 62
 '@T6G_MB_LIB.T6G(SCH_1):PAGE99_I22@PURE_QUANTA.SCONN288_DDR506112002KQ(CHIPS)':
 'ALERT_N': CDS_PINID='ALERT_N';
NET_NAME
'M_C_CPU1_ALERT_R_N'
 '@T6G_MB_LIB.T6G(SCH_1):M_C_CPU1_ALERT_R_N':
 C_SIGNAL='@t6g_mb_lib.t6g(sch_1):m_c_cpu1_alert_r_n';
NODE_NAME     U26 AT55
 '@T6G_MB_LIB.T6G(SCH_1):PAGE39_I159@PURE_QUANTA.GENOA_SP5(CHIPS)':
 'MC_ALERT_L': CDS_PINID='MC_ALERT_L';
NODE_NAME     R502 2
 '@T6G_MB_LIB.T6G(SCH_1):PAGE39_I313@PURE_QUANTA.Q_RES(CHIPS)':
 'B': CDS_PINID='B';
NET_NAME
'M_C_CPU1_CLK_DN<0>'
 '@T6G_MB_LIB.T6G(SCH_1):M_C_CPU1_CLK_DN'<0>:
 C_SIGNAL='@t6g_mb_lib.t6g(sch_1):m_c_cpu1_clk_dn(0)';
NODE_NAME     U26 BD56
 '@T6G_MB_LIB.T6G(SCH_1):PAGE39_I159@PURE_QUANTA.GENOA_SP5(CHIPS)':
 'MC0_CLK_L': CDS_PINID='MC0_CLK_L';
NODE_NAME     J28 218
 '@T6G_MB_LIB.T6G(SCH_1):PAGE99_I22@PURE_QUANTA.SCONN288_DDR506112002KQ(CHIPS)':
 'CK_C': CDS_PINID='CK_C';
NET_NAME
'M_C_CPU1_CLK_DP<0>'
 '@T6G_MB_LIB.T6G(SCH_1):M_C_CPU1_CLK_DP'<0>:
 C_SIGNAL='@t6g_mb_lib.t6g(sch_1):m_c_cpu1_clk_dp(0)';
NODE_NAME     U26 BC57
 '@T6G_MB_LIB.T6G(SCH_1):PAGE39_I159@PURE_QUANTA.GENOA_SP5(CHIPS)':
 'MC0_CLK_H': CDS_PINID='MC0_CLK_H';
NODE_NAME     J28 217
 '@T6G_MB_LIB.T6G(SCH_1):PAGE99_I22@PURE_QUANTA.SCONN288_DDR506112002KQ(CHIPS)':
 'CK_T': CDS_PINID='CK_T';
NET_NAME
'M_C_CPU1_RESET_N'
 '@T6G_MB_LIB.T6G(SCH_1):M_C_CPU1_RESET_N':
 C_SIGNAL='@t6g_mb_lib.t6g(sch_1):m_c_cpu1_reset_n';
NODE_NAME     U26 AU55
 '@T6G_MB_LIB.T6G(SCH_1):PAGE39_I159@PURE_QUANTA.GENOA_SP5(CHIPS)':
 'MC_RESET_L': CDS_PINID='MC_RESET_L';
NODE_NAME     J28 207
 '@T6G_MB_LIB.T6G(SCH_1):PAGE99_I22@PURE_QUANTA.SCONN288_DDR506112002KQ(CHIPS)':
 'RESET_N': CDS_PINID='RESET_N';
NET_NAME
'M_C_CPU1_SA_CA<0>'
 '@T6G_MB_LIB.T6G(SCH_1):M_C_CPU1_SA_CA'<0>:
 C_SIGNAL='@t6g_mb_lib.t6g(sch_1):m_c_cpu1_sa_ca(0)';
NODE_NAME     U26 AW57
 '@T6G_MB_LIB.T6G(SCH_1):PAGE39_I159@PURE_QUANTA.GENOA_SP5(CHIPS)':
 'MCA_CA0': CDS_PINID='MCA_CA0';
NODE_NAME     J28 66
 '@T6G_MB_LIB.T6G(SCH_1):PAGE99_I22@PURE_QUANTA.SCONN288_DDR506112002KQ(CHIPS)':
 'CA0_A': CDS_PINID='CA0_A';
NET_NAME
'M_C_CPU1_SA_CA<1>'
 '@T6G_MB_LIB.T6G(SCH_1):M_C_CPU1_SA_CA'<1>:
 C_SIGNAL='@t6g_mb_lib.t6g(sch_1):m_c_cpu1_sa_ca(1)';
NODE_NAME     U26 AY56
 '@T6G_MB_LIB.T6G(SCH_1):PAGE39_I159@PURE_QUANTA.GENOA_SP5(CHIPS)':
 'MCA_CA1': CDS_PINID='MCA_CA1';
NODE_NAME     J28 211
 '@T6G_MB_LIB.T6G(SCH_1):PAGE99_I22@PURE_QUANTA.SCONN288_DDR506112002KQ(CHIPS)':
 'CA1_A': CDS_PINID='CA1_A';
NET_NAME
'M_C_CPU1_SA_CA<2>'
 '@T6G_MB_LIB.T6G(SCH_1):M_C_CPU1_SA_CA'<2>:
 C_SIGNAL='@t6g_mb_lib.t6g(sch_1):m_c_cpu1_sa_ca(2)';
NODE_NAME     U26 AY55
 '@T6G_MB_LIB.T6G(SCH_1):PAGE39_I159@PURE_QUANTA.GENOA_SP5(CHIPS)':
 'MCA_CA2': CDS_PINID='MCA_CA2';
NODE_NAME     J28 68
 '@T6G_MB_LIB.T6G(SCH_1):PAGE99_I22@PURE_QUANTA.SCONN288_DDR506112002KQ(CHIPS)':
 'CA2_A': CDS_PINID='CA2_A';
NET_NAME
'M_C_CPU1_SA_CA<3>'
 '@T6G_MB_LIB.T6G(SCH_1):M_C_CPU1_SA_CA'<3>:
 C_SIGNAL='@t6g_mb_lib.t6g(sch_1):m_c_cpu1_sa_ca(3)';
NODE_NAME     U26 BA55
 '@T6G_MB_LIB.T6G(SCH_1):PAGE39_I159@PURE_QUANTA.GENOA_SP5(CHIPS)':
 'MCA_CA3': CDS_PINID='MCA_CA3';
NODE_NAME     J28 213
 '@T6G_MB_LIB.T6G(SCH_1):PAGE99_I22@PURE_QUANTA.SCONN288_DDR506112002KQ(CHIPS)':
 'CA3_A': CDS_PINID='CA3_A';
NET_NAME
'M_C_CPU1_SA_CA<4>'
 '@T6G_MB_LIB.T6G(SCH_1):M_C_CPU1_SA_CA'<4>:
 C_SIGNAL='@t6g_mb_lib.t6g(sch_1):m_c_cpu1_sa_ca(4)';
NODE_NAME     U26 BA57
 '@T6G_MB_LIB.T6G(SCH_1):PAGE39_I159@PURE_QUANTA.GENOA_SP5(CHIPS)':
 'MCA_CA4': CDS_PINID='MCA_CA4';
NODE_NAME     J28 70
 '@T6G_MB_LIB.T6G(SCH_1):PAGE99_I22@PURE_QUANTA.SCONN288_DDR506112002KQ(CHIPS)':
 'CA4_A': CDS_PINID='CA4_A';
NET_NAME
'M_C_CPU1_SA_CA<5>'
 '@T6G_MB_LIB.T6G(SCH_1):M_C_CPU1_SA_CA'<5>:
 C_SIGNAL='@t6g_mb_lib.t6g(sch_1):m_c_cpu1_sa_ca(5)';
NODE_NAME     U26 BB56
 '@T6G_MB_LIB.T6G(SCH_1):PAGE39_I159@PURE_QUANTA.GENOA_SP5(CHIPS)':
 'MCA_CA5': CDS_PINID='MCA_CA5';
NODE_NAME     J28 215
 '@T6G_MB_LIB.T6G(SCH_1):PAGE99_I22@PURE_QUANTA.SCONN288_DDR506112002KQ(CHIPS)':
 'CA5_A': CDS_PINID='CA5_A';
NET_NAME
'M_C_CPU1_SA_CA<6>'
 '@T6G_MB_LIB.T6G(SCH_1):M_C_CPU1_SA_CA'<6>:
 C_SIGNAL='@t6g_mb_lib.t6g(sch_1):m_c_cpu1_sa_ca(6)';
NODE_NAME     U26 BB55
 '@T6G_MB_LIB.T6G(SCH_1):PAGE39_I159@PURE_QUANTA.GENOA_SP5(CHIPS)':
 'MCA_CA6': CDS_PINID='MCA_CA6';
NODE_NAME     J28 72
 '@T6G_MB_LIB.T6G(SCH_1):PAGE99_I22@PURE_QUANTA.SCONN288_DDR506112002KQ(CHIPS)':
 'CA6_A': CDS_PINID='CA6_A';
NET_NAME
'M_C_CPU1_SA_CB<0>'
 '@T6G_MB_LIB.T6G(SCH_1):M_C_CPU1_SA_CB'<0>:
 C_SIGNAL='@t6g_mb_lib.t6g(sch_1):m_c_cpu1_sa_cb(0)';
NODE_NAME     U26 AJ57
 '@T6G_MB_LIB.T6G(SCH_1):PAGE39_I159@PURE_QUANTA.GENOA_SP5(CHIPS)':
 'MCA_CHECK0': CDS_PINID='MCA_CHECK0';
NODE_NAME     J28 51
 '@T6G_MB_LIB.T6G(SCH_1):PAGE99_I22@PURE_QUANTA.SCONN288_DDR506112002KQ(CHIPS)':
 'CB0_A': CDS_PINID='CB0_A';
NET_NAME
'M_C_CPU1_SA_CB<1>'
 '@T6G_MB_LIB.T6G(SCH_1):M_C_CPU1_SA_CB'<1>:
 C_SIGNAL='@t6g_mb_lib.t6g(sch_1):m_c_cpu1_sa_cb(1)';
NODE_NAME     U26 AK55
 '@T6G_MB_LIB.T6G(SCH_1):PAGE39_I159@PURE_QUANTA.GENOA_SP5(CHIPS)':
 'MCA_CHECK1': CDS_PINID='MCA_CHECK1';
NODE_NAME     J28 53
 '@T6G_MB_LIB.T6G(SCH_1):PAGE99_I22@PURE_QUANTA.SCONN288_DDR506112002KQ(CHIPS)':
 'CB1_A': CDS_PINID='CB1_A';
NET_NAME
'M_C_CPU1_SA_CB<2>'
 '@T6G_MB_LIB.T6G(SCH_1):M_C_CPU1_SA_CB'<2>:
 C_SIGNAL='@t6g_mb_lib.t6g(sch_1):m_c_cpu1_sa_cb(2)';
NODE_NAME     U26 AK56
 '@T6G_MB_LIB.T6G(SCH_1):PAGE39_I159@PURE_QUANTA.GENOA_SP5(CHIPS)':
 'MCA_CHECK2': CDS_PINID='MCA_CHECK2';
NODE_NAME     J28 196
 '@T6G_MB_LIB.T6G(SCH_1):PAGE99_I22@PURE_QUANTA.SCONN288_DDR506112002KQ(CHIPS)':
 'CB2_A': CDS_PINID='CB2_A';
NET_NAME
'M_C_CPU1_SA_CB<3>'
 '@T6G_MB_LIB.T6G(SCH_1):M_C_CPU1_SA_CB'<3>:
 C_SIGNAL='@t6g_mb_lib.t6g(sch_1):m_c_cpu1_sa_cb(3)';
NODE_NAME     U26 AL55
 '@T6G_MB_LIB.T6G(SCH_1):PAGE39_I159@PURE_QUANTA.GENOA_SP5(CHIPS)':
 'MCA_CHECK3': CDS_PINID='MCA_CHECK3';
NODE_NAME     J28 198
 '@T6G_MB_LIB.T6G(SCH_1):PAGE99_I22@PURE_QUANTA.SCONN288_DDR506112002KQ(CHIPS)':
 'CB3_A': CDS_PINID='CB3_A';
NET_NAME
'M_C_CPU1_SA_CB<4>'
 '@T6G_MB_LIB.T6G(SCH_1):M_C_CPU1_SA_CB'<4>:
 C_SIGNAL='@t6g_mb_lib.t6g(sch_1):m_c_cpu1_sa_cb(4)';
NODE_NAME     U26 AN57
 '@T6G_MB_LIB.T6G(SCH_1):PAGE39_I159@PURE_QUANTA.GENOA_SP5(CHIPS)':
 'MCA_CHECK4': CDS_PINID='MCA_CHECK4';
NODE_NAME     J28 58
 '@T6G_MB_LIB.T6G(SCH_1):PAGE99_I22@PURE_QUANTA.SCONN288_DDR506112002KQ(CHIPS)':
 'CB4_A': CDS_PINID='CB4_A';
NET_NAME
'M_C_CPU1_SA_CB<5>'
 '@T6G_MB_LIB.T6G(SCH_1):M_C_CPU1_SA_CB'<5>:
 C_SIGNAL='@t6g_mb_lib.t6g(sch_1):m_c_cpu1_sa_cb(5)';
NODE_NAME     U26 AP55
 '@T6G_MB_LIB.T6G(SCH_1):PAGE39_I159@PURE_QUANTA.GENOA_SP5(CHIPS)':
 'MCA_CHECK5': CDS_PINID='MCA_CHECK5';
NODE_NAME     J28 60
 '@T6G_MB_LIB.T6G(SCH_1):PAGE99_I22@PURE_QUANTA.SCONN288_DDR506112002KQ(CHIPS)':
 'CB5_A': CDS_PINID='CB5_A';
NET_NAME
'M_C_CPU1_SA_CB<6>'
 '@T6G_MB_LIB.T6G(SCH_1):M_C_CPU1_SA_CB'<6>:
 C_SIGNAL='@t6g_mb_lib.t6g(sch_1):m_c_cpu1_sa_cb(6)';
NODE_NAME     U26 AP56
 '@T6G_MB_LIB.T6G(SCH_1):PAGE39_I159@PURE_QUANTA.GENOA_SP5(CHIPS)':
 'MCA_CHECK6': CDS_PINID='MCA_CHECK6';
NODE_NAME     J28 203
 '@T6G_MB_LIB.T6G(SCH_1):PAGE99_I22@PURE_QUANTA.SCONN288_DDR506112002KQ(CHIPS)':
 'CB6_A': CDS_PINID='CB6_A';
NET_NAME
'M_C_CPU1_SA_CB<7>'
 '@T6G_MB_LIB.T6G(SCH_1):M_C_CPU1_SA_CB'<7>:
 C_SIGNAL='@t6g_mb_lib.t6g(sch_1):m_c_cpu1_sa_cb(7)';
NODE_NAME     U26 AR55
 '@T6G_MB_LIB.T6G(SCH_1):PAGE39_I159@PURE_QUANTA.GENOA_SP5(CHIPS)':
 'MCA_CHECK7': CDS_PINID='MCA_CHECK7';
NODE_NAME     J28 205
 '@T6G_MB_LIB.T6G(SCH_1):PAGE99_I22@PURE_QUANTA.SCONN288_DDR506112002KQ(CHIPS)':
 'CB7_A': CDS_PINID='CB7_A';
NET_NAME
'M_C_CPU1_SA_CS_N<0>'
 '@T6G_MB_LIB.T6G(SCH_1):M_C_CPU1_SA_CS_N'<0>:
 C_SIGNAL='@t6g_mb_lib.t6g(sch_1):m_c_cpu1_sa_cs_n(0)';
NODE_NAME     U26 AV56
 '@T6G_MB_LIB.T6G(SCH_1):PAGE39_I159@PURE_QUANTA.GENOA_SP5(CHIPS)':
 'MCA0_CS_L0': CDS_PINID='MCA0_CS_L0';
NODE_NAME     J28 64
 '@T6G_MB_LIB.T6G(SCH_1):PAGE99_I22@PURE_QUANTA.SCONN288_DDR506112002KQ(CHIPS)':
 'CS0_A_N': CDS_PINID='CS0_A_N';
NET_NAME
'M_C_CPU1_SA_CS_N<1>'
 '@T6G_MB_LIB.T6G(SCH_1):M_C_CPU1_SA_CS_N'<1>:
 C_SIGNAL='@t6g_mb_lib.t6g(sch_1):m_c_cpu1_sa_cs_n(1)';
NODE_NAME     U26 AW55
 '@T6G_MB_LIB.T6G(SCH_1):PAGE39_I159@PURE_QUANTA.GENOA_SP5(CHIPS)':
 'MCA0_CS_L1': CDS_PINID='MCA0_CS_L1';
NODE_NAME     J28 209
 '@T6G_MB_LIB.T6G(SCH_1):PAGE99_I22@PURE_QUANTA.SCONN288_DDR506112002KQ(CHIPS)':
 'CS1_A_N': CDS_PINID='CS1_A_N';
NET_NAME
'M_C_CPU1_SA_DQ<0>'
 '@T6G_MB_LIB.T6G(SCH_1):M_C_CPU1_SA_DQ'<0>:
 C_SIGNAL='@t6g_mb_lib.t6g(sch_1):m_c_cpu1_sa_dq(0)';
NODE_NAME     U26 E57
 '@T6G_MB_LIB.T6G(SCH_1):PAGE39_I159@PURE_QUANTA.GENOA_SP5(CHIPS)':
 'MCA_DATA0': CDS_PINID='MCA_DATA0';
NODE_NAME     J28 7
 '@T6G_MB_LIB.T6G(SCH_1):PAGE99_I22@PURE_QUANTA.SCONN288_DDR506112002KQ(CHIPS)':
 'DQ0_A': CDS_PINID='DQ0_A';
NET_NAME
'M_C_CPU1_SA_DQ<10>'
 '@T6G_MB_LIB.T6G(SCH_1):M_C_CPU1_SA_DQ'<10>:
 C_SIGNAL='@t6g_mb_lib.t6g(sch_1):m_c_cpu1_sa_dq(10)';
NODE_NAME     U26 M56
 '@T6G_MB_LIB.T6G(SCH_1):PAGE39_I159@PURE_QUANTA.GENOA_SP5(CHIPS)':
 'MCA_DATA10': CDS_PINID='MCA_DATA10';
NODE_NAME     J28 163
 '@T6G_MB_LIB.T6G(SCH_1):PAGE99_I22@PURE_QUANTA.SCONN288_DDR506112002KQ(CHIPS)':
 'DQ10_A': CDS_PINID='DQ10_A';
NET_NAME
'M_C_CPU1_SA_DQ<11>'
 '@T6G_MB_LIB.T6G(SCH_1):M_C_CPU1_SA_DQ'<11>:
 C_SIGNAL='@t6g_mb_lib.t6g(sch_1):m_c_cpu1_sa_dq(11)';
NODE_NAME     U26 N55
 '@T6G_MB_LIB.T6G(SCH_1):PAGE39_I159@PURE_QUANTA.GENOA_SP5(CHIPS)':
 'MCA_DATA11': CDS_PINID='MCA_DATA11';
NODE_NAME     J28 165
 '@T6G_MB_LIB.T6G(SCH_1):PAGE99_I22@PURE_QUANTA.SCONN288_DDR506112002KQ(CHIPS)':
 'DQ11_A': CDS_PINID='DQ11_A';
NET_NAME
'M_C_CPU1_SA_DQ<12>'
 '@T6G_MB_LIB.T6G(SCH_1):M_C_CPU1_SA_DQ'<12>:
 C_SIGNAL='@t6g_mb_lib.t6g(sch_1):m_c_cpu1_sa_dq(12)';
NODE_NAME     U26 R57
 '@T6G_MB_LIB.T6G(SCH_1):PAGE39_I159@PURE_QUANTA.GENOA_SP5(CHIPS)':
 'MCA_DATA12': CDS_PINID='MCA_DATA12';
NODE_NAME     J28 25
 '@T6G_MB_LIB.T6G(SCH_1):PAGE99_I22@PURE_QUANTA.SCONN288_DDR506112002KQ(CHIPS)':
 'DQ12_A': CDS_PINID='DQ12_A';
NET_NAME
'M_C_CPU1_SA_DQ<13>'
 '@T6G_MB_LIB.T6G(SCH_1):M_C_CPU1_SA_DQ'<13>:
 C_SIGNAL='@t6g_mb_lib.t6g(sch_1):m_c_cpu1_sa_dq(13)';
NODE_NAME     U26 T55
 '@T6G_MB_LIB.T6G(SCH_1):PAGE39_I159@PURE_QUANTA.GENOA_SP5(CHIPS)':
 'MCA_DATA13': CDS_PINID='MCA_DATA13';
NODE_NAME     J28 27
 '@T6G_MB_LIB.T6G(SCH_1):PAGE99_I22@PURE_QUANTA.SCONN288_DDR506112002KQ(CHIPS)':
 'DQ13_A': CDS_PINID='DQ13_A';
NET_NAME
'M_C_CPU1_SA_DQ<14>'
 '@T6G_MB_LIB.T6G(SCH_1):M_C_CPU1_SA_DQ'<14>:
 C_SIGNAL='@t6g_mb_lib.t6g(sch_1):m_c_cpu1_sa_dq(14)';
NODE_NAME     U26 T56
 '@T6G_MB_LIB.T6G(SCH_1):PAGE39_I159@PURE_QUANTA.GENOA_SP5(CHIPS)':
 'MCA_DATA14': CDS_PINID='MCA_DATA14';
NODE_NAME     J28 170
 '@T6G_MB_LIB.T6G(SCH_1):PAGE99_I22@PURE_QUANTA.SCONN288_DDR506112002KQ(CHIPS)':
 'DQ14_A': CDS_PINID='DQ14_A';
NET_NAME
'M_C_CPU1_SA_DQ<15>'
 '@T6G_MB_LIB.T6G(SCH_1):M_C_CPU1_SA_DQ'<15>:
 C_SIGNAL='@t6g_mb_lib.t6g(sch_1):m_c_cpu1_sa_dq(15)';
NODE_NAME     U26 U55
 '@T6G_MB_LIB.T6G(SCH_1):PAGE39_I159@PURE_QUANTA.GENOA_SP5(CHIPS)':
 'MCA_DATA15': CDS_PINID='MCA_DATA15';
NODE_NAME     J28 172
 '@T6G_MB_LIB.T6G(SCH_1):PAGE99_I22@PURE_QUANTA.SCONN288_DDR506112002KQ(CHIPS)':
 'DQ15_A': CDS_PINID='DQ15_A';
NET_NAME
'M_C_CPU1_SA_DQ<16>'
 '@T6G_MB_LIB.T6G(SCH_1):M_C_CPU1_SA_DQ'<16>:
 C_SIGNAL='@t6g_mb_lib.t6g(sch_1):m_c_cpu1_sa_dq(16)';
NODE_NAME     U26 U57
 '@T6G_MB_LIB.T6G(SCH_1):PAGE39_I159@PURE_QUANTA.GENOA_SP5(CHIPS)':
 'MCA_DATA16': CDS_PINID='MCA_DATA16';
NODE_NAME     J28 29
 '@T6G_MB_LIB.T6G(SCH_1):PAGE99_I22@PURE_QUANTA.SCONN288_DDR506112002KQ(CHIPS)':
 'DQ16_A': CDS_PINID='DQ16_A';
NET_NAME
'M_C_CPU1_SA_DQ<17>'
 '@T6G_MB_LIB.T6G(SCH_1):M_C_CPU1_SA_DQ'<17>:
 C_SIGNAL='@t6g_mb_lib.t6g(sch_1):m_c_cpu1_sa_dq(17)';
NODE_NAME     U26 V55
 '@T6G_MB_LIB.T6G(SCH_1):PAGE39_I159@PURE_QUANTA.GENOA_SP5(CHIPS)':
 'MCA_DATA17': CDS_PINID='MCA_DATA17';
NODE_NAME     J28 31
 '@T6G_MB_LIB.T6G(SCH_1):PAGE99_I22@PURE_QUANTA.SCONN288_DDR506112002KQ(CHIPS)':
 'DQ17_A': CDS_PINID='DQ17_A';
NET_NAME
'M_C_CPU1_SA_DQ<18>'
 '@T6G_MB_LIB.T6G(SCH_1):M_C_CPU1_SA_DQ'<18>:
 C_SIGNAL='@t6g_mb_lib.t6g(sch_1):m_c_cpu1_sa_dq(18)';
NODE_NAME     U26 V56
 '@T6G_MB_LIB.T6G(SCH_1):PAGE39_I159@PURE_QUANTA.GENOA_SP5(CHIPS)':
 'MCA_DATA18': CDS_PINID='MCA_DATA18';
NODE_NAME     J28 174
 '@T6G_MB_LIB.T6G(SCH_1):PAGE99_I22@PURE_QUANTA.SCONN288_DDR506112002KQ(CHIPS)':
 'DQ18_A': CDS_PINID='DQ18_A';
NET_NAME
'M_C_CPU1_SA_DQ<19>'
 '@T6G_MB_LIB.T6G(SCH_1):M_C_CPU1_SA_DQ'<19>:
 C_SIGNAL='@t6g_mb_lib.t6g(sch_1):m_c_cpu1_sa_dq(19)';
NODE_NAME     U26 W55
 '@T6G_MB_LIB.T6G(SCH_1):PAGE39_I159@PURE_QUANTA.GENOA_SP5(CHIPS)':
 'MCA_DATA19': CDS_PINID='MCA_DATA19';
NODE_NAME     J28 176
 '@T6G_MB_LIB.T6G(SCH_1):PAGE99_I22@PURE_QUANTA.SCONN288_DDR506112002KQ(CHIPS)':
 'DQ19_A': CDS_PINID='DQ19_A';
NET_NAME
'M_C_CPU1_SA_DQ<1>'
 '@T6G_MB_LIB.T6G(SCH_1):M_C_CPU1_SA_DQ'<1>:
 C_SIGNAL='@t6g_mb_lib.t6g(sch_1):m_c_cpu1_sa_dq(1)';
NODE_NAME     U26 F55
 '@T6G_MB_LIB.T6G(SCH_1):PAGE39_I159@PURE_QUANTA.GENOA_SP5(CHIPS)':
 'MCA_DATA1': CDS_PINID='MCA_DATA1';
NODE_NAME     J28 9
 '@T6G_MB_LIB.T6G(SCH_1):PAGE99_I22@PURE_QUANTA.SCONN288_DDR506112002KQ(CHIPS)':
 'DQ1_A': CDS_PINID='DQ1_A';
NET_NAME
'M_C_CPU1_SA_DQ<20>'
 '@T6G_MB_LIB.T6G(SCH_1):M_C_CPU1_SA_DQ'<20>:
 C_SIGNAL='@t6g_mb_lib.t6g(sch_1):m_c_cpu1_sa_dq(20)';
NODE_NAME     U26 AA57
 '@T6G_MB_LIB.T6G(SCH_1):PAGE39_I159@PURE_QUANTA.GENOA_SP5(CHIPS)':
 'MCA_DATA20': CDS_PINID='MCA_DATA20';
NODE_NAME     J28 36
 '@T6G_MB_LIB.T6G(SCH_1):PAGE99_I22@PURE_QUANTA.SCONN288_DDR506112002KQ(CHIPS)':
 'DQ20_A': CDS_PINID='DQ20_A';
NET_NAME
'M_C_CPU1_SA_DQ<21>'
 '@T6G_MB_LIB.T6G(SCH_1):M_C_CPU1_SA_DQ'<21>:
 C_SIGNAL='@t6g_mb_lib.t6g(sch_1):m_c_cpu1_sa_dq(21)';
NODE_NAME     U26 AB55
 '@T6G_MB_LIB.T6G(SCH_1):PAGE39_I159@PURE_QUANTA.GENOA_SP5(CHIPS)':
 'MCA_DATA21': CDS_PINID='MCA_DATA21';
NODE_NAME     J28 38
 '@T6G_MB_LIB.T6G(SCH_1):PAGE99_I22@PURE_QUANTA.SCONN288_DDR506112002KQ(CHIPS)':
 'DQ21_A': CDS_PINID='DQ21_A';
NET_NAME
'M_C_CPU1_SA_DQ<22>'
 '@T6G_MB_LIB.T6G(SCH_1):M_C_CPU1_SA_DQ'<22>:
 C_SIGNAL='@t6g_mb_lib.t6g(sch_1):m_c_cpu1_sa_dq(22)';
NODE_NAME     U26 AB56
 '@T6G_MB_LIB.T6G(SCH_1):PAGE39_I159@PURE_QUANTA.GENOA_SP5(CHIPS)':
 'MCA_DATA22': CDS_PINID='MCA_DATA22';
NODE_NAME     J28 181
 '@T6G_MB_LIB.T6G(SCH_1):PAGE99_I22@PURE_QUANTA.SCONN288_DDR506112002KQ(CHIPS)':
 'DQ22_A': CDS_PINID='DQ22_A';
NET_NAME
'M_C_CPU1_SA_DQ<23>'
 '@T6G_MB_LIB.T6G(SCH_1):M_C_CPU1_SA_DQ'<23>:
 C_SIGNAL='@t6g_mb_lib.t6g(sch_1):m_c_cpu1_sa_dq(23)';
NODE_NAME     U26 AC55
 '@T6G_MB_LIB.T6G(SCH_1):PAGE39_I159@PURE_QUANTA.GENOA_SP5(CHIPS)':
 'MCA_DATA23': CDS_PINID='MCA_DATA23';
NODE_NAME     J28 183
 '@T6G_MB_LIB.T6G(SCH_1):PAGE99_I22@PURE_QUANTA.SCONN288_DDR506112002KQ(CHIPS)':
 'DQ23_A': CDS_PINID='DQ23_A';
NET_NAME
'M_C_CPU1_SA_DQ<24>'
 '@T6G_MB_LIB.T6G(SCH_1):M_C_CPU1_SA_DQ'<24>:
 C_SIGNAL='@t6g_mb_lib.t6g(sch_1):m_c_cpu1_sa_dq(24)';
NODE_NAME     U26 AC57
 '@T6G_MB_LIB.T6G(SCH_1):PAGE39_I159@PURE_QUANTA.GENOA_SP5(CHIPS)':
 'MCA_DATA24': CDS_PINID='MCA_DATA24';
NODE_NAME     J28 40
 '@T6G_MB_LIB.T6G(SCH_1):PAGE99_I22@PURE_QUANTA.SCONN288_DDR506112002KQ(CHIPS)':
 'DQ24_A': CDS_PINID='DQ24_A';
NET_NAME
'M_C_CPU1_SA_DQ<25>'
 '@T6G_MB_LIB.T6G(SCH_1):M_C_CPU1_SA_DQ'<25>:
 C_SIGNAL='@t6g_mb_lib.t6g(sch_1):m_c_cpu1_sa_dq(25)';
NODE_NAME     U26 AD55
 '@T6G_MB_LIB.T6G(SCH_1):PAGE39_I159@PURE_QUANTA.GENOA_SP5(CHIPS)':
 'MCA_DATA25': CDS_PINID='MCA_DATA25';
NODE_NAME     J28 42
 '@T6G_MB_LIB.T6G(SCH_1):PAGE99_I22@PURE_QUANTA.SCONN288_DDR506112002KQ(CHIPS)':
 'DQ25_A': CDS_PINID='DQ25_A';
NET_NAME
'M_C_CPU1_SA_DQ<26>'
 '@T6G_MB_LIB.T6G(SCH_1):M_C_CPU1_SA_DQ'<26>:
 C_SIGNAL='@t6g_mb_lib.t6g(sch_1):m_c_cpu1_sa_dq(26)';
NODE_NAME     U26 AD56
 '@T6G_MB_LIB.T6G(SCH_1):PAGE39_I159@PURE_QUANTA.GENOA_SP5(CHIPS)':
 'MCA_DATA26': CDS_PINID='MCA_DATA26';
NODE_NAME     J28 185
 '@T6G_MB_LIB.T6G(SCH_1):PAGE99_I22@PURE_QUANTA.SCONN288_DDR506112002KQ(CHIPS)':
 'DQ26_A': CDS_PINID='DQ26_A';
NET_NAME
'M_C_CPU1_SA_DQ<27>'
 '@T6G_MB_LIB.T6G(SCH_1):M_C_CPU1_SA_DQ'<27>:
 C_SIGNAL='@t6g_mb_lib.t6g(sch_1):m_c_cpu1_sa_dq(27)';
NODE_NAME     U26 AE55
 '@T6G_MB_LIB.T6G(SCH_1):PAGE39_I159@PURE_QUANTA.GENOA_SP5(CHIPS)':
 'MCA_DATA27': CDS_PINID='MCA_DATA27';
NODE_NAME     J28 187
 '@T6G_MB_LIB.T6G(SCH_1):PAGE99_I22@PURE_QUANTA.SCONN288_DDR506112002KQ(CHIPS)':
 'DQ27_A': CDS_PINID='DQ27_A';
NET_NAME
'M_C_CPU1_SA_DQ<28>'
 '@T6G_MB_LIB.T6G(SCH_1):M_C_CPU1_SA_DQ'<28>:
 C_SIGNAL='@t6g_mb_lib.t6g(sch_1):m_c_cpu1_sa_dq(28)';
NODE_NAME     U26 AG57
 '@T6G_MB_LIB.T6G(SCH_1):PAGE39_I159@PURE_QUANTA.GENOA_SP5(CHIPS)':
 'MCA_DATA28': CDS_PINID='MCA_DATA28';
NODE_NAME     J28 47
 '@T6G_MB_LIB.T6G(SCH_1):PAGE99_I22@PURE_QUANTA.SCONN288_DDR506112002KQ(CHIPS)':
 'DQ28_A': CDS_PINID='DQ28_A';
NET_NAME
'M_C_CPU1_SA_DQ<29>'
 '@T6G_MB_LIB.T6G(SCH_1):M_C_CPU1_SA_DQ'<29>:
 C_SIGNAL='@t6g_mb_lib.t6g(sch_1):m_c_cpu1_sa_dq(29)';
NODE_NAME     U26 AH55
 '@T6G_MB_LIB.T6G(SCH_1):PAGE39_I159@PURE_QUANTA.GENOA_SP5(CHIPS)':
 'MCA_DATA29': CDS_PINID='MCA_DATA29';
NODE_NAME     J28 49
 '@T6G_MB_LIB.T6G(SCH_1):PAGE99_I22@PURE_QUANTA.SCONN288_DDR506112002KQ(CHIPS)':
 'DQ29_A': CDS_PINID='DQ29_A';
NET_NAME
'M_C_CPU1_SA_DQ<2>'
 '@T6G_MB_LIB.T6G(SCH_1):M_C_CPU1_SA_DQ'<2>:
 C_SIGNAL='@t6g_mb_lib.t6g(sch_1):m_c_cpu1_sa_dq(2)';
NODE_NAME     U26 F56
 '@T6G_MB_LIB.T6G(SCH_1):PAGE39_I159@PURE_QUANTA.GENOA_SP5(CHIPS)':
 'MCA_DATA2': CDS_PINID='MCA_DATA2';
NODE_NAME     J28 152
 '@T6G_MB_LIB.T6G(SCH_1):PAGE99_I22@PURE_QUANTA.SCONN288_DDR506112002KQ(CHIPS)':
 'DQ2_A': CDS_PINID='DQ2_A';
NET_NAME
'M_C_CPU1_SA_DQ<30>'
 '@T6G_MB_LIB.T6G(SCH_1):M_C_CPU1_SA_DQ'<30>:
 C_SIGNAL='@t6g_mb_lib.t6g(sch_1):m_c_cpu1_sa_dq(30)';
NODE_NAME     U26 AH56
 '@T6G_MB_LIB.T6G(SCH_1):PAGE39_I159@PURE_QUANTA.GENOA_SP5(CHIPS)':
 'MCA_DATA30': CDS_PINID='MCA_DATA30';
NODE_NAME     J28 192
 '@T6G_MB_LIB.T6G(SCH_1):PAGE99_I22@PURE_QUANTA.SCONN288_DDR506112002KQ(CHIPS)':
 'DQ30_A': CDS_PINID='DQ30_A';
NET_NAME
'M_C_CPU1_SA_DQ<31>'
 '@T6G_MB_LIB.T6G(SCH_1):M_C_CPU1_SA_DQ'<31>:
 C_SIGNAL='@t6g_mb_lib.t6g(sch_1):m_c_cpu1_sa_dq(31)';
NODE_NAME     U26 AJ55
 '@T6G_MB_LIB.T6G(SCH_1):PAGE39_I159@PURE_QUANTA.GENOA_SP5(CHIPS)':
 'MCA_DATA31': CDS_PINID='MCA_DATA31';
NODE_NAME     J28 194
 '@T6G_MB_LIB.T6G(SCH_1):PAGE99_I22@PURE_QUANTA.SCONN288_DDR506112002KQ(CHIPS)':
 'DQ31_A': CDS_PINID='DQ31_A';
NET_NAME
'M_C_CPU1_SA_DQ<3>'
 '@T6G_MB_LIB.T6G(SCH_1):M_C_CPU1_SA_DQ'<3>:
 C_SIGNAL='@t6g_mb_lib.t6g(sch_1):m_c_cpu1_sa_dq(3)';
NODE_NAME     U26 G55
 '@T6G_MB_LIB.T6G(SCH_1):PAGE39_I159@PURE_QUANTA.GENOA_SP5(CHIPS)':
 'MCA_DATA3': CDS_PINID='MCA_DATA3';
NODE_NAME     J28 154
 '@T6G_MB_LIB.T6G(SCH_1):PAGE99_I22@PURE_QUANTA.SCONN288_DDR506112002KQ(CHIPS)':
 'DQ3_A': CDS_PINID='DQ3_A';
NET_NAME
'M_C_CPU1_SA_DQ<4>'
 '@T6G_MB_LIB.T6G(SCH_1):M_C_CPU1_SA_DQ'<4>:
 C_SIGNAL='@t6g_mb_lib.t6g(sch_1):m_c_cpu1_sa_dq(4)';
NODE_NAME     U26 J57
 '@T6G_MB_LIB.T6G(SCH_1):PAGE39_I159@PURE_QUANTA.GENOA_SP5(CHIPS)':
 'MCA_DATA4': CDS_PINID='MCA_DATA4';
NODE_NAME     J28 14
 '@T6G_MB_LIB.T6G(SCH_1):PAGE99_I22@PURE_QUANTA.SCONN288_DDR506112002KQ(CHIPS)':
 'DQ4_A': CDS_PINID='DQ4_A';
NET_NAME
'M_C_CPU1_SA_DQ<5>'
 '@T6G_MB_LIB.T6G(SCH_1):M_C_CPU1_SA_DQ'<5>:
 C_SIGNAL='@t6g_mb_lib.t6g(sch_1):m_c_cpu1_sa_dq(5)';
NODE_NAME     U26 K55
 '@T6G_MB_LIB.T6G(SCH_1):PAGE39_I159@PURE_QUANTA.GENOA_SP5(CHIPS)':
 'MCA_DATA5': CDS_PINID='MCA_DATA5';
NODE_NAME     J28 16
 '@T6G_MB_LIB.T6G(SCH_1):PAGE99_I22@PURE_QUANTA.SCONN288_DDR506112002KQ(CHIPS)':
 'DQ5_A': CDS_PINID='DQ5_A';
NET_NAME
'M_C_CPU1_SA_DQ<6>'
 '@T6G_MB_LIB.T6G(SCH_1):M_C_CPU1_SA_DQ'<6>:
 C_SIGNAL='@t6g_mb_lib.t6g(sch_1):m_c_cpu1_sa_dq(6)';
NODE_NAME     U26 K56
 '@T6G_MB_LIB.T6G(SCH_1):PAGE39_I159@PURE_QUANTA.GENOA_SP5(CHIPS)':
 'MCA_DATA6': CDS_PINID='MCA_DATA6';
NODE_NAME     J28 159
 '@T6G_MB_LIB.T6G(SCH_1):PAGE99_I22@PURE_QUANTA.SCONN288_DDR506112002KQ(CHIPS)':
 'DQ6_A': CDS_PINID='DQ6_A';
NET_NAME
'M_C_CPU1_SA_DQ<7>'
 '@T6G_MB_LIB.T6G(SCH_1):M_C_CPU1_SA_DQ'<7>:
 C_SIGNAL='@t6g_mb_lib.t6g(sch_1):m_c_cpu1_sa_dq(7)';
NODE_NAME     U26 L55
 '@T6G_MB_LIB.T6G(SCH_1):PAGE39_I159@PURE_QUANTA.GENOA_SP5(CHIPS)':
 'MCA_DATA7': CDS_PINID='MCA_DATA7';
NODE_NAME     J28 161
 '@T6G_MB_LIB.T6G(SCH_1):PAGE99_I22@PURE_QUANTA.SCONN288_DDR506112002KQ(CHIPS)':
 'DQ7_A': CDS_PINID='DQ7_A';
NET_NAME
'M_C_CPU1_SA_DQ<8>'
 '@T6G_MB_LIB.T6G(SCH_1):M_C_CPU1_SA_DQ'<8>:
 C_SIGNAL='@t6g_mb_lib.t6g(sch_1):m_c_cpu1_sa_dq(8)';
NODE_NAME     U26 L57
 '@T6G_MB_LIB.T6G(SCH_1):PAGE39_I159@PURE_QUANTA.GENOA_SP5(CHIPS)':
 'MCA_DATA8': CDS_PINID='MCA_DATA8';
NODE_NAME     J28 18
 '@T6G_MB_LIB.T6G(SCH_1):PAGE99_I22@PURE_QUANTA.SCONN288_DDR506112002KQ(CHIPS)':
 'DQ8_A': CDS_PINID='DQ8_A';
NET_NAME
'M_C_CPU1_SA_DQ<9>'
 '@T6G_MB_LIB.T6G(SCH_1):M_C_CPU1_SA_DQ'<9>:
 C_SIGNAL='@t6g_mb_lib.t6g(sch_1):m_c_cpu1_sa_dq(9)';
NODE_NAME     U26 M55
 '@T6G_MB_LIB.T6G(SCH_1):PAGE39_I159@PURE_QUANTA.GENOA_SP5(CHIPS)':
 'MCA_DATA9': CDS_PINID='MCA_DATA9';
NODE_NAME     J28 20
 '@T6G_MB_LIB.T6G(SCH_1):PAGE99_I22@PURE_QUANTA.SCONN288_DDR506112002KQ(CHIPS)':
 'DQ9_A': CDS_PINID='DQ9_A';
NET_NAME
'M_C_CPU1_SA_DQS_DN<0>'
 '@T6G_MB_LIB.T6G(SCH_1):M_C_CPU1_SA_DQS_DN'<0>:
 C_SIGNAL='@t6g_mb_lib.t6g(sch_1):m_c_cpu1_sa_dqs_dn(0)';
NODE_NAME     U26 H56
 '@T6G_MB_LIB.T6G(SCH_1):PAGE39_I159@PURE_QUANTA.GENOA_SP5(CHIPS)':
 'MCA_DQS_L0': CDS_PINID='MCA_DQS_L0';
NODE_NAME     J28 12
 '@T6G_MB_LIB.T6G(SCH_1):PAGE99_I236@PURE_QUANTA.SCONN288_DDR506112002KQ(CHIPS)':
 'DQS0_A_C': CDS_PINID='DQS0_A_C';
NET_NAME
'M_C_CPU1_SA_DQS_DN<1>'
 '@T6G_MB_LIB.T6G(SCH_1):M_C_CPU1_SA_DQS_DN'<1>:
 C_SIGNAL='@t6g_mb_lib.t6g(sch_1):m_c_cpu1_sa_dqs_dn(1)';
NODE_NAME     U26 P56
 '@T6G_MB_LIB.T6G(SCH_1):PAGE39_I159@PURE_QUANTA.GENOA_SP5(CHIPS)':
 'MCA_DQS_L1': CDS_PINID='MCA_DQS_L1';
NODE_NAME     J28 23
 '@T6G_MB_LIB.T6G(SCH_1):PAGE99_I236@PURE_QUANTA.SCONN288_DDR506112002KQ(CHIPS)':
 'DQS1_A_C': CDS_PINID='DQS1_A_C';
NET_NAME
'M_C_CPU1_SA_DQS_DN<2>'
 '@T6G_MB_LIB.T6G(SCH_1):M_C_CPU1_SA_DQS_DN'<2>:
 C_SIGNAL='@t6g_mb_lib.t6g(sch_1):m_c_cpu1_sa_dqs_dn(2)';
NODE_NAME     U26 Y56
 '@T6G_MB_LIB.T6G(SCH_1):PAGE39_I159@PURE_QUANTA.GENOA_SP5(CHIPS)':
 'MCA_DQS_L2': CDS_PINID='MCA_DQS_L2';
NODE_NAME     J28 34
 '@T6G_MB_LIB.T6G(SCH_1):PAGE99_I236@PURE_QUANTA.SCONN288_DDR506112002KQ(CHIPS)':
 'DQS2_A_C': CDS_PINID='DQS2_A_C';
NET_NAME
'M_C_CPU1_SA_DQS_DN<3>'
 '@T6G_MB_LIB.T6G(SCH_1):M_C_CPU1_SA_DQS_DN'<3>:
 C_SIGNAL='@t6g_mb_lib.t6g(sch_1):m_c_cpu1_sa_dqs_dn(3)';
NODE_NAME     U26 AF56
 '@T6G_MB_LIB.T6G(SCH_1):PAGE39_I159@PURE_QUANTA.GENOA_SP5(CHIPS)':
 'MCA_DQS_L3': CDS_PINID='MCA_DQS_L3';
NODE_NAME     J28 45
 '@T6G_MB_LIB.T6G(SCH_1):PAGE99_I236@PURE_QUANTA.SCONN288_DDR506112002KQ(CHIPS)':
 'DQS3_A_C': CDS_PINID='DQS3_A_C';
NET_NAME
'M_C_CPU1_SA_DQS_DN<4>'
 '@T6G_MB_LIB.T6G(SCH_1):M_C_CPU1_SA_DQS_DN'<4>:
 C_SIGNAL='@t6g_mb_lib.t6g(sch_1):m_c_cpu1_sa_dqs_dn(4)';
NODE_NAME     U26 AM56
 '@T6G_MB_LIB.T6G(SCH_1):PAGE39_I159@PURE_QUANTA.GENOA_SP5(CHIPS)':
 'MCA_DQS_L4': CDS_PINID='MCA_DQS_L4';
NODE_NAME     J28 56
 '@T6G_MB_LIB.T6G(SCH_1):PAGE99_I236@PURE_QUANTA.SCONN288_DDR506112002KQ(CHIPS)':
 'DQS4_A_C': CDS_PINID='DQS4_A_C';
NET_NAME
'M_C_CPU1_SA_DQS_DN<5>'
 '@T6G_MB_LIB.T6G(SCH_1):M_C_CPU1_SA_DQS_DN'<5>:
 C_SIGNAL='@t6g_mb_lib.t6g(sch_1):m_c_cpu1_sa_dqs_dn(5)';
NODE_NAME     U26 H55
 '@T6G_MB_LIB.T6G(SCH_1):PAGE39_I159@PURE_QUANTA.GENOA_SP5(CHIPS)':
 'MCA_DQS_L5': CDS_PINID='MCA_DQS_L5';
NODE_NAME     J28 156
 '@T6G_MB_LIB.T6G(SCH_1):PAGE99_I236@PURE_QUANTA.SCONN288_DDR506112002KQ(CHIPS)':
 'DQS5_A_C||TDQS5_A_C||DQS5_A_T||TDQS5_A_T': CDS_PINID='\dqs5_a_c||tdqs5_a_c||dqs5_a_t||tdqs5_a_t\';
NET_NAME
'M_C_CPU1_SA_DQS_DN<6>'
 '@T6G_MB_LIB.T6G(SCH_1):M_C_CPU1_SA_DQS_DN'<6>:
 C_SIGNAL='@t6g_mb_lib.t6g(sch_1):m_c_cpu1_sa_dqs_dn(6)';
NODE_NAME     U26 P55
 '@T6G_MB_LIB.T6G(SCH_1):PAGE39_I159@PURE_QUANTA.GENOA_SP5(CHIPS)':
 'MCA_DQS_L6': CDS_PINID='MCA_DQS_L6';
NODE_NAME     J28 167
 '@T6G_MB_LIB.T6G(SCH_1):PAGE99_I236@PURE_QUANTA.SCONN288_DDR506112002KQ(CHIPS)':
 'DQS6_A_C||TDQS6_A_C||DQS6_A_T||TDQS6_A_T': CDS_PINID='\dqs6_a_c||tdqs6_a_c||dqs6_a_t||tdqs6_a_t\';
NET_NAME
'M_C_CPU1_SA_DQS_DN<7>'
 '@T6G_MB_LIB.T6G(SCH_1):M_C_CPU1_SA_DQS_DN'<7>:
 C_SIGNAL='@t6g_mb_lib.t6g(sch_1):m_c_cpu1_sa_dqs_dn(7)';
NODE_NAME     U26 Y55
 '@T6G_MB_LIB.T6G(SCH_1):PAGE39_I159@PURE_QUANTA.GENOA_SP5(CHIPS)':
 'MCA_DQS_L7': CDS_PINID='MCA_DQS_L7';
NODE_NAME     J28 178
 '@T6G_MB_LIB.T6G(SCH_1):PAGE99_I236@PURE_QUANTA.SCONN288_DDR506112002KQ(CHIPS)':
 'DQS7_A_C||TDQS7_A_C': CDS_PINID='\dqs7_a_c||tdqs7_a_c\';
NET_NAME
'M_C_CPU1_SA_DQS_DN<8>'
 '@T6G_MB_LIB.T6G(SCH_1):M_C_CPU1_SA_DQS_DN'<8>:
 C_SIGNAL='@t6g_mb_lib.t6g(sch_1):m_c_cpu1_sa_dqs_dn(8)';
NODE_NAME     U26 AF55
 '@T6G_MB_LIB.T6G(SCH_1):PAGE39_I159@PURE_QUANTA.GENOA_SP5(CHIPS)':
 'MCA_DQS_L8': CDS_PINID='MCA_DQS_L8';
NODE_NAME     J28 189
 '@T6G_MB_LIB.T6G(SCH_1):PAGE99_I236@PURE_QUANTA.SCONN288_DDR506112002KQ(CHIPS)':
 'DQS8_A_C||TDQS8_A_C': CDS_PINID='\dqs8_a_c||tdqs8_a_c\';
NET_NAME
'M_C_CPU1_SA_DQS_DN<9>'
 '@T6G_MB_LIB.T6G(SCH_1):M_C_CPU1_SA_DQS_DN'<9>:
 C_SIGNAL='@t6g_mb_lib.t6g(sch_1):m_c_cpu1_sa_dqs_dn(9)';
NODE_NAME     U26 AM55
 '@T6G_MB_LIB.T6G(SCH_1):PAGE39_I159@PURE_QUANTA.GENOA_SP5(CHIPS)':
 'MCA_DQS_L9': CDS_PINID='MCA_DQS_L9';
NODE_NAME     J28 200
 '@T6G_MB_LIB.T6G(SCH_1):PAGE99_I236@PURE_QUANTA.SCONN288_DDR506112002KQ(CHIPS)':
 'DQS9_A_C||TDQS9_A_C': CDS_PINID='\dqs9_a_c||tdqs9_a_c\';
NET_NAME
'M_C_CPU1_SA_DQS_DP<0>'
 '@T6G_MB_LIB.T6G(SCH_1):M_C_CPU1_SA_DQS_DP'<0>:
 C_SIGNAL='@t6g_mb_lib.t6g(sch_1):m_c_cpu1_sa_dqs_dp(0)';
NODE_NAME     U26 G57
 '@T6G_MB_LIB.T6G(SCH_1):PAGE39_I159@PURE_QUANTA.GENOA_SP5(CHIPS)':
 'MCA_DQS_H0': CDS_PINID='MCA_DQS_H0';
NODE_NAME     J28 11
 '@T6G_MB_LIB.T6G(SCH_1):PAGE99_I236@PURE_QUANTA.SCONN288_DDR506112002KQ(CHIPS)':
 'DQS0_A_T': CDS_PINID='DQS0_A_T';
NET_NAME
'M_C_CPU1_SA_DQS_DP<1>'
 '@T6G_MB_LIB.T6G(SCH_1):M_C_CPU1_SA_DQS_DP'<1>:
 C_SIGNAL='@t6g_mb_lib.t6g(sch_1):m_c_cpu1_sa_dqs_dp(1)';
NODE_NAME     U26 N57
 '@T6G_MB_LIB.T6G(SCH_1):PAGE39_I159@PURE_QUANTA.GENOA_SP5(CHIPS)':
 'MCA_DQS_H1': CDS_PINID='MCA_DQS_H1';
NODE_NAME     J28 22
 '@T6G_MB_LIB.T6G(SCH_1):PAGE99_I236@PURE_QUANTA.SCONN288_DDR506112002KQ(CHIPS)':
 'DQS1_A_T': CDS_PINID='DQS1_A_T';
NET_NAME
'M_C_CPU1_SA_DQS_DP<2>'
 '@T6G_MB_LIB.T6G(SCH_1):M_C_CPU1_SA_DQS_DP'<2>:
 C_SIGNAL='@t6g_mb_lib.t6g(sch_1):m_c_cpu1_sa_dqs_dp(2)';
NODE_NAME     U26 W57
 '@T6G_MB_LIB.T6G(SCH_1):PAGE39_I159@PURE_QUANTA.GENOA_SP5(CHIPS)':
 'MCA_DQS_H2': CDS_PINID='MCA_DQS_H2';
NODE_NAME     J28 33
 '@T6G_MB_LIB.T6G(SCH_1):PAGE99_I236@PURE_QUANTA.SCONN288_DDR506112002KQ(CHIPS)':
 'DQS2_A_T': CDS_PINID='DQS2_A_T';
NET_NAME
'M_C_CPU1_SA_DQS_DP<3>'
 '@T6G_MB_LIB.T6G(SCH_1):M_C_CPU1_SA_DQS_DP'<3>:
 C_SIGNAL='@t6g_mb_lib.t6g(sch_1):m_c_cpu1_sa_dqs_dp(3)';
NODE_NAME     U26 AE57
 '@T6G_MB_LIB.T6G(SCH_1):PAGE39_I159@PURE_QUANTA.GENOA_SP5(CHIPS)':
 'MCA_DQS_H3': CDS_PINID='MCA_DQS_H3';
NODE_NAME     J28 44
 '@T6G_MB_LIB.T6G(SCH_1):PAGE99_I236@PURE_QUANTA.SCONN288_DDR506112002KQ(CHIPS)':
 'DQS3_A_T': CDS_PINID='DQS3_A_T';
NET_NAME
'M_C_CPU1_SA_DQS_DP<4>'
 '@T6G_MB_LIB.T6G(SCH_1):M_C_CPU1_SA_DQS_DP'<4>:
 C_SIGNAL='@t6g_mb_lib.t6g(sch_1):m_c_cpu1_sa_dqs_dp(4)';
NODE_NAME     U26 AL57
 '@T6G_MB_LIB.T6G(SCH_1):PAGE39_I159@PURE_QUANTA.GENOA_SP5(CHIPS)':
 'MCA_DQS_H4': CDS_PINID='MCA_DQS_H4';
NODE_NAME     J28 55
 '@T6G_MB_LIB.T6G(SCH_1):PAGE99_I236@PURE_QUANTA.SCONN288_DDR506112002KQ(CHIPS)':
 'DQS4_A_T': CDS_PINID='DQS4_A_T';
NET_NAME
'M_C_CPU1_SA_DQS_DP<5>'
 '@T6G_MB_LIB.T6G(SCH_1):M_C_CPU1_SA_DQS_DP'<5>:
 C_SIGNAL='@t6g_mb_lib.t6g(sch_1):m_c_cpu1_sa_dqs_dp(5)';
NODE_NAME     U26 J55
 '@T6G_MB_LIB.T6G(SCH_1):PAGE39_I159@PURE_QUANTA.GENOA_SP5(CHIPS)':
 'MCA_DQS_H5': CDS_PINID='MCA_DQS_H5';
NODE_NAME     J28 157
 '@T6G_MB_LIB.T6G(SCH_1):PAGE99_I236@PURE_QUANTA.SCONN288_DDR506112002KQ(CHIPS)':
 'DQS5_A_T||TDQS5_A_T': CDS_PINID='\dqs5_a_t||tdqs5_a_t\';
NET_NAME
'M_C_CPU1_SA_DQS_DP<6>'
 '@T6G_MB_LIB.T6G(SCH_1):M_C_CPU1_SA_DQS_DP'<6>:
 C_SIGNAL='@t6g_mb_lib.t6g(sch_1):m_c_cpu1_sa_dqs_dp(6)';
NODE_NAME     U26 R55
 '@T6G_MB_LIB.T6G(SCH_1):PAGE39_I159@PURE_QUANTA.GENOA_SP5(CHIPS)':
 'MCA_DQS_H6': CDS_PINID='MCA_DQS_H6';
NODE_NAME     J28 168
 '@T6G_MB_LIB.T6G(SCH_1):PAGE99_I236@PURE_QUANTA.SCONN288_DDR506112002KQ(CHIPS)':
 'DQS6_A_T||TDQS6_A_T': CDS_PINID='\dqs6_a_t||tdqs6_a_t\';
NET_NAME
'M_C_CPU1_SA_DQS_DP<7>'
 '@T6G_MB_LIB.T6G(SCH_1):M_C_CPU1_SA_DQS_DP'<7>:
 C_SIGNAL='@t6g_mb_lib.t6g(sch_1):m_c_cpu1_sa_dqs_dp(7)';
NODE_NAME     U26 AA55
 '@T6G_MB_LIB.T6G(SCH_1):PAGE39_I159@PURE_QUANTA.GENOA_SP5(CHIPS)':
 'MCA_DQS_H7': CDS_PINID='MCA_DQS_H7';
NODE_NAME     J28 179
 '@T6G_MB_LIB.T6G(SCH_1):PAGE99_I236@PURE_QUANTA.SCONN288_DDR506112002KQ(CHIPS)':
 'DQS7_A_T||TDQS7_A_T': CDS_PINID='\dqs7_a_t||tdqs7_a_t\';
NET_NAME
'M_C_CPU1_SA_DQS_DP<8>'
 '@T6G_MB_LIB.T6G(SCH_1):M_C_CPU1_SA_DQS_DP'<8>:
 C_SIGNAL='@t6g_mb_lib.t6g(sch_1):m_c_cpu1_sa_dqs_dp(8)';
NODE_NAME     U26 AG55
 '@T6G_MB_LIB.T6G(SCH_1):PAGE39_I159@PURE_QUANTA.GENOA_SP5(CHIPS)':
 'MCA_DQS_H8': CDS_PINID='MCA_DQS_H8';
NODE_NAME     J28 190
 '@T6G_MB_LIB.T6G(SCH_1):PAGE99_I236@PURE_QUANTA.SCONN288_DDR506112002KQ(CHIPS)':
 'DQS8_A_T||TDQS8_A_T': CDS_PINID='\dqs8_a_t||tdqs8_a_t\';
NET_NAME
'M_C_CPU1_SA_DQS_DP<9>'
 '@T6G_MB_LIB.T6G(SCH_1):M_C_CPU1_SA_DQS_DP'<9>:
 C_SIGNAL='@t6g_mb_lib.t6g(sch_1):m_c_cpu1_sa_dqs_dp(9)';
NODE_NAME     U26 AN55
 '@T6G_MB_LIB.T6G(SCH_1):PAGE39_I159@PURE_QUANTA.GENOA_SP5(CHIPS)':
 'MCA_DQS_H9': CDS_PINID='MCA_DQS_H9';
NODE_NAME     J28 201
 '@T6G_MB_LIB.T6G(SCH_1):PAGE99_I236@PURE_QUANTA.SCONN288_DDR506112002KQ(CHIPS)':
 'DQS9_A_T||TDQS9_A_T': CDS_PINID='\dqs9_a_t||tdqs9_a_t\';
NET_NAME
'M_C_CPU1_SA_PAR'
 '@T6G_MB_LIB.T6G(SCH_1):M_C_CPU1_SA_PAR':
 C_SIGNAL='@t6g_mb_lib.t6g(sch_1):m_c_cpu1_sa_par';
NODE_NAME     U26 BC55
 '@T6G_MB_LIB.T6G(SCH_1):PAGE39_I159@PURE_QUANTA.GENOA_SP5(CHIPS)':
 'MCA_PAR': CDS_PINID='MCA_PAR';
NODE_NAME     J28 74
 '@T6G_MB_LIB.T6G(SCH_1):PAGE99_I22@PURE_QUANTA.SCONN288_DDR506112002KQ(CHIPS)':
 'PAR_A': CDS_PINID='PAR_A';
NET_NAME
'M_C_CPU1_SA_RSP<0>'
 '@T6G_MB_LIB.T6G(SCH_1):M_C_CPU1_SA_RSP'<0>:
 C_SIGNAL='@t6g_mb_lib.t6g(sch_1):m_c_cpu1_sa_rsp(0)';
NODE_NAME     U26 BN55
 '@T6G_MB_LIB.T6G(SCH_1):PAGE39_I159@PURE_QUANTA.GENOA_SP5(CHIPS)':
 'MCA0_RSP_L': CDS_PINID='MCA0_RSP_L';
NODE_NAME     J28 86
 '@T6G_MB_LIB.T6G(SCH_1):PAGE99_I22@PURE_QUANTA.SCONN288_DDR506112002KQ(CHIPS)':
 'LBD||RSP_A_N': CDS_PINID='\lbd||rsp_a_n\';
NET_NAME
'M_C_CPU1_SB_CA<0>'
 '@T6G_MB_LIB.T6G(SCH_1):M_C_CPU1_SB_CA'<0>:
 C_SIGNAL='@t6g_mb_lib.t6g(sch_1):m_c_cpu1_sb_ca(0)';
NODE_NAME     U26 BG55
 '@T6G_MB_LIB.T6G(SCH_1):PAGE39_I159@PURE_QUANTA.GENOA_SP5(CHIPS)':
 'MCB_CA0': CDS_PINID='MCB_CA0';
NODE_NAME     J28 76
 '@T6G_MB_LIB.T6G(SCH_1):PAGE99_I22@PURE_QUANTA.SCONN288_DDR506112002KQ(CHIPS)':
 'CA0_B': CDS_PINID='CA0_B';
NET_NAME
'M_C_CPU1_SB_CA<1>'
 '@T6G_MB_LIB.T6G(SCH_1):M_C_CPU1_SB_CA'<1>:
 C_SIGNAL='@t6g_mb_lib.t6g(sch_1):m_c_cpu1_sb_ca(1)';
NODE_NAME     U26 BH55
 '@T6G_MB_LIB.T6G(SCH_1):PAGE39_I159@PURE_QUANTA.GENOA_SP5(CHIPS)':
 'MCB_CA1': CDS_PINID='MCB_CA1';
NODE_NAME     J28 221
 '@T6G_MB_LIB.T6G(SCH_1):PAGE99_I22@PURE_QUANTA.SCONN288_DDR506112002KQ(CHIPS)':
 'CA1_B': CDS_PINID='CA1_B';
NET_NAME
'M_C_CPU1_SB_CA<2>'
 '@T6G_MB_LIB.T6G(SCH_1):M_C_CPU1_SB_CA'<2>:
 C_SIGNAL='@t6g_mb_lib.t6g(sch_1):m_c_cpu1_sb_ca(2)';
NODE_NAME     U26 BH56
 '@T6G_MB_LIB.T6G(SCH_1):PAGE39_I159@PURE_QUANTA.GENOA_SP5(CHIPS)':
 'MCB_CA2': CDS_PINID='MCB_CA2';
NODE_NAME     J28 78
 '@T6G_MB_LIB.T6G(SCH_1):PAGE99_I22@PURE_QUANTA.SCONN288_DDR506112002KQ(CHIPS)':
 'CA2_B': CDS_PINID='CA2_B';
NET_NAME
'M_C_CPU1_SB_CA<3>'
 '@T6G_MB_LIB.T6G(SCH_1):M_C_CPU1_SB_CA'<3>:
 C_SIGNAL='@t6g_mb_lib.t6g(sch_1):m_c_cpu1_sb_ca(3)';
NODE_NAME     U26 BJ57
 '@T6G_MB_LIB.T6G(SCH_1):PAGE39_I159@PURE_QUANTA.GENOA_SP5(CHIPS)':
 'MCB_CA3': CDS_PINID='MCB_CA3';
NODE_NAME     J28 223
 '@T6G_MB_LIB.T6G(SCH_1):PAGE99_I22@PURE_QUANTA.SCONN288_DDR506112002KQ(CHIPS)':
 'CA3_B': CDS_PINID='CA3_B';
NET_NAME
'M_C_CPU1_SB_CA<4>'
 '@T6G_MB_LIB.T6G(SCH_1):M_C_CPU1_SB_CA'<4>:
 C_SIGNAL='@t6g_mb_lib.t6g(sch_1):m_c_cpu1_sb_ca(4)';
NODE_NAME     U26 BJ55
 '@T6G_MB_LIB.T6G(SCH_1):PAGE39_I159@PURE_QUANTA.GENOA_SP5(CHIPS)':
 'MCB_CA4': CDS_PINID='MCB_CA4';
NODE_NAME     J28 80
 '@T6G_MB_LIB.T6G(SCH_1):PAGE99_I22@PURE_QUANTA.SCONN288_DDR506112002KQ(CHIPS)':
 'CA4_B': CDS_PINID='CA4_B';
NET_NAME
'M_C_CPU1_SB_CA<5>'
 '@T6G_MB_LIB.T6G(SCH_1):M_C_CPU1_SB_CA'<5>:
 C_SIGNAL='@t6g_mb_lib.t6g(sch_1):m_c_cpu1_sb_ca(5)';
NODE_NAME     U26 BK55
 '@T6G_MB_LIB.T6G(SCH_1):PAGE39_I159@PURE_QUANTA.GENOA_SP5(CHIPS)':
 'MCB_CA5': CDS_PINID='MCB_CA5';
NODE_NAME     J28 225
 '@T6G_MB_LIB.T6G(SCH_1):PAGE99_I22@PURE_QUANTA.SCONN288_DDR506112002KQ(CHIPS)':
 'CA5_B': CDS_PINID='CA5_B';
NET_NAME
'M_C_CPU1_SB_CA<6>'
 '@T6G_MB_LIB.T6G(SCH_1):M_C_CPU1_SB_CA'<6>:
 C_SIGNAL='@t6g_mb_lib.t6g(sch_1):m_c_cpu1_sb_ca(6)';
NODE_NAME     U26 BK56
 '@T6G_MB_LIB.T6G(SCH_1):PAGE39_I159@PURE_QUANTA.GENOA_SP5(CHIPS)':
 'MCB_CA6': CDS_PINID='MCB_CA6';
NODE_NAME     J28 82
 '@T6G_MB_LIB.T6G(SCH_1):PAGE99_I22@PURE_QUANTA.SCONN288_DDR506112002KQ(CHIPS)':
 'CA6_B': CDS_PINID='CA6_B';
NET_NAME
'M_C_CPU1_SB_CB<0>'
 '@T6G_MB_LIB.T6G(SCH_1):M_C_CPU1_SB_CB'<0>:
 C_SIGNAL='@t6g_mb_lib.t6g(sch_1):m_c_cpu1_sb_cb(0)';
NODE_NAME     U26 BY56
 '@T6G_MB_LIB.T6G(SCH_1):PAGE39_I159@PURE_QUANTA.GENOA_SP5(CHIPS)':
 'MCB_CHECK0': CDS_PINID='MCB_CHECK0';
NODE_NAME     J28 96
 '@T6G_MB_LIB.T6G(SCH_1):PAGE99_I22@PURE_QUANTA.SCONN288_DDR506112002KQ(CHIPS)':
 'CB0_B': CDS_PINID='CB0_B';
NET_NAME
'M_C_CPU1_SB_CB<1>'
 '@T6G_MB_LIB.T6G(SCH_1):M_C_CPU1_SB_CB'<1>:
 C_SIGNAL='@t6g_mb_lib.t6g(sch_1):m_c_cpu1_sb_cb(1)';
NODE_NAME     U26 CA55
 '@T6G_MB_LIB.T6G(SCH_1):PAGE39_I159@PURE_QUANTA.GENOA_SP5(CHIPS)':
 'MCB_CHECK1': CDS_PINID='MCB_CHECK1';
NODE_NAME     J28 98
 '@T6G_MB_LIB.T6G(SCH_1):PAGE99_I22@PURE_QUANTA.SCONN288_DDR506112002KQ(CHIPS)':
 'CB1_B': CDS_PINID='CB1_B';
NET_NAME
'M_C_CPU1_SB_CB<2>'
 '@T6G_MB_LIB.T6G(SCH_1):M_C_CPU1_SB_CB'<2>:
 C_SIGNAL='@t6g_mb_lib.t6g(sch_1):m_c_cpu1_sb_cb(2)';
NODE_NAME     U26 CA57
 '@T6G_MB_LIB.T6G(SCH_1):PAGE39_I159@PURE_QUANTA.GENOA_SP5(CHIPS)':
 'MCB_CHECK2': CDS_PINID='MCB_CHECK2';
NODE_NAME     J28 241
 '@T6G_MB_LIB.T6G(SCH_1):PAGE99_I22@PURE_QUANTA.SCONN288_DDR506112002KQ(CHIPS)':
 'CB2_B': CDS_PINID='CB2_B';
NET_NAME
'M_C_CPU1_SB_CB<3>'
 '@T6G_MB_LIB.T6G(SCH_1):M_C_CPU1_SB_CB'<3>:
 C_SIGNAL='@t6g_mb_lib.t6g(sch_1):m_c_cpu1_sb_cb(3)';
NODE_NAME     U26 CB55
 '@T6G_MB_LIB.T6G(SCH_1):PAGE39_I159@PURE_QUANTA.GENOA_SP5(CHIPS)':
 'MCB_CHECK3': CDS_PINID='MCB_CHECK3';
NODE_NAME     J28 243
 '@T6G_MB_LIB.T6G(SCH_1):PAGE99_I22@PURE_QUANTA.SCONN288_DDR506112002KQ(CHIPS)':
 'CB3_B': CDS_PINID='CB3_B';
NET_NAME
'M_C_CPU1_SB_CB<4>'
 '@T6G_MB_LIB.T6G(SCH_1):M_C_CPU1_SB_CB'<4>:
 C_SIGNAL='@t6g_mb_lib.t6g(sch_1):m_c_cpu1_sb_cb(4)';
NODE_NAME     U26 BT56
 '@T6G_MB_LIB.T6G(SCH_1):PAGE39_I159@PURE_QUANTA.GENOA_SP5(CHIPS)':
 'MCB_CHECK4': CDS_PINID='MCB_CHECK4';
NODE_NAME     J28 89
 '@T6G_MB_LIB.T6G(SCH_1):PAGE99_I22@PURE_QUANTA.SCONN288_DDR506112002KQ(CHIPS)':
 'CB4_B': CDS_PINID='CB4_B';
NET_NAME
'M_C_CPU1_SB_CB<5>'
 '@T6G_MB_LIB.T6G(SCH_1):M_C_CPU1_SB_CB'<5>:
 C_SIGNAL='@t6g_mb_lib.t6g(sch_1):m_c_cpu1_sb_cb(5)';
NODE_NAME     U26 BU55
 '@T6G_MB_LIB.T6G(SCH_1):PAGE39_I159@PURE_QUANTA.GENOA_SP5(CHIPS)':
 'MCB_CHECK5': CDS_PINID='MCB_CHECK5';
NODE_NAME     J28 91
 '@T6G_MB_LIB.T6G(SCH_1):PAGE99_I22@PURE_QUANTA.SCONN288_DDR506112002KQ(CHIPS)':
 'CB5_B': CDS_PINID='CB5_B';
NET_NAME
'M_C_CPU1_SB_CB<6>'
 '@T6G_MB_LIB.T6G(SCH_1):M_C_CPU1_SB_CB'<6>:
 C_SIGNAL='@t6g_mb_lib.t6g(sch_1):m_c_cpu1_sb_cb(6)';
NODE_NAME     U26 BU57
 '@T6G_MB_LIB.T6G(SCH_1):PAGE39_I159@PURE_QUANTA.GENOA_SP5(CHIPS)':
 'MCB_CHECK6': CDS_PINID='MCB_CHECK6';
NODE_NAME     J28 234
 '@T6G_MB_LIB.T6G(SCH_1):PAGE99_I22@PURE_QUANTA.SCONN288_DDR506112002KQ(CHIPS)':
 'CB6_B': CDS_PINID='CB6_B';
NET_NAME
'M_C_CPU1_SB_CB<7>'
 '@T6G_MB_LIB.T6G(SCH_1):M_C_CPU1_SB_CB'<7>:
 C_SIGNAL='@t6g_mb_lib.t6g(sch_1):m_c_cpu1_sb_cb(7)';
NODE_NAME     U26 BV55
 '@T6G_MB_LIB.T6G(SCH_1):PAGE39_I159@PURE_QUANTA.GENOA_SP5(CHIPS)':
 'MCB_CHECK7': CDS_PINID='MCB_CHECK7';
NODE_NAME     J28 236
 '@T6G_MB_LIB.T6G(SCH_1):PAGE99_I22@PURE_QUANTA.SCONN288_DDR506112002KQ(CHIPS)':
 'CB7_B': CDS_PINID='CB7_B';
NET_NAME
'M_C_CPU1_SB_CS_N<0>'
 '@T6G_MB_LIB.T6G(SCH_1):M_C_CPU1_SB_CS_N'<0>:
 C_SIGNAL='@t6g_mb_lib.t6g(sch_1):m_c_cpu1_sb_cs_n(0)';
NODE_NAME     U26 BM55
 '@T6G_MB_LIB.T6G(SCH_1):PAGE39_I159@PURE_QUANTA.GENOA_SP5(CHIPS)':
 'MCB0_CS_L0': CDS_PINID='MCB0_CS_L0';
NODE_NAME     J28 84
 '@T6G_MB_LIB.T6G(SCH_1):PAGE99_I22@PURE_QUANTA.SCONN288_DDR506112002KQ(CHIPS)':
 'CS0_B_N': CDS_PINID='CS0_B_N';
NET_NAME
'M_C_CPU1_SB_CS_N<1>'
 '@T6G_MB_LIB.T6G(SCH_1):M_C_CPU1_SB_CS_N'<1>:
 C_SIGNAL='@t6g_mb_lib.t6g(sch_1):m_c_cpu1_sb_cs_n(1)';
NODE_NAME     U26 BN57
 '@T6G_MB_LIB.T6G(SCH_1):PAGE39_I159@PURE_QUANTA.GENOA_SP5(CHIPS)':
 'MCB0_CS_L1': CDS_PINID='MCB0_CS_L1';
NODE_NAME     J28 229
 '@T6G_MB_LIB.T6G(SCH_1):PAGE99_I22@PURE_QUANTA.SCONN288_DDR506112002KQ(CHIPS)':
 'CS1_B_N': CDS_PINID='CS1_B_N';
NET_NAME
'M_C_CPU1_SB_DQ<0>'
 '@T6G_MB_LIB.T6G(SCH_1):M_C_CPU1_SB_DQ'<0>:
 C_SIGNAL='@t6g_mb_lib.t6g(sch_1):m_c_cpu1_sb_dq(0)';
NODE_NAME     U26 CB56
 '@T6G_MB_LIB.T6G(SCH_1):PAGE39_I159@PURE_QUANTA.GENOA_SP5(CHIPS)':
 'MCB_DATA0': CDS_PINID='MCB_DATA0';
NODE_NAME     J28 100
 '@T6G_MB_LIB.T6G(SCH_1):PAGE99_I22@PURE_QUANTA.SCONN288_DDR506112002KQ(CHIPS)':
 'DQ0_B': CDS_PINID='DQ0_B';
NET_NAME
'M_C_CPU1_SB_DQ<10>'
 '@T6G_MB_LIB.T6G(SCH_1):M_C_CPU1_SB_DQ'<10>:
 C_SIGNAL='@t6g_mb_lib.t6g(sch_1):m_c_cpu1_sb_dq(10)';
NODE_NAME     U26 CJ57
 '@T6G_MB_LIB.T6G(SCH_1):PAGE39_I159@PURE_QUANTA.GENOA_SP5(CHIPS)':
 'MCB_DATA10': CDS_PINID='MCB_DATA10';
NODE_NAME     J28 256
 '@T6G_MB_LIB.T6G(SCH_1):PAGE99_I22@PURE_QUANTA.SCONN288_DDR506112002KQ(CHIPS)':
 'DQ10_B': CDS_PINID='DQ10_B';
NET_NAME
'M_C_CPU1_SB_DQ<11>'
 '@T6G_MB_LIB.T6G(SCH_1):M_C_CPU1_SB_DQ'<11>:
 C_SIGNAL='@t6g_mb_lib.t6g(sch_1):m_c_cpu1_sb_dq(11)';
NODE_NAME     U26 CK55
 '@T6G_MB_LIB.T6G(SCH_1):PAGE39_I159@PURE_QUANTA.GENOA_SP5(CHIPS)':
 'MCB_DATA11': CDS_PINID='MCB_DATA11';
NODE_NAME     J28 258
 '@T6G_MB_LIB.T6G(SCH_1):PAGE99_I22@PURE_QUANTA.SCONN288_DDR506112002KQ(CHIPS)':
 'DQ11_B': CDS_PINID='DQ11_B';
NET_NAME
'M_C_CPU1_SB_DQ<12>'
 '@T6G_MB_LIB.T6G(SCH_1):M_C_CPU1_SB_DQ'<12>:
 C_SIGNAL='@t6g_mb_lib.t6g(sch_1):m_c_cpu1_sb_dq(12)';
NODE_NAME     U26 CM56
 '@T6G_MB_LIB.T6G(SCH_1):PAGE39_I159@PURE_QUANTA.GENOA_SP5(CHIPS)':
 'MCB_DATA12': CDS_PINID='MCB_DATA12';
NODE_NAME     J28 118
 '@T6G_MB_LIB.T6G(SCH_1):PAGE99_I22@PURE_QUANTA.SCONN288_DDR506112002KQ(CHIPS)':
 'DQ12_B': CDS_PINID='DQ12_B';
NET_NAME
'M_C_CPU1_SB_DQ<13>'
 '@T6G_MB_LIB.T6G(SCH_1):M_C_CPU1_SB_DQ'<13>:
 C_SIGNAL='@t6g_mb_lib.t6g(sch_1):m_c_cpu1_sb_dq(13)';
NODE_NAME     U26 CN55
 '@T6G_MB_LIB.T6G(SCH_1):PAGE39_I159@PURE_QUANTA.GENOA_SP5(CHIPS)':
 'MCB_DATA13': CDS_PINID='MCB_DATA13';
NODE_NAME     J28 120
 '@T6G_MB_LIB.T6G(SCH_1):PAGE99_I22@PURE_QUANTA.SCONN288_DDR506112002KQ(CHIPS)':
 'DQ13_B': CDS_PINID='DQ13_B';
NET_NAME
'M_C_CPU1_SB_DQ<14>'
 '@T6G_MB_LIB.T6G(SCH_1):M_C_CPU1_SB_DQ'<14>:
 C_SIGNAL='@t6g_mb_lib.t6g(sch_1):m_c_cpu1_sb_dq(14)';
NODE_NAME     U26 CN57
 '@T6G_MB_LIB.T6G(SCH_1):PAGE39_I159@PURE_QUANTA.GENOA_SP5(CHIPS)':
 'MCB_DATA14': CDS_PINID='MCB_DATA14';
NODE_NAME     J28 263
 '@T6G_MB_LIB.T6G(SCH_1):PAGE99_I22@PURE_QUANTA.SCONN288_DDR506112002KQ(CHIPS)':
 'DQ14_B': CDS_PINID='DQ14_B';
NET_NAME
'M_C_CPU1_SB_DQ<15>'
 '@T6G_MB_LIB.T6G(SCH_1):M_C_CPU1_SB_DQ'<15>:
 C_SIGNAL='@t6g_mb_lib.t6g(sch_1):m_c_cpu1_sb_dq(15)';
NODE_NAME     U26 CP55
 '@T6G_MB_LIB.T6G(SCH_1):PAGE39_I159@PURE_QUANTA.GENOA_SP5(CHIPS)':
 'MCB_DATA15': CDS_PINID='MCB_DATA15';
NODE_NAME     J28 265
 '@T6G_MB_LIB.T6G(SCH_1):PAGE99_I22@PURE_QUANTA.SCONN288_DDR506112002KQ(CHIPS)':
 'DQ15_B': CDS_PINID='DQ15_B';
NET_NAME
'M_C_CPU1_SB_DQ<16>'
 '@T6G_MB_LIB.T6G(SCH_1):M_C_CPU1_SB_DQ'<16>:
 C_SIGNAL='@t6g_mb_lib.t6g(sch_1):m_c_cpu1_sb_dq(16)';
NODE_NAME     U26 CP56
 '@T6G_MB_LIB.T6G(SCH_1):PAGE39_I159@PURE_QUANTA.GENOA_SP5(CHIPS)':
 'MCB_DATA16': CDS_PINID='MCB_DATA16';
NODE_NAME     J28 122
 '@T6G_MB_LIB.T6G(SCH_1):PAGE99_I22@PURE_QUANTA.SCONN288_DDR506112002KQ(CHIPS)':
 'DQ16_B': CDS_PINID='DQ16_B';
NET_NAME
'M_C_CPU1_SB_DQ<17>'
 '@T6G_MB_LIB.T6G(SCH_1):M_C_CPU1_SB_DQ'<17>:
 C_SIGNAL='@t6g_mb_lib.t6g(sch_1):m_c_cpu1_sb_dq(17)';
NODE_NAME     U26 CR55
 '@T6G_MB_LIB.T6G(SCH_1):PAGE39_I159@PURE_QUANTA.GENOA_SP5(CHIPS)':
 'MCB_DATA17': CDS_PINID='MCB_DATA17';
NODE_NAME     J28 124
 '@T6G_MB_LIB.T6G(SCH_1):PAGE99_I22@PURE_QUANTA.SCONN288_DDR506112002KQ(CHIPS)':
 'DQ17_B': CDS_PINID='DQ17_B';
NET_NAME
'M_C_CPU1_SB_DQ<18>'
 '@T6G_MB_LIB.T6G(SCH_1):M_C_CPU1_SB_DQ'<18>:
 C_SIGNAL='@t6g_mb_lib.t6g(sch_1):m_c_cpu1_sb_dq(18)';
NODE_NAME     U26 CR57
 '@T6G_MB_LIB.T6G(SCH_1):PAGE39_I159@PURE_QUANTA.GENOA_SP5(CHIPS)':
 'MCB_DATA18': CDS_PINID='MCB_DATA18';
NODE_NAME     J28 267
 '@T6G_MB_LIB.T6G(SCH_1):PAGE99_I22@PURE_QUANTA.SCONN288_DDR506112002KQ(CHIPS)':
 'DQ18_B': CDS_PINID='DQ18_B';
NET_NAME
'M_C_CPU1_SB_DQ<19>'
 '@T6G_MB_LIB.T6G(SCH_1):M_C_CPU1_SB_DQ'<19>:
 C_SIGNAL='@t6g_mb_lib.t6g(sch_1):m_c_cpu1_sb_dq(19)';
NODE_NAME     U26 CT55
 '@T6G_MB_LIB.T6G(SCH_1):PAGE39_I159@PURE_QUANTA.GENOA_SP5(CHIPS)':
 'MCB_DATA19': CDS_PINID='MCB_DATA19';
NODE_NAME     J28 269
 '@T6G_MB_LIB.T6G(SCH_1):PAGE99_I22@PURE_QUANTA.SCONN288_DDR506112002KQ(CHIPS)':
 'DQ19_B': CDS_PINID='DQ19_B';
NET_NAME
'M_C_CPU1_SB_DQ<1>'
 '@T6G_MB_LIB.T6G(SCH_1):M_C_CPU1_SB_DQ'<1>:
 C_SIGNAL='@t6g_mb_lib.t6g(sch_1):m_c_cpu1_sb_dq(1)';
NODE_NAME     U26 CC55
 '@T6G_MB_LIB.T6G(SCH_1):PAGE39_I159@PURE_QUANTA.GENOA_SP5(CHIPS)':
 'MCB_DATA1': CDS_PINID='MCB_DATA1';
NODE_NAME     J28 102
 '@T6G_MB_LIB.T6G(SCH_1):PAGE99_I22@PURE_QUANTA.SCONN288_DDR506112002KQ(CHIPS)':
 'DQ1_B': CDS_PINID='DQ1_B';
NET_NAME
'M_C_CPU1_SB_DQ<20>'
 '@T6G_MB_LIB.T6G(SCH_1):M_C_CPU1_SB_DQ'<20>:
 C_SIGNAL='@t6g_mb_lib.t6g(sch_1):m_c_cpu1_sb_dq(20)';
NODE_NAME     U26 CV56
 '@T6G_MB_LIB.T6G(SCH_1):PAGE39_I159@PURE_QUANTA.GENOA_SP5(CHIPS)':
 'MCB_DATA20': CDS_PINID='MCB_DATA20';
NODE_NAME     J28 129
 '@T6G_MB_LIB.T6G(SCH_1):PAGE99_I22@PURE_QUANTA.SCONN288_DDR506112002KQ(CHIPS)':
 'DQ20_B': CDS_PINID='DQ20_B';
NET_NAME
'M_C_CPU1_SB_DQ<21>'
 '@T6G_MB_LIB.T6G(SCH_1):M_C_CPU1_SB_DQ'<21>:
 C_SIGNAL='@t6g_mb_lib.t6g(sch_1):m_c_cpu1_sb_dq(21)';
NODE_NAME     U26 CW55
 '@T6G_MB_LIB.T6G(SCH_1):PAGE39_I159@PURE_QUANTA.GENOA_SP5(CHIPS)':
 'MCB_DATA21': CDS_PINID='MCB_DATA21';
NODE_NAME     J28 131
 '@T6G_MB_LIB.T6G(SCH_1):PAGE99_I22@PURE_QUANTA.SCONN288_DDR506112002KQ(CHIPS)':
 'DQ21_B': CDS_PINID='DQ21_B';
NET_NAME
'M_C_CPU1_SB_DQ<22>'
 '@T6G_MB_LIB.T6G(SCH_1):M_C_CPU1_SB_DQ'<22>:
 C_SIGNAL='@t6g_mb_lib.t6g(sch_1):m_c_cpu1_sb_dq(22)';
NODE_NAME     U26 CW57
 '@T6G_MB_LIB.T6G(SCH_1):PAGE39_I159@PURE_QUANTA.GENOA_SP5(CHIPS)':
 'MCB_DATA22': CDS_PINID='MCB_DATA22';
NODE_NAME     J28 274
 '@T6G_MB_LIB.T6G(SCH_1):PAGE99_I22@PURE_QUANTA.SCONN288_DDR506112002KQ(CHIPS)':
 'DQ22_B': CDS_PINID='DQ22_B';
NET_NAME
'M_C_CPU1_SB_DQ<23>'
 '@T6G_MB_LIB.T6G(SCH_1):M_C_CPU1_SB_DQ'<23>:
 C_SIGNAL='@t6g_mb_lib.t6g(sch_1):m_c_cpu1_sb_dq(23)';
NODE_NAME     U26 CY55
 '@T6G_MB_LIB.T6G(SCH_1):PAGE39_I159@PURE_QUANTA.GENOA_SP5(CHIPS)':
 'MCB_DATA23': CDS_PINID='MCB_DATA23';
NODE_NAME     J28 276
 '@T6G_MB_LIB.T6G(SCH_1):PAGE99_I22@PURE_QUANTA.SCONN288_DDR506112002KQ(CHIPS)':
 'DQ23_B': CDS_PINID='DQ23_B';
NET_NAME
'M_C_CPU1_SB_DQ<24>'
 '@T6G_MB_LIB.T6G(SCH_1):M_C_CPU1_SB_DQ'<24>:
 C_SIGNAL='@t6g_mb_lib.t6g(sch_1):m_c_cpu1_sb_dq(24)';
NODE_NAME     U26 CY56
 '@T6G_MB_LIB.T6G(SCH_1):PAGE39_I159@PURE_QUANTA.GENOA_SP5(CHIPS)':
 'MCB_DATA24': CDS_PINID='MCB_DATA24';
NODE_NAME     J28 133
 '@T6G_MB_LIB.T6G(SCH_1):PAGE99_I22@PURE_QUANTA.SCONN288_DDR506112002KQ(CHIPS)':
 'DQ24_B': CDS_PINID='DQ24_B';
NET_NAME
'M_C_CPU1_SB_DQ<25>'
 '@T6G_MB_LIB.T6G(SCH_1):M_C_CPU1_SB_DQ'<25>:
 C_SIGNAL='@t6g_mb_lib.t6g(sch_1):m_c_cpu1_sb_dq(25)';
NODE_NAME     U26 DA55
 '@T6G_MB_LIB.T6G(SCH_1):PAGE39_I159@PURE_QUANTA.GENOA_SP5(CHIPS)':
 'MCB_DATA25': CDS_PINID='MCB_DATA25';
NODE_NAME     J28 135
 '@T6G_MB_LIB.T6G(SCH_1):PAGE99_I22@PURE_QUANTA.SCONN288_DDR506112002KQ(CHIPS)':
 'DQ25_B': CDS_PINID='DQ25_B';
NET_NAME
'M_C_CPU1_SB_DQ<26>'
 '@T6G_MB_LIB.T6G(SCH_1):M_C_CPU1_SB_DQ'<26>:
 C_SIGNAL='@t6g_mb_lib.t6g(sch_1):m_c_cpu1_sb_dq(26)';
NODE_NAME     U26 DA57
 '@T6G_MB_LIB.T6G(SCH_1):PAGE39_I159@PURE_QUANTA.GENOA_SP5(CHIPS)':
 'MCB_DATA26': CDS_PINID='MCB_DATA26';
NODE_NAME     J28 278
 '@T6G_MB_LIB.T6G(SCH_1):PAGE99_I22@PURE_QUANTA.SCONN288_DDR506112002KQ(CHIPS)':
 'DQ26_B': CDS_PINID='DQ26_B';
NET_NAME
'M_C_CPU1_SB_DQ<27>'
 '@T6G_MB_LIB.T6G(SCH_1):M_C_CPU1_SB_DQ'<27>:
 C_SIGNAL='@t6g_mb_lib.t6g(sch_1):m_c_cpu1_sb_dq(27)';
NODE_NAME     U26 DB55
 '@T6G_MB_LIB.T6G(SCH_1):PAGE39_I159@PURE_QUANTA.GENOA_SP5(CHIPS)':
 'MCB_DATA27': CDS_PINID='MCB_DATA27';
NODE_NAME     J28 280
 '@T6G_MB_LIB.T6G(SCH_1):PAGE99_I22@PURE_QUANTA.SCONN288_DDR506112002KQ(CHIPS)':
 'DQ27_B': CDS_PINID='DQ27_B';
NET_NAME
'M_C_CPU1_SB_DQ<28>'
 '@T6G_MB_LIB.T6G(SCH_1):M_C_CPU1_SB_DQ'<28>:
 C_SIGNAL='@t6g_mb_lib.t6g(sch_1):m_c_cpu1_sb_dq(28)';
NODE_NAME     U26 DD56
 '@T6G_MB_LIB.T6G(SCH_1):PAGE39_I159@PURE_QUANTA.GENOA_SP5(CHIPS)':
 'MCB_DATA28': CDS_PINID='MCB_DATA28';
NODE_NAME     J28 140
 '@T6G_MB_LIB.T6G(SCH_1):PAGE99_I22@PURE_QUANTA.SCONN288_DDR506112002KQ(CHIPS)':
 'DQ28_B': CDS_PINID='DQ28_B';
NET_NAME
'M_C_CPU1_SB_DQ<29>'
 '@T6G_MB_LIB.T6G(SCH_1):M_C_CPU1_SB_DQ'<29>:
 C_SIGNAL='@t6g_mb_lib.t6g(sch_1):m_c_cpu1_sb_dq(29)';
NODE_NAME     U26 DE55
 '@T6G_MB_LIB.T6G(SCH_1):PAGE39_I159@PURE_QUANTA.GENOA_SP5(CHIPS)':
 'MCB_DATA29': CDS_PINID='MCB_DATA29';
NODE_NAME     J28 142
 '@T6G_MB_LIB.T6G(SCH_1):PAGE99_I22@PURE_QUANTA.SCONN288_DDR506112002KQ(CHIPS)':
 'DQ29_B': CDS_PINID='DQ29_B';
NET_NAME
'M_C_CPU1_SB_DQ<2>'
 '@T6G_MB_LIB.T6G(SCH_1):M_C_CPU1_SB_DQ'<2>:
 C_SIGNAL='@t6g_mb_lib.t6g(sch_1):m_c_cpu1_sb_dq(2)';
NODE_NAME     U26 CC57
 '@T6G_MB_LIB.T6G(SCH_1):PAGE39_I159@PURE_QUANTA.GENOA_SP5(CHIPS)':
 'MCB_DATA2': CDS_PINID='MCB_DATA2';
NODE_NAME     J28 245
 '@T6G_MB_LIB.T6G(SCH_1):PAGE99_I22@PURE_QUANTA.SCONN288_DDR506112002KQ(CHIPS)':
 'DQ2_B': CDS_PINID='DQ2_B';
NET_NAME
'M_C_CPU1_SB_DQ<30>'
 '@T6G_MB_LIB.T6G(SCH_1):M_C_CPU1_SB_DQ'<30>:
 C_SIGNAL='@t6g_mb_lib.t6g(sch_1):m_c_cpu1_sb_dq(30)';
NODE_NAME     U26 DE57
 '@T6G_MB_LIB.T6G(SCH_1):PAGE39_I159@PURE_QUANTA.GENOA_SP5(CHIPS)':
 'MCB_DATA30': CDS_PINID='MCB_DATA30';
NODE_NAME     J28 285
 '@T6G_MB_LIB.T6G(SCH_1):PAGE99_I22@PURE_QUANTA.SCONN288_DDR506112002KQ(CHIPS)':
 'DQ30_B': CDS_PINID='DQ30_B';
NET_NAME
'M_C_CPU1_SB_DQ<31>'
 '@T6G_MB_LIB.T6G(SCH_1):M_C_CPU1_SB_DQ'<31>:
 C_SIGNAL='@t6g_mb_lib.t6g(sch_1):m_c_cpu1_sb_dq(31)';
NODE_NAME     U26 DF55
 '@T6G_MB_LIB.T6G(SCH_1):PAGE39_I159@PURE_QUANTA.GENOA_SP5(CHIPS)':
 'MCB_DATA31': CDS_PINID='MCB_DATA31';
NODE_NAME     J28 287
 '@T6G_MB_LIB.T6G(SCH_1):PAGE99_I22@PURE_QUANTA.SCONN288_DDR506112002KQ(CHIPS)':
 'DQ31_B': CDS_PINID='DQ31_B';
NET_NAME
'M_C_CPU1_SB_DQ<3>'
 '@T6G_MB_LIB.T6G(SCH_1):M_C_CPU1_SB_DQ'<3>:
 C_SIGNAL='@t6g_mb_lib.t6g(sch_1):m_c_cpu1_sb_dq(3)';
NODE_NAME     U26 CD55
 '@T6G_MB_LIB.T6G(SCH_1):PAGE39_I159@PURE_QUANTA.GENOA_SP5(CHIPS)':
 'MCB_DATA3': CDS_PINID='MCB_DATA3';
NODE_NAME     J28 247
 '@T6G_MB_LIB.T6G(SCH_1):PAGE99_I22@PURE_QUANTA.SCONN288_DDR506112002KQ(CHIPS)':
 'DQ3_B': CDS_PINID='DQ3_B';
NET_NAME
'M_C_CPU1_SB_DQ<4>'
 '@T6G_MB_LIB.T6G(SCH_1):M_C_CPU1_SB_DQ'<4>:
 C_SIGNAL='@t6g_mb_lib.t6g(sch_1):m_c_cpu1_sb_dq(4)';
NODE_NAME     U26 CF56
 '@T6G_MB_LIB.T6G(SCH_1):PAGE39_I159@PURE_QUANTA.GENOA_SP5(CHIPS)':
 'MCB_DATA4': CDS_PINID='MCB_DATA4';
NODE_NAME     J28 107
 '@T6G_MB_LIB.T6G(SCH_1):PAGE99_I22@PURE_QUANTA.SCONN288_DDR506112002KQ(CHIPS)':
 'DQ4_B': CDS_PINID='DQ4_B';
NET_NAME
'M_C_CPU1_SB_DQ<5>'
 '@T6G_MB_LIB.T6G(SCH_1):M_C_CPU1_SB_DQ'<5>:
 C_SIGNAL='@t6g_mb_lib.t6g(sch_1):m_c_cpu1_sb_dq(5)';
NODE_NAME     U26 CG55
 '@T6G_MB_LIB.T6G(SCH_1):PAGE39_I159@PURE_QUANTA.GENOA_SP5(CHIPS)':
 'MCB_DATA5': CDS_PINID='MCB_DATA5';
NODE_NAME     J28 109
 '@T6G_MB_LIB.T6G(SCH_1):PAGE99_I22@PURE_QUANTA.SCONN288_DDR506112002KQ(CHIPS)':
 'DQ5_B': CDS_PINID='DQ5_B';
NET_NAME
'M_C_CPU1_SB_DQ<6>'
 '@T6G_MB_LIB.T6G(SCH_1):M_C_CPU1_SB_DQ'<6>:
 C_SIGNAL='@t6g_mb_lib.t6g(sch_1):m_c_cpu1_sb_dq(6)';
NODE_NAME     U26 CG57
 '@T6G_MB_LIB.T6G(SCH_1):PAGE39_I159@PURE_QUANTA.GENOA_SP5(CHIPS)':
 'MCB_DATA6': CDS_PINID='MCB_DATA6';
NODE_NAME     J28 252
 '@T6G_MB_LIB.T6G(SCH_1):PAGE99_I22@PURE_QUANTA.SCONN288_DDR506112002KQ(CHIPS)':
 'DQ6_B': CDS_PINID='DQ6_B';
NET_NAME
'M_C_CPU1_SB_DQ<7>'
 '@T6G_MB_LIB.T6G(SCH_1):M_C_CPU1_SB_DQ'<7>:
 C_SIGNAL='@t6g_mb_lib.t6g(sch_1):m_c_cpu1_sb_dq(7)';
NODE_NAME     U26 CH55
 '@T6G_MB_LIB.T6G(SCH_1):PAGE39_I159@PURE_QUANTA.GENOA_SP5(CHIPS)':
 'MCB_DATA7': CDS_PINID='MCB_DATA7';
NODE_NAME     J28 254
 '@T6G_MB_LIB.T6G(SCH_1):PAGE99_I22@PURE_QUANTA.SCONN288_DDR506112002KQ(CHIPS)':
 'DQ7_B': CDS_PINID='DQ7_B';
NET_NAME
'M_C_CPU1_SB_DQ<8>'
 '@T6G_MB_LIB.T6G(SCH_1):M_C_CPU1_SB_DQ'<8>:
 C_SIGNAL='@t6g_mb_lib.t6g(sch_1):m_c_cpu1_sb_dq(8)';
NODE_NAME     U26 CH56
 '@T6G_MB_LIB.T6G(SCH_1):PAGE39_I159@PURE_QUANTA.GENOA_SP5(CHIPS)':
 'MCB_DATA8': CDS_PINID='MCB_DATA8';
NODE_NAME     J28 111
 '@T6G_MB_LIB.T6G(SCH_1):PAGE99_I22@PURE_QUANTA.SCONN288_DDR506112002KQ(CHIPS)':
 'DQ8_B': CDS_PINID='DQ8_B';
NET_NAME
'M_C_CPU1_SB_DQ<9>'
 '@T6G_MB_LIB.T6G(SCH_1):M_C_CPU1_SB_DQ'<9>:
 C_SIGNAL='@t6g_mb_lib.t6g(sch_1):m_c_cpu1_sb_dq(9)';
NODE_NAME     U26 CJ55
 '@T6G_MB_LIB.T6G(SCH_1):PAGE39_I159@PURE_QUANTA.GENOA_SP5(CHIPS)':
 'MCB_DATA9': CDS_PINID='MCB_DATA9';
NODE_NAME     J28 113
 '@T6G_MB_LIB.T6G(SCH_1):PAGE99_I22@PURE_QUANTA.SCONN288_DDR506112002KQ(CHIPS)':
 'DQ9_B': CDS_PINID='DQ9_B';
NET_NAME
'M_C_CPU1_SB_DQS_DN<0>'
 '@T6G_MB_LIB.T6G(SCH_1):M_C_CPU1_SB_DQS_DN'<0>:
 C_SIGNAL='@t6g_mb_lib.t6g(sch_1):m_c_cpu1_sb_dqs_dn(0)';
NODE_NAME     U26 CE57
 '@T6G_MB_LIB.T6G(SCH_1):PAGE39_I159@PURE_QUANTA.GENOA_SP5(CHIPS)':
 'MCB_DQS_L0': CDS_PINID='MCB_DQS_L0';
NODE_NAME     J28 105
 '@T6G_MB_LIB.T6G(SCH_1):PAGE99_I236@PURE_QUANTA.SCONN288_DDR506112002KQ(CHIPS)':
 'DQS0_B_C': CDS_PINID='DQS0_B_C';
NET_NAME
'M_C_CPU1_SB_DQS_DN<1>'
 '@T6G_MB_LIB.T6G(SCH_1):M_C_CPU1_SB_DQS_DN'<1>:
 C_SIGNAL='@t6g_mb_lib.t6g(sch_1):m_c_cpu1_sb_dqs_dn(1)';
NODE_NAME     U26 CL57
 '@T6G_MB_LIB.T6G(SCH_1):PAGE39_I159@PURE_QUANTA.GENOA_SP5(CHIPS)':
 'MCB_DQS_L1': CDS_PINID='MCB_DQS_L1';
NODE_NAME     J28 116
 '@T6G_MB_LIB.T6G(SCH_1):PAGE99_I236@PURE_QUANTA.SCONN288_DDR506112002KQ(CHIPS)':
 'DQS1_B_C': CDS_PINID='DQS1_B_C';
NET_NAME
'M_C_CPU1_SB_DQS_DN<2>'
 '@T6G_MB_LIB.T6G(SCH_1):M_C_CPU1_SB_DQS_DN'<2>:
 C_SIGNAL='@t6g_mb_lib.t6g(sch_1):m_c_cpu1_sb_dqs_dn(2)';
NODE_NAME     U26 CU57
 '@T6G_MB_LIB.T6G(SCH_1):PAGE39_I159@PURE_QUANTA.GENOA_SP5(CHIPS)':
 'MCB_DQS_L2': CDS_PINID='MCB_DQS_L2';
NODE_NAME     J28 127
 '@T6G_MB_LIB.T6G(SCH_1):PAGE99_I236@PURE_QUANTA.SCONN288_DDR506112002KQ(CHIPS)':
 'DQS2_B_C': CDS_PINID='DQS2_B_C';
NET_NAME
'M_C_CPU1_SB_DQS_DN<3>'
 '@T6G_MB_LIB.T6G(SCH_1):M_C_CPU1_SB_DQS_DN'<3>:
 C_SIGNAL='@t6g_mb_lib.t6g(sch_1):m_c_cpu1_sb_dqs_dn(3)';
NODE_NAME     U26 DC57
 '@T6G_MB_LIB.T6G(SCH_1):PAGE39_I159@PURE_QUANTA.GENOA_SP5(CHIPS)':
 'MCB_DQS_L3': CDS_PINID='MCB_DQS_L3';
NODE_NAME     J28 138
 '@T6G_MB_LIB.T6G(SCH_1):PAGE99_I236@PURE_QUANTA.SCONN288_DDR506112002KQ(CHIPS)':
 'DQS3_B_C': CDS_PINID='DQS3_B_C';
NET_NAME
'M_C_CPU1_SB_DQS_DN<4>'
 '@T6G_MB_LIB.T6G(SCH_1):M_C_CPU1_SB_DQS_DN'<4>:
 C_SIGNAL='@t6g_mb_lib.t6g(sch_1):m_c_cpu1_sb_dqs_dn(4)';
NODE_NAME     U26 BW55
 '@T6G_MB_LIB.T6G(SCH_1):PAGE39_I159@PURE_QUANTA.GENOA_SP5(CHIPS)':
 'MCB_DQS_L4': CDS_PINID='MCB_DQS_L4';
NODE_NAME     J28 238
 '@T6G_MB_LIB.T6G(SCH_1):PAGE99_I236@PURE_QUANTA.SCONN288_DDR506112002KQ(CHIPS)':
 'DQS4_B_C': CDS_PINID='DQS4_B_C';
NET_NAME
'M_C_CPU1_SB_DQS_DN<5>'
 '@T6G_MB_LIB.T6G(SCH_1):M_C_CPU1_SB_DQS_DN'<5>:
 C_SIGNAL='@t6g_mb_lib.t6g(sch_1):m_c_cpu1_sb_dqs_dn(5)';
NODE_NAME     U26 CE55
 '@T6G_MB_LIB.T6G(SCH_1):PAGE39_I159@PURE_QUANTA.GENOA_SP5(CHIPS)':
 'MCB_DQS_L5': CDS_PINID='MCB_DQS_L5';
NODE_NAME     J28 249
 '@T6G_MB_LIB.T6G(SCH_1):PAGE99_I236@PURE_QUANTA.SCONN288_DDR506112002KQ(CHIPS)':
 'DQS5_B_C||TDQS5_B_C': CDS_PINID='\dqs5_b_c||tdqs5_b_c\';
NET_NAME
'M_C_CPU1_SB_DQS_DN<6>'
 '@T6G_MB_LIB.T6G(SCH_1):M_C_CPU1_SB_DQS_DN'<6>:
 C_SIGNAL='@t6g_mb_lib.t6g(sch_1):m_c_cpu1_sb_dqs_dn(6)';
NODE_NAME     U26 CL55
 '@T6G_MB_LIB.T6G(SCH_1):PAGE39_I159@PURE_QUANTA.GENOA_SP5(CHIPS)':
 'MCB_DQS_L6': CDS_PINID='MCB_DQS_L6';
NODE_NAME     J28 260
 '@T6G_MB_LIB.T6G(SCH_1):PAGE99_I236@PURE_QUANTA.SCONN288_DDR506112002KQ(CHIPS)':
 'DQS6_B_C||TDQS6_B_C': CDS_PINID='\dqs6_b_c||tdqs6_b_c\';
NET_NAME
'M_C_CPU1_SB_DQS_DN<7>'
 '@T6G_MB_LIB.T6G(SCH_1):M_C_CPU1_SB_DQS_DN'<7>:
 C_SIGNAL='@t6g_mb_lib.t6g(sch_1):m_c_cpu1_sb_dqs_dn(7)';
NODE_NAME     U26 CU55
 '@T6G_MB_LIB.T6G(SCH_1):PAGE39_I159@PURE_QUANTA.GENOA_SP5(CHIPS)':
 'MCB_DQS_L7': CDS_PINID='MCB_DQS_L7';
NODE_NAME     J28 271
 '@T6G_MB_LIB.T6G(SCH_1):PAGE99_I236@PURE_QUANTA.SCONN288_DDR506112002KQ(CHIPS)':
 'DQS7_B_C||TDQS7_B_C': CDS_PINID='\dqs7_b_c||tdqs7_b_c\';
NET_NAME
'M_C_CPU1_SB_DQS_DN<8>'
 '@T6G_MB_LIB.T6G(SCH_1):M_C_CPU1_SB_DQS_DN'<8>:
 C_SIGNAL='@t6g_mb_lib.t6g(sch_1):m_c_cpu1_sb_dqs_dn(8)';
NODE_NAME     U26 DC55
 '@T6G_MB_LIB.T6G(SCH_1):PAGE39_I159@PURE_QUANTA.GENOA_SP5(CHIPS)':
 'MCB_DQS_L8': CDS_PINID='MCB_DQS_L8';
NODE_NAME     J28 282
 '@T6G_MB_LIB.T6G(SCH_1):PAGE99_I236@PURE_QUANTA.SCONN288_DDR506112002KQ(CHIPS)':
 'DQS8_B_C||TDQS8_B_C': CDS_PINID='\dqs8_b_c||tdqs8_b_c\';
NET_NAME
'M_C_CPU1_SB_DQS_DN<9>'
 '@T6G_MB_LIB.T6G(SCH_1):M_C_CPU1_SB_DQS_DN'<9>:
 C_SIGNAL='@t6g_mb_lib.t6g(sch_1):m_c_cpu1_sb_dqs_dn(9)';
NODE_NAME     U26 BW57
 '@T6G_MB_LIB.T6G(SCH_1):PAGE39_I159@PURE_QUANTA.GENOA_SP5(CHIPS)':
 'MCB_DQS_L9': CDS_PINID='MCB_DQS_L9';
NODE_NAME     J28 94
 '@T6G_MB_LIB.T6G(SCH_1):PAGE99_I236@PURE_QUANTA.SCONN288_DDR506112002KQ(CHIPS)':
 'DQS9_B_C||TDQS9_B_C': CDS_PINID='\dqs9_b_c||tdqs9_b_c\';
NET_NAME
'M_C_CPU1_SB_DQS_DP<0>'
 '@T6G_MB_LIB.T6G(SCH_1):M_C_CPU1_SB_DQS_DP'<0>:
 C_SIGNAL='@t6g_mb_lib.t6g(sch_1):m_c_cpu1_sb_dqs_dp(0)';
NODE_NAME     U26 CD56
 '@T6G_MB_LIB.T6G(SCH_1):PAGE39_I159@PURE_QUANTA.GENOA_SP5(CHIPS)':
 'MCB_DQS_H0': CDS_PINID='MCB_DQS_H0';
NODE_NAME     J28 104
 '@T6G_MB_LIB.T6G(SCH_1):PAGE99_I236@PURE_QUANTA.SCONN288_DDR506112002KQ(CHIPS)':
 'DQS0_B_T': CDS_PINID='DQS0_B_T';
NET_NAME
'M_C_CPU1_SB_DQS_DP<1>'
 '@T6G_MB_LIB.T6G(SCH_1):M_C_CPU1_SB_DQS_DP'<1>:
 C_SIGNAL='@t6g_mb_lib.t6g(sch_1):m_c_cpu1_sb_dqs_dp(1)';
NODE_NAME     U26 CK56
 '@T6G_MB_LIB.T6G(SCH_1):PAGE39_I159@PURE_QUANTA.GENOA_SP5(CHIPS)':
 'MCB_DQS_H1': CDS_PINID='MCB_DQS_H1';
NODE_NAME     J28 115
 '@T6G_MB_LIB.T6G(SCH_1):PAGE99_I236@PURE_QUANTA.SCONN288_DDR506112002KQ(CHIPS)':
 'DQS1_B_T': CDS_PINID='DQS1_B_T';
NET_NAME
'M_C_CPU1_SB_DQS_DP<2>'
 '@T6G_MB_LIB.T6G(SCH_1):M_C_CPU1_SB_DQS_DP'<2>:
 C_SIGNAL='@t6g_mb_lib.t6g(sch_1):m_c_cpu1_sb_dqs_dp(2)';
NODE_NAME     U26 CT56
 '@T6G_MB_LIB.T6G(SCH_1):PAGE39_I159@PURE_QUANTA.GENOA_SP5(CHIPS)':
 'MCB_DQS_H2': CDS_PINID='MCB_DQS_H2';
NODE_NAME     J28 126
 '@T6G_MB_LIB.T6G(SCH_1):PAGE99_I236@PURE_QUANTA.SCONN288_DDR506112002KQ(CHIPS)':
 'DQS2_B_T': CDS_PINID='DQS2_B_T';
NET_NAME
'M_C_CPU1_SB_DQS_DP<3>'
 '@T6G_MB_LIB.T6G(SCH_1):M_C_CPU1_SB_DQS_DP'<3>:
 C_SIGNAL='@t6g_mb_lib.t6g(sch_1):m_c_cpu1_sb_dqs_dp(3)';
NODE_NAME     U26 DB56
 '@T6G_MB_LIB.T6G(SCH_1):PAGE39_I159@PURE_QUANTA.GENOA_SP5(CHIPS)':
 'MCB_DQS_H3': CDS_PINID='MCB_DQS_H3';
NODE_NAME     J28 137
 '@T6G_MB_LIB.T6G(SCH_1):PAGE99_I236@PURE_QUANTA.SCONN288_DDR506112002KQ(CHIPS)':
 'DQS3_B_T': CDS_PINID='DQS3_B_T';
NET_NAME
'M_C_CPU1_SB_DQS_DP<4>'
 '@T6G_MB_LIB.T6G(SCH_1):M_C_CPU1_SB_DQS_DP'<4>:
 C_SIGNAL='@t6g_mb_lib.t6g(sch_1):m_c_cpu1_sb_dqs_dp(4)';
NODE_NAME     U26 BY55
 '@T6G_MB_LIB.T6G(SCH_1):PAGE39_I159@PURE_QUANTA.GENOA_SP5(CHIPS)':
 'MCB_DQS_H4': CDS_PINID='MCB_DQS_H4';
NODE_NAME     J28 239
 '@T6G_MB_LIB.T6G(SCH_1):PAGE99_I236@PURE_QUANTA.SCONN288_DDR506112002KQ(CHIPS)':
 'DQS4_B_T': CDS_PINID='DQS4_B_T';
NET_NAME
'M_C_CPU1_SB_DQS_DP<5>'
 '@T6G_MB_LIB.T6G(SCH_1):M_C_CPU1_SB_DQS_DP'<5>:
 C_SIGNAL='@t6g_mb_lib.t6g(sch_1):m_c_cpu1_sb_dqs_dp(5)';
NODE_NAME     U26 CF55
 '@T6G_MB_LIB.T6G(SCH_1):PAGE39_I159@PURE_QUANTA.GENOA_SP5(CHIPS)':
 'MCB_DQS_H5': CDS_PINID='MCB_DQS_H5';
NODE_NAME     J28 250
 '@T6G_MB_LIB.T6G(SCH_1):PAGE99_I236@PURE_QUANTA.SCONN288_DDR506112002KQ(CHIPS)':
 'DQS5_B_T||TDQS5_B_T': CDS_PINID='\dqs5_b_t||tdqs5_b_t\';
NET_NAME
'M_C_CPU1_SB_DQS_DP<6>'
 '@T6G_MB_LIB.T6G(SCH_1):M_C_CPU1_SB_DQS_DP'<6>:
 C_SIGNAL='@t6g_mb_lib.t6g(sch_1):m_c_cpu1_sb_dqs_dp(6)';
NODE_NAME     U26 CM55
 '@T6G_MB_LIB.T6G(SCH_1):PAGE39_I159@PURE_QUANTA.GENOA_SP5(CHIPS)':
 'MCB_DQS_H6': CDS_PINID='MCB_DQS_H6';
NODE_NAME     J28 261
 '@T6G_MB_LIB.T6G(SCH_1):PAGE99_I236@PURE_QUANTA.SCONN288_DDR506112002KQ(CHIPS)':
 'DQS6_B_T||TDQS6_B_T': CDS_PINID='\dqs6_b_t||tdqs6_b_t\';
NET_NAME
'M_C_CPU1_SB_DQS_DP<7>'
 '@T6G_MB_LIB.T6G(SCH_1):M_C_CPU1_SB_DQS_DP'<7>:
 C_SIGNAL='@t6g_mb_lib.t6g(sch_1):m_c_cpu1_sb_dqs_dp(7)';
NODE_NAME     U26 CV55
 '@T6G_MB_LIB.T6G(SCH_1):PAGE39_I159@PURE_QUANTA.GENOA_SP5(CHIPS)':
 'MCB_DQS_H7': CDS_PINID='MCB_DQS_H7';
NODE_NAME     J28 272
 '@T6G_MB_LIB.T6G(SCH_1):PAGE99_I236@PURE_QUANTA.SCONN288_DDR506112002KQ(CHIPS)':
 'DQS7_B_T||TDQS7_B_T': CDS_PINID='\dqs7_b_t||tdqs7_b_t\';
NET_NAME
'M_C_CPU1_SB_DQS_DP<8>'
 '@T6G_MB_LIB.T6G(SCH_1):M_C_CPU1_SB_DQS_DP'<8>:
 C_SIGNAL='@t6g_mb_lib.t6g(sch_1):m_c_cpu1_sb_dqs_dp(8)';
NODE_NAME     U26 DD55
 '@T6G_MB_LIB.T6G(SCH_1):PAGE39_I159@PURE_QUANTA.GENOA_SP5(CHIPS)':
 'MCB_DQS_H8': CDS_PINID='MCB_DQS_H8';
NODE_NAME     J28 283
 '@T6G_MB_LIB.T6G(SCH_1):PAGE99_I236@PURE_QUANTA.SCONN288_DDR506112002KQ(CHIPS)':
 'DQS8_B_T||TDQS8_B_T': CDS_PINID='\dqs8_b_t||tdqs8_b_t\';
NET_NAME
'M_C_CPU1_SB_DQS_DP<9>'
 '@T6G_MB_LIB.T6G(SCH_1):M_C_CPU1_SB_DQS_DP'<9>:
 C_SIGNAL='@t6g_mb_lib.t6g(sch_1):m_c_cpu1_sb_dqs_dp(9)';
NODE_NAME     U26 BV56
 '@T6G_MB_LIB.T6G(SCH_1):PAGE39_I159@PURE_QUANTA.GENOA_SP5(CHIPS)':
 'MCB_DQS_H9': CDS_PINID='MCB_DQS_H9';
NODE_NAME     J28 93
 '@T6G_MB_LIB.T6G(SCH_1):PAGE99_I236@PURE_QUANTA.SCONN288_DDR506112002KQ(CHIPS)':
 'DQS9_B_T||TDQS9_B_T||DBI4_B_N': CDS_PINID='\dqs9_b_t||tdqs9_b_t||dbi4_b_n\';
NET_NAME
'M_C_CPU1_SB_PAR'
 '@T6G_MB_LIB.T6G(SCH_1):M_C_CPU1_SB_PAR':
 C_SIGNAL='@t6g_mb_lib.t6g(sch_1):m_c_cpu1_sb_par';
NODE_NAME     U26 BL57
 '@T6G_MB_LIB.T6G(SCH_1):PAGE39_I159@PURE_QUANTA.GENOA_SP5(CHIPS)':
 'MCB_PAR': CDS_PINID='MCB_PAR';
NODE_NAME     J28 227
 '@T6G_MB_LIB.T6G(SCH_1):PAGE99_I22@PURE_QUANTA.SCONN288_DDR506112002KQ(CHIPS)':
 'PAR_B': CDS_PINID='PAR_B';
NET_NAME
'M_C_CPU1_SB_RSP<0>'
 '@T6G_MB_LIB.T6G(SCH_1):M_C_CPU1_SB_RSP'<0>:
 C_SIGNAL='@t6g_mb_lib.t6g(sch_1):m_c_cpu1_sb_rsp(0)';
NODE_NAME     U26 BP56
 '@T6G_MB_LIB.T6G(SCH_1):PAGE39_I159@PURE_QUANTA.GENOA_SP5(CHIPS)':
 'MCB0_RSP_L': CDS_PINID='MCB0_RSP_L';
NODE_NAME     J28 87
 '@T6G_MB_LIB.T6G(SCH_1):PAGE99_I22@PURE_QUANTA.SCONN288_DDR506112002KQ(CHIPS)':
 'LBS||RSP_B_N': CDS_PINID='\lbs||rsp_b_n\';
NET_NAME
'M_D_CPU0_ALERT_N'
 '@T6G_MB_LIB.T6G(SCH_1):M_D_CPU0_ALERT_N':
 C_SIGNAL='@t6g_mb_lib.t6g(sch_1):m_d_cpu0_alert_n';
NODE_NAME     R378 1
 '@T6G_MB_LIB.T6G(SCH_1):PAGE13_I314@PURE_QUANTA.Q_RES(CHIPS)':
 'A': CDS_PINID='A';
NODE_NAME     J19 62
 '@T6G_MB_LIB.T6G(SCH_1):PAGE88_I350@PURE_QUANTA.SCONN288_DDR506112002KQ(CHIPS)':
 'ALERT_N': CDS_PINID='ALERT_N';
NET_NAME
'M_D_CPU0_ALERT_R_N'
 '@T6G_MB_LIB.T6G(SCH_1):M_D_CPU0_ALERT_R_N':
 C_SIGNAL='@t6g_mb_lib.t6g(sch_1):m_d_cpu0_alert_r_n';
NODE_NAME     U25 AT58
 '@T6G_MB_LIB.T6G(SCH_1):PAGE13_I159@PURE_QUANTA.GENOA_SP5(CHIPS)':
 'MD_ALERT_L': CDS_PINID='MD_ALERT_L';
NODE_NAME     R378 2
 '@T6G_MB_LIB.T6G(SCH_1):PAGE13_I314@PURE_QUANTA.Q_RES(CHIPS)':
 'B': CDS_PINID='B';
NET_NAME
'M_D_CPU0_CLK_DN<0>'
 '@T6G_MB_LIB.T6G(SCH_1):M_D_CPU0_CLK_DN'<0>:
 C_SIGNAL='@t6g_mb_lib.t6g(sch_1):m_d_cpu0_clk_dn(0)';
NODE_NAME     U25 BD60
 '@T6G_MB_LIB.T6G(SCH_1):PAGE13_I159@PURE_QUANTA.GENOA_SP5(CHIPS)':
 'MD0_CLK_L': CDS_PINID='MD0_CLK_L';
NODE_NAME     J19 218
 '@T6G_MB_LIB.T6G(SCH_1):PAGE88_I350@PURE_QUANTA.SCONN288_DDR506112002KQ(CHIPS)':
 'CK_C': CDS_PINID='CK_C';
NET_NAME
'M_D_CPU0_CLK_DP<0>'
 '@T6G_MB_LIB.T6G(SCH_1):M_D_CPU0_CLK_DP'<0>:
 C_SIGNAL='@t6g_mb_lib.t6g(sch_1):m_d_cpu0_clk_dp(0)';
NODE_NAME     U25 BC60
 '@T6G_MB_LIB.T6G(SCH_1):PAGE13_I159@PURE_QUANTA.GENOA_SP5(CHIPS)':
 'MD0_CLK_H': CDS_PINID='MD0_CLK_H';
NODE_NAME     J19 217
 '@T6G_MB_LIB.T6G(SCH_1):PAGE88_I350@PURE_QUANTA.SCONN288_DDR506112002KQ(CHIPS)':
 'CK_T': CDS_PINID='CK_T';
NET_NAME
'M_D_CPU0_RESET_N'
 '@T6G_MB_LIB.T6G(SCH_1):M_D_CPU0_RESET_N':
 C_SIGNAL='@t6g_mb_lib.t6g(sch_1):m_d_cpu0_reset_n';
NODE_NAME     U25 AU59
 '@T6G_MB_LIB.T6G(SCH_1):PAGE13_I159@PURE_QUANTA.GENOA_SP5(CHIPS)':
 'MD_RESET_L': CDS_PINID='MD_RESET_L';
NODE_NAME     J19 207
 '@T6G_MB_LIB.T6G(SCH_1):PAGE88_I350@PURE_QUANTA.SCONN288_DDR506112002KQ(CHIPS)':
 'RESET_N': CDS_PINID='RESET_N';
NET_NAME
'M_D_CPU0_SA_CA<0>'
 '@T6G_MB_LIB.T6G(SCH_1):M_D_CPU0_SA_CA'<0>:
 C_SIGNAL='@t6g_mb_lib.t6g(sch_1):m_d_cpu0_sa_ca(0)';
NODE_NAME     U25 AW60
 '@T6G_MB_LIB.T6G(SCH_1):PAGE13_I159@PURE_QUANTA.GENOA_SP5(CHIPS)':
 'MDA_CA0': CDS_PINID='MDA_CA0';
NODE_NAME     J19 66
 '@T6G_MB_LIB.T6G(SCH_1):PAGE88_I350@PURE_QUANTA.SCONN288_DDR506112002KQ(CHIPS)':
 'CA0_A': CDS_PINID='CA0_A';
NET_NAME
'M_D_CPU0_SA_CA<1>'
 '@T6G_MB_LIB.T6G(SCH_1):M_D_CPU0_SA_CA'<1>:
 C_SIGNAL='@t6g_mb_lib.t6g(sch_1):m_d_cpu0_sa_ca(1)';
NODE_NAME     U25 AY60
 '@T6G_MB_LIB.T6G(SCH_1):PAGE13_I159@PURE_QUANTA.GENOA_SP5(CHIPS)':
 'MDA_CA1': CDS_PINID='MDA_CA1';
NODE_NAME     J19 211
 '@T6G_MB_LIB.T6G(SCH_1):PAGE88_I350@PURE_QUANTA.SCONN288_DDR506112002KQ(CHIPS)':
 'CA1_A': CDS_PINID='CA1_A';
NET_NAME
'M_D_CPU0_SA_CA<2>'
 '@T6G_MB_LIB.T6G(SCH_1):M_D_CPU0_SA_CA'<2>:
 C_SIGNAL='@t6g_mb_lib.t6g(sch_1):m_d_cpu0_sa_ca(2)';
NODE_NAME     U25 AY58
 '@T6G_MB_LIB.T6G(SCH_1):PAGE13_I159@PURE_QUANTA.GENOA_SP5(CHIPS)':
 'MDA_CA2': CDS_PINID='MDA_CA2';
NODE_NAME     J19 68
 '@T6G_MB_LIB.T6G(SCH_1):PAGE88_I350@PURE_QUANTA.SCONN288_DDR506112002KQ(CHIPS)':
 'CA2_A': CDS_PINID='CA2_A';
NET_NAME
'M_D_CPU0_SA_CA<3>'
 '@T6G_MB_LIB.T6G(SCH_1):M_D_CPU0_SA_CA'<3>:
 C_SIGNAL='@t6g_mb_lib.t6g(sch_1):m_d_cpu0_sa_ca(3)';
NODE_NAME     U25 BA59
 '@T6G_MB_LIB.T6G(SCH_1):PAGE13_I159@PURE_QUANTA.GENOA_SP5(CHIPS)':
 'MDA_CA3': CDS_PINID='MDA_CA3';
NODE_NAME     J19 213
 '@T6G_MB_LIB.T6G(SCH_1):PAGE88_I350@PURE_QUANTA.SCONN288_DDR506112002KQ(CHIPS)':
 'CA3_A': CDS_PINID='CA3_A';
NET_NAME
'M_D_CPU0_SA_CA<4>'
 '@T6G_MB_LIB.T6G(SCH_1):M_D_CPU0_SA_CA'<4>:
 C_SIGNAL='@t6g_mb_lib.t6g(sch_1):m_d_cpu0_sa_ca(4)';
NODE_NAME     U25 BA60
 '@T6G_MB_LIB.T6G(SCH_1):PAGE13_I159@PURE_QUANTA.GENOA_SP5(CHIPS)':
 'MDA_CA4': CDS_PINID='MDA_CA4';
NODE_NAME     J19 70
 '@T6G_MB_LIB.T6G(SCH_1):PAGE88_I350@PURE_QUANTA.SCONN288_DDR506112002KQ(CHIPS)':
 'CA4_A': CDS_PINID='CA4_A';
NET_NAME
'M_D_CPU0_SA_CA<5>'
 '@T6G_MB_LIB.T6G(SCH_1):M_D_CPU0_SA_CA'<5>:
 C_SIGNAL='@t6g_mb_lib.t6g(sch_1):m_d_cpu0_sa_ca(5)';
NODE_NAME     U25 BB60
 '@T6G_MB_LIB.T6G(SCH_1):PAGE13_I159@PURE_QUANTA.GENOA_SP5(CHIPS)':
 'MDA_CA5': CDS_PINID='MDA_CA5';
NODE_NAME     J19 215
 '@T6G_MB_LIB.T6G(SCH_1):PAGE88_I350@PURE_QUANTA.SCONN288_DDR506112002KQ(CHIPS)':
 'CA5_A': CDS_PINID='CA5_A';
NET_NAME
'M_D_CPU0_SA_CA<6>'
 '@T6G_MB_LIB.T6G(SCH_1):M_D_CPU0_SA_CA'<6>:
 C_SIGNAL='@t6g_mb_lib.t6g(sch_1):m_d_cpu0_sa_ca(6)';
NODE_NAME     U25 BB58
 '@T6G_MB_LIB.T6G(SCH_1):PAGE13_I159@PURE_QUANTA.GENOA_SP5(CHIPS)':
 'MDA_CA6': CDS_PINID='MDA_CA6';
NODE_NAME     J19 72
 '@T6G_MB_LIB.T6G(SCH_1):PAGE88_I350@PURE_QUANTA.SCONN288_DDR506112002KQ(CHIPS)':
 'CA6_A': CDS_PINID='CA6_A';
NET_NAME
'M_D_CPU0_SA_CB<0>'
 '@T6G_MB_LIB.T6G(SCH_1):M_D_CPU0_SA_CB'<0>:
 C_SIGNAL='@t6g_mb_lib.t6g(sch_1):m_d_cpu0_sa_cb(0)';
NODE_NAME     U25 AJ60
 '@T6G_MB_LIB.T6G(SCH_1):PAGE13_I159@PURE_QUANTA.GENOA_SP5(CHIPS)':
 'MDA_CHECK0': CDS_PINID='MDA_CHECK0';
NODE_NAME     J19 51
 '@T6G_MB_LIB.T6G(SCH_1):PAGE88_I350@PURE_QUANTA.SCONN288_DDR506112002KQ(CHIPS)':
 'CB0_A': CDS_PINID='CB0_A';
NET_NAME
'M_D_CPU0_SA_CB<1>'
 '@T6G_MB_LIB.T6G(SCH_1):M_D_CPU0_SA_CB'<1>:
 C_SIGNAL='@t6g_mb_lib.t6g(sch_1):m_d_cpu0_sa_cb(1)';
NODE_NAME     U25 AK58
 '@T6G_MB_LIB.T6G(SCH_1):PAGE13_I159@PURE_QUANTA.GENOA_SP5(CHIPS)':
 'MDA_CHECK1': CDS_PINID='MDA_CHECK1';
NODE_NAME     J19 53
 '@T6G_MB_LIB.T6G(SCH_1):PAGE88_I350@PURE_QUANTA.SCONN288_DDR506112002KQ(CHIPS)':
 'CB1_A': CDS_PINID='CB1_A';
NET_NAME
'M_D_CPU0_SA_CB<2>'
 '@T6G_MB_LIB.T6G(SCH_1):M_D_CPU0_SA_CB'<2>:
 C_SIGNAL='@t6g_mb_lib.t6g(sch_1):m_d_cpu0_sa_cb(2)';
NODE_NAME     U25 AK60
 '@T6G_MB_LIB.T6G(SCH_1):PAGE13_I159@PURE_QUANTA.GENOA_SP5(CHIPS)':
 'MDA_CHECK2': CDS_PINID='MDA_CHECK2';
NODE_NAME     J19 196
 '@T6G_MB_LIB.T6G(SCH_1):PAGE88_I350@PURE_QUANTA.SCONN288_DDR506112002KQ(CHIPS)':
 'CB2_A': CDS_PINID='CB2_A';
NET_NAME
'M_D_CPU0_SA_CB<3>'
 '@T6G_MB_LIB.T6G(SCH_1):M_D_CPU0_SA_CB'<3>:
 C_SIGNAL='@t6g_mb_lib.t6g(sch_1):m_d_cpu0_sa_cb(3)';
NODE_NAME     U25 AL59
 '@T6G_MB_LIB.T6G(SCH_1):PAGE13_I159@PURE_QUANTA.GENOA_SP5(CHIPS)':
 'MDA_CHECK3': CDS_PINID='MDA_CHECK3';
NODE_NAME     J19 198
 '@T6G_MB_LIB.T6G(SCH_1):PAGE88_I350@PURE_QUANTA.SCONN288_DDR506112002KQ(CHIPS)':
 'CB3_A': CDS_PINID='CB3_A';
NET_NAME
'M_D_CPU0_SA_CB<4>'
 '@T6G_MB_LIB.T6G(SCH_1):M_D_CPU0_SA_CB'<4>:
 C_SIGNAL='@t6g_mb_lib.t6g(sch_1):m_d_cpu0_sa_cb(4)';
NODE_NAME     U25 AN60
 '@T6G_MB_LIB.T6G(SCH_1):PAGE13_I159@PURE_QUANTA.GENOA_SP5(CHIPS)':
 'MDA_CHECK4': CDS_PINID='MDA_CHECK4';
NODE_NAME     J19 58
 '@T6G_MB_LIB.T6G(SCH_1):PAGE88_I350@PURE_QUANTA.SCONN288_DDR506112002KQ(CHIPS)':
 'CB4_A': CDS_PINID='CB4_A';
NET_NAME
'M_D_CPU0_SA_CB<5>'
 '@T6G_MB_LIB.T6G(SCH_1):M_D_CPU0_SA_CB'<5>:
 C_SIGNAL='@t6g_mb_lib.t6g(sch_1):m_d_cpu0_sa_cb(5)';
NODE_NAME     U25 AP58
 '@T6G_MB_LIB.T6G(SCH_1):PAGE13_I159@PURE_QUANTA.GENOA_SP5(CHIPS)':
 'MDA_CHECK5': CDS_PINID='MDA_CHECK5';
NODE_NAME     J19 60
 '@T6G_MB_LIB.T6G(SCH_1):PAGE88_I350@PURE_QUANTA.SCONN288_DDR506112002KQ(CHIPS)':
 'CB5_A': CDS_PINID='CB5_A';
NET_NAME
'M_D_CPU0_SA_CB<6>'
 '@T6G_MB_LIB.T6G(SCH_1):M_D_CPU0_SA_CB'<6>:
 C_SIGNAL='@t6g_mb_lib.t6g(sch_1):m_d_cpu0_sa_cb(6)';
NODE_NAME     U25 AP60
 '@T6G_MB_LIB.T6G(SCH_1):PAGE13_I159@PURE_QUANTA.GENOA_SP5(CHIPS)':
 'MDA_CHECK6': CDS_PINID='MDA_CHECK6';
NODE_NAME     J19 203
 '@T6G_MB_LIB.T6G(SCH_1):PAGE88_I350@PURE_QUANTA.SCONN288_DDR506112002KQ(CHIPS)':
 'CB6_A': CDS_PINID='CB6_A';
NET_NAME
'M_D_CPU0_SA_CB<7>'
 '@T6G_MB_LIB.T6G(SCH_1):M_D_CPU0_SA_CB'<7>:
 C_SIGNAL='@t6g_mb_lib.t6g(sch_1):m_d_cpu0_sa_cb(7)';
NODE_NAME     U25 AR59
 '@T6G_MB_LIB.T6G(SCH_1):PAGE13_I159@PURE_QUANTA.GENOA_SP5(CHIPS)':
 'MDA_CHECK7': CDS_PINID='MDA_CHECK7';
NODE_NAME     J19 205
 '@T6G_MB_LIB.T6G(SCH_1):PAGE88_I350@PURE_QUANTA.SCONN288_DDR506112002KQ(CHIPS)':
 'CB7_A': CDS_PINID='CB7_A';
NET_NAME
'M_D_CPU0_SA_CS_N<0>'
 '@T6G_MB_LIB.T6G(SCH_1):M_D_CPU0_SA_CS_N'<0>:
 C_SIGNAL='@t6g_mb_lib.t6g(sch_1):m_d_cpu0_sa_cs_n(0)';
NODE_NAME     U25 AV60
 '@T6G_MB_LIB.T6G(SCH_1):PAGE13_I159@PURE_QUANTA.GENOA_SP5(CHIPS)':
 'MDA0_CS_L0': CDS_PINID='MDA0_CS_L0';
NODE_NAME     J19 64
 '@T6G_MB_LIB.T6G(SCH_1):PAGE88_I350@PURE_QUANTA.SCONN288_DDR506112002KQ(CHIPS)':
 'CS0_A_N': CDS_PINID='CS0_A_N';
NET_NAME
'M_D_CPU0_SA_CS_N<1>'
 '@T6G_MB_LIB.T6G(SCH_1):M_D_CPU0_SA_CS_N'<1>:
 C_SIGNAL='@t6g_mb_lib.t6g(sch_1):m_d_cpu0_sa_cs_n(1)';
NODE_NAME     U25 AW59
 '@T6G_MB_LIB.T6G(SCH_1):PAGE13_I159@PURE_QUANTA.GENOA_SP5(CHIPS)':
 'MDA0_CS_L1': CDS_PINID='MDA0_CS_L1';
NODE_NAME     J19 209
 '@T6G_MB_LIB.T6G(SCH_1):PAGE88_I350@PURE_QUANTA.SCONN288_DDR506112002KQ(CHIPS)':
 'CS1_A_N': CDS_PINID='CS1_A_N';
NET_NAME
'M_D_CPU0_SA_DQ<0>'
 '@T6G_MB_LIB.T6G(SCH_1):M_D_CPU0_SA_DQ'<0>:
 C_SIGNAL='@t6g_mb_lib.t6g(sch_1):m_d_cpu0_sa_dq(0)';
NODE_NAME     U25 E60
 '@T6G_MB_LIB.T6G(SCH_1):PAGE13_I159@PURE_QUANTA.GENOA_SP5(CHIPS)':
 'MDA_DATA0': CDS_PINID='MDA_DATA0';
NODE_NAME     J19 7
 '@T6G_MB_LIB.T6G(SCH_1):PAGE88_I350@PURE_QUANTA.SCONN288_DDR506112002KQ(CHIPS)':
 'DQ0_A': CDS_PINID='DQ0_A';
NET_NAME
'M_D_CPU0_SA_DQ<10>'
 '@T6G_MB_LIB.T6G(SCH_1):M_D_CPU0_SA_DQ'<10>:
 C_SIGNAL='@t6g_mb_lib.t6g(sch_1):m_d_cpu0_sa_dq(10)';
NODE_NAME     U25 M60
 '@T6G_MB_LIB.T6G(SCH_1):PAGE13_I159@PURE_QUANTA.GENOA_SP5(CHIPS)':
 'MDA_DATA10': CDS_PINID='MDA_DATA10';
NODE_NAME     J19 163
 '@T6G_MB_LIB.T6G(SCH_1):PAGE88_I350@PURE_QUANTA.SCONN288_DDR506112002KQ(CHIPS)':
 'DQ10_A': CDS_PINID='DQ10_A';
NET_NAME
'M_D_CPU0_SA_DQ<11>'
 '@T6G_MB_LIB.T6G(SCH_1):M_D_CPU0_SA_DQ'<11>:
 C_SIGNAL='@t6g_mb_lib.t6g(sch_1):m_d_cpu0_sa_dq(11)';
NODE_NAME     U25 N59
 '@T6G_MB_LIB.T6G(SCH_1):PAGE13_I159@PURE_QUANTA.GENOA_SP5(CHIPS)':
 'MDA_DATA11': CDS_PINID='MDA_DATA11';
NODE_NAME     J19 165
 '@T6G_MB_LIB.T6G(SCH_1):PAGE88_I350@PURE_QUANTA.SCONN288_DDR506112002KQ(CHIPS)':
 'DQ11_A': CDS_PINID='DQ11_A';
NET_NAME
'M_D_CPU0_SA_DQ<12>'
 '@T6G_MB_LIB.T6G(SCH_1):M_D_CPU0_SA_DQ'<12>:
 C_SIGNAL='@t6g_mb_lib.t6g(sch_1):m_d_cpu0_sa_dq(12)';
NODE_NAME     U25 R60
 '@T6G_MB_LIB.T6G(SCH_1):PAGE13_I159@PURE_QUANTA.GENOA_SP5(CHIPS)':
 'MDA_DATA12': CDS_PINID='MDA_DATA12';
NODE_NAME     J19 25
 '@T6G_MB_LIB.T6G(SCH_1):PAGE88_I350@PURE_QUANTA.SCONN288_DDR506112002KQ(CHIPS)':
 'DQ12_A': CDS_PINID='DQ12_A';
NET_NAME
'M_D_CPU0_SA_DQ<13>'
 '@T6G_MB_LIB.T6G(SCH_1):M_D_CPU0_SA_DQ'<13>:
 C_SIGNAL='@t6g_mb_lib.t6g(sch_1):m_d_cpu0_sa_dq(13)';
NODE_NAME     U25 T58
 '@T6G_MB_LIB.T6G(SCH_1):PAGE13_I159@PURE_QUANTA.GENOA_SP5(CHIPS)':
 'MDA_DATA13': CDS_PINID='MDA_DATA13';
NODE_NAME     J19 27
 '@T6G_MB_LIB.T6G(SCH_1):PAGE88_I350@PURE_QUANTA.SCONN288_DDR506112002KQ(CHIPS)':
 'DQ13_A': CDS_PINID='DQ13_A';
NET_NAME
'M_D_CPU0_SA_DQ<14>'
 '@T6G_MB_LIB.T6G(SCH_1):M_D_CPU0_SA_DQ'<14>:
 C_SIGNAL='@t6g_mb_lib.t6g(sch_1):m_d_cpu0_sa_dq(14)';
NODE_NAME     U25 T60
 '@T6G_MB_LIB.T6G(SCH_1):PAGE13_I159@PURE_QUANTA.GENOA_SP5(CHIPS)':
 'MDA_DATA14': CDS_PINID='MDA_DATA14';
NODE_NAME     J19 170
 '@T6G_MB_LIB.T6G(SCH_1):PAGE88_I350@PURE_QUANTA.SCONN288_DDR506112002KQ(CHIPS)':
 'DQ14_A': CDS_PINID='DQ14_A';
NET_NAME
'M_D_CPU0_SA_DQ<15>'
 '@T6G_MB_LIB.T6G(SCH_1):M_D_CPU0_SA_DQ'<15>:
 C_SIGNAL='@t6g_mb_lib.t6g(sch_1):m_d_cpu0_sa_dq(15)';
NODE_NAME     U25 U59
 '@T6G_MB_LIB.T6G(SCH_1):PAGE13_I159@PURE_QUANTA.GENOA_SP5(CHIPS)':
 'MDA_DATA15': CDS_PINID='MDA_DATA15';
NODE_NAME     J19 172
 '@T6G_MB_LIB.T6G(SCH_1):PAGE88_I350@PURE_QUANTA.SCONN288_DDR506112002KQ(CHIPS)':
 'DQ15_A': CDS_PINID='DQ15_A';
NET_NAME
'M_D_CPU0_SA_DQ<16>'
 '@T6G_MB_LIB.T6G(SCH_1):M_D_CPU0_SA_DQ'<16>:
 C_SIGNAL='@t6g_mb_lib.t6g(sch_1):m_d_cpu0_sa_dq(16)';
NODE_NAME     U25 U60
 '@T6G_MB_LIB.T6G(SCH_1):PAGE13_I159@PURE_QUANTA.GENOA_SP5(CHIPS)':
 'MDA_DATA16': CDS_PINID='MDA_DATA16';
NODE_NAME     J19 29
 '@T6G_MB_LIB.T6G(SCH_1):PAGE88_I350@PURE_QUANTA.SCONN288_DDR506112002KQ(CHIPS)':
 'DQ16_A': CDS_PINID='DQ16_A';
NET_NAME
'M_D_CPU0_SA_DQ<17>'
 '@T6G_MB_LIB.T6G(SCH_1):M_D_CPU0_SA_DQ'<17>:
 C_SIGNAL='@t6g_mb_lib.t6g(sch_1):m_d_cpu0_sa_dq(17)';
NODE_NAME     U25 V58
 '@T6G_MB_LIB.T6G(SCH_1):PAGE13_I159@PURE_QUANTA.GENOA_SP5(CHIPS)':
 'MDA_DATA17': CDS_PINID='MDA_DATA17';
NODE_NAME     J19 31
 '@T6G_MB_LIB.T6G(SCH_1):PAGE88_I350@PURE_QUANTA.SCONN288_DDR506112002KQ(CHIPS)':
 'DQ17_A': CDS_PINID='DQ17_A';
NET_NAME
'M_D_CPU0_SA_DQ<18>'
 '@T6G_MB_LIB.T6G(SCH_1):M_D_CPU0_SA_DQ'<18>:
 C_SIGNAL='@t6g_mb_lib.t6g(sch_1):m_d_cpu0_sa_dq(18)';
NODE_NAME     U25 V60
 '@T6G_MB_LIB.T6G(SCH_1):PAGE13_I159@PURE_QUANTA.GENOA_SP5(CHIPS)':
 'MDA_DATA18': CDS_PINID='MDA_DATA18';
NODE_NAME     J19 174
 '@T6G_MB_LIB.T6G(SCH_1):PAGE88_I350@PURE_QUANTA.SCONN288_DDR506112002KQ(CHIPS)':
 'DQ18_A': CDS_PINID='DQ18_A';
NET_NAME
'M_D_CPU0_SA_DQ<19>'
 '@T6G_MB_LIB.T6G(SCH_1):M_D_CPU0_SA_DQ'<19>:
 C_SIGNAL='@t6g_mb_lib.t6g(sch_1):m_d_cpu0_sa_dq(19)';
NODE_NAME     U25 W59
 '@T6G_MB_LIB.T6G(SCH_1):PAGE13_I159@PURE_QUANTA.GENOA_SP5(CHIPS)':
 'MDA_DATA19': CDS_PINID='MDA_DATA19';
NODE_NAME     J19 176
 '@T6G_MB_LIB.T6G(SCH_1):PAGE88_I350@PURE_QUANTA.SCONN288_DDR506112002KQ(CHIPS)':
 'DQ19_A': CDS_PINID='DQ19_A';
NET_NAME
'M_D_CPU0_SA_DQ<1>'
 '@T6G_MB_LIB.T6G(SCH_1):M_D_CPU0_SA_DQ'<1>:
 C_SIGNAL='@t6g_mb_lib.t6g(sch_1):m_d_cpu0_sa_dq(1)';
NODE_NAME     U25 F58
 '@T6G_MB_LIB.T6G(SCH_1):PAGE13_I159@PURE_QUANTA.GENOA_SP5(CHIPS)':
 'MDA_DATA1': CDS_PINID='MDA_DATA1';
NODE_NAME     J19 9
 '@T6G_MB_LIB.T6G(SCH_1):PAGE88_I350@PURE_QUANTA.SCONN288_DDR506112002KQ(CHIPS)':
 'DQ1_A': CDS_PINID='DQ1_A';
NET_NAME
'M_D_CPU0_SA_DQ<20>'
 '@T6G_MB_LIB.T6G(SCH_1):M_D_CPU0_SA_DQ'<20>:
 C_SIGNAL='@t6g_mb_lib.t6g(sch_1):m_d_cpu0_sa_dq(20)';
NODE_NAME     U25 AA60
 '@T6G_MB_LIB.T6G(SCH_1):PAGE13_I159@PURE_QUANTA.GENOA_SP5(CHIPS)':
 'MDA_DATA20': CDS_PINID='MDA_DATA20';
NODE_NAME     J19 36
 '@T6G_MB_LIB.T6G(SCH_1):PAGE88_I350@PURE_QUANTA.SCONN288_DDR506112002KQ(CHIPS)':
 'DQ20_A': CDS_PINID='DQ20_A';
NET_NAME
'M_D_CPU0_SA_DQ<21>'
 '@T6G_MB_LIB.T6G(SCH_1):M_D_CPU0_SA_DQ'<21>:
 C_SIGNAL='@t6g_mb_lib.t6g(sch_1):m_d_cpu0_sa_dq(21)';
NODE_NAME     U25 AB58
 '@T6G_MB_LIB.T6G(SCH_1):PAGE13_I159@PURE_QUANTA.GENOA_SP5(CHIPS)':
 'MDA_DATA21': CDS_PINID='MDA_DATA21';
NODE_NAME     J19 38
 '@T6G_MB_LIB.T6G(SCH_1):PAGE88_I350@PURE_QUANTA.SCONN288_DDR506112002KQ(CHIPS)':
 'DQ21_A': CDS_PINID='DQ21_A';
NET_NAME
'M_D_CPU0_SA_DQ<22>'
 '@T6G_MB_LIB.T6G(SCH_1):M_D_CPU0_SA_DQ'<22>:
 C_SIGNAL='@t6g_mb_lib.t6g(sch_1):m_d_cpu0_sa_dq(22)';
NODE_NAME     U25 AB60
 '@T6G_MB_LIB.T6G(SCH_1):PAGE13_I159@PURE_QUANTA.GENOA_SP5(CHIPS)':
 'MDA_DATA22': CDS_PINID='MDA_DATA22';
NODE_NAME     J19 181
 '@T6G_MB_LIB.T6G(SCH_1):PAGE88_I350@PURE_QUANTA.SCONN288_DDR506112002KQ(CHIPS)':
 'DQ22_A': CDS_PINID='DQ22_A';
NET_NAME
'M_D_CPU0_SA_DQ<23>'
 '@T6G_MB_LIB.T6G(SCH_1):M_D_CPU0_SA_DQ'<23>:
 C_SIGNAL='@t6g_mb_lib.t6g(sch_1):m_d_cpu0_sa_dq(23)';
NODE_NAME     U25 AC59
 '@T6G_MB_LIB.T6G(SCH_1):PAGE13_I159@PURE_QUANTA.GENOA_SP5(CHIPS)':
 'MDA_DATA23': CDS_PINID='MDA_DATA23';
NODE_NAME     J19 183
 '@T6G_MB_LIB.T6G(SCH_1):PAGE88_I350@PURE_QUANTA.SCONN288_DDR506112002KQ(CHIPS)':
 'DQ23_A': CDS_PINID='DQ23_A';
NET_NAME
'M_D_CPU0_SA_DQ<24>'
 '@T6G_MB_LIB.T6G(SCH_1):M_D_CPU0_SA_DQ'<24>:
 C_SIGNAL='@t6g_mb_lib.t6g(sch_1):m_d_cpu0_sa_dq(24)';
NODE_NAME     U25 AC60
 '@T6G_MB_LIB.T6G(SCH_1):PAGE13_I159@PURE_QUANTA.GENOA_SP5(CHIPS)':
 'MDA_DATA24': CDS_PINID='MDA_DATA24';
NODE_NAME     J19 40
 '@T6G_MB_LIB.T6G(SCH_1):PAGE88_I350@PURE_QUANTA.SCONN288_DDR506112002KQ(CHIPS)':
 'DQ24_A': CDS_PINID='DQ24_A';
NET_NAME
'M_D_CPU0_SA_DQ<25>'
 '@T6G_MB_LIB.T6G(SCH_1):M_D_CPU0_SA_DQ'<25>:
 C_SIGNAL='@t6g_mb_lib.t6g(sch_1):m_d_cpu0_sa_dq(25)';
NODE_NAME     U25 AD58
 '@T6G_MB_LIB.T6G(SCH_1):PAGE13_I159@PURE_QUANTA.GENOA_SP5(CHIPS)':
 'MDA_DATA25': CDS_PINID='MDA_DATA25';
NODE_NAME     J19 42
 '@T6G_MB_LIB.T6G(SCH_1):PAGE88_I350@PURE_QUANTA.SCONN288_DDR506112002KQ(CHIPS)':
 'DQ25_A': CDS_PINID='DQ25_A';
NET_NAME
'M_D_CPU0_SA_DQ<26>'
 '@T6G_MB_LIB.T6G(SCH_1):M_D_CPU0_SA_DQ'<26>:
 C_SIGNAL='@t6g_mb_lib.t6g(sch_1):m_d_cpu0_sa_dq(26)';
NODE_NAME     U25 AD60
 '@T6G_MB_LIB.T6G(SCH_1):PAGE13_I159@PURE_QUANTA.GENOA_SP5(CHIPS)':
 'MDA_DATA26': CDS_PINID='MDA_DATA26';
NODE_NAME     J19 185
 '@T6G_MB_LIB.T6G(SCH_1):PAGE88_I350@PURE_QUANTA.SCONN288_DDR506112002KQ(CHIPS)':
 'DQ26_A': CDS_PINID='DQ26_A';
NET_NAME
'M_D_CPU0_SA_DQ<27>'
 '@T6G_MB_LIB.T6G(SCH_1):M_D_CPU0_SA_DQ'<27>:
 C_SIGNAL='@t6g_mb_lib.t6g(sch_1):m_d_cpu0_sa_dq(27)';
NODE_NAME     U25 AE59
 '@T6G_MB_LIB.T6G(SCH_1):PAGE13_I159@PURE_QUANTA.GENOA_SP5(CHIPS)':
 'MDA_DATA27': CDS_PINID='MDA_DATA27';
NODE_NAME     J19 187
 '@T6G_MB_LIB.T6G(SCH_1):PAGE88_I350@PURE_QUANTA.SCONN288_DDR506112002KQ(CHIPS)':
 'DQ27_A': CDS_PINID='DQ27_A';
NET_NAME
'M_D_CPU0_SA_DQ<28>'
 '@T6G_MB_LIB.T6G(SCH_1):M_D_CPU0_SA_DQ'<28>:
 C_SIGNAL='@t6g_mb_lib.t6g(sch_1):m_d_cpu0_sa_dq(28)';
NODE_NAME     U25 AG60
 '@T6G_MB_LIB.T6G(SCH_1):PAGE13_I159@PURE_QUANTA.GENOA_SP5(CHIPS)':
 'MDA_DATA28': CDS_PINID='MDA_DATA28';
NODE_NAME     J19 47
 '@T6G_MB_LIB.T6G(SCH_1):PAGE88_I350@PURE_QUANTA.SCONN288_DDR506112002KQ(CHIPS)':
 'DQ28_A': CDS_PINID='DQ28_A';
NET_NAME
'M_D_CPU0_SA_DQ<29>'
 '@T6G_MB_LIB.T6G(SCH_1):M_D_CPU0_SA_DQ'<29>:
 C_SIGNAL='@t6g_mb_lib.t6g(sch_1):m_d_cpu0_sa_dq(29)';
NODE_NAME     U25 AH58
 '@T6G_MB_LIB.T6G(SCH_1):PAGE13_I159@PURE_QUANTA.GENOA_SP5(CHIPS)':
 'MDA_DATA29': CDS_PINID='MDA_DATA29';
NODE_NAME     J19 49
 '@T6G_MB_LIB.T6G(SCH_1):PAGE88_I350@PURE_QUANTA.SCONN288_DDR506112002KQ(CHIPS)':
 'DQ29_A': CDS_PINID='DQ29_A';
NET_NAME
'M_D_CPU0_SA_DQ<2>'
 '@T6G_MB_LIB.T6G(SCH_1):M_D_CPU0_SA_DQ'<2>:
 C_SIGNAL='@t6g_mb_lib.t6g(sch_1):m_d_cpu0_sa_dq(2)';
NODE_NAME     U25 F60
 '@T6G_MB_LIB.T6G(SCH_1):PAGE13_I159@PURE_QUANTA.GENOA_SP5(CHIPS)':
 'MDA_DATA2': CDS_PINID='MDA_DATA2';
NODE_NAME     J19 152
 '@T6G_MB_LIB.T6G(SCH_1):PAGE88_I350@PURE_QUANTA.SCONN288_DDR506112002KQ(CHIPS)':
 'DQ2_A': CDS_PINID='DQ2_A';
NET_NAME
'M_D_CPU0_SA_DQ<30>'
 '@T6G_MB_LIB.T6G(SCH_1):M_D_CPU0_SA_DQ'<30>:
 C_SIGNAL='@t6g_mb_lib.t6g(sch_1):m_d_cpu0_sa_dq(30)';
NODE_NAME     U25 AH60
 '@T6G_MB_LIB.T6G(SCH_1):PAGE13_I159@PURE_QUANTA.GENOA_SP5(CHIPS)':
 'MDA_DATA30': CDS_PINID='MDA_DATA30';
NODE_NAME     J19 192
 '@T6G_MB_LIB.T6G(SCH_1):PAGE88_I350@PURE_QUANTA.SCONN288_DDR506112002KQ(CHIPS)':
 'DQ30_A': CDS_PINID='DQ30_A';
NET_NAME
'M_D_CPU0_SA_DQ<31>'
 '@T6G_MB_LIB.T6G(SCH_1):M_D_CPU0_SA_DQ'<31>:
 C_SIGNAL='@t6g_mb_lib.t6g(sch_1):m_d_cpu0_sa_dq(31)';
NODE_NAME     U25 AJ59
 '@T6G_MB_LIB.T6G(SCH_1):PAGE13_I159@PURE_QUANTA.GENOA_SP5(CHIPS)':
 'MDA_DATA31': CDS_PINID='MDA_DATA31';
NODE_NAME     J19 194
 '@T6G_MB_LIB.T6G(SCH_1):PAGE88_I350@PURE_QUANTA.SCONN288_DDR506112002KQ(CHIPS)':
 'DQ31_A': CDS_PINID='DQ31_A';
NET_NAME
'M_D_CPU0_SA_DQ<3>'
 '@T6G_MB_LIB.T6G(SCH_1):M_D_CPU0_SA_DQ'<3>:
 C_SIGNAL='@t6g_mb_lib.t6g(sch_1):m_d_cpu0_sa_dq(3)';
NODE_NAME     U25 G59
 '@T6G_MB_LIB.T6G(SCH_1):PAGE13_I159@PURE_QUANTA.GENOA_SP5(CHIPS)':
 'MDA_DATA3': CDS_PINID='MDA_DATA3';
NODE_NAME     J19 154
 '@T6G_MB_LIB.T6G(SCH_1):PAGE88_I350@PURE_QUANTA.SCONN288_DDR506112002KQ(CHIPS)':
 'DQ3_A': CDS_PINID='DQ3_A';
NET_NAME
'M_D_CPU0_SA_DQ<4>'
 '@T6G_MB_LIB.T6G(SCH_1):M_D_CPU0_SA_DQ'<4>:
 C_SIGNAL='@t6g_mb_lib.t6g(sch_1):m_d_cpu0_sa_dq(4)';
NODE_NAME     U25 J60
 '@T6G_MB_LIB.T6G(SCH_1):PAGE13_I159@PURE_QUANTA.GENOA_SP5(CHIPS)':
 'MDA_DATA4': CDS_PINID='MDA_DATA4';
NODE_NAME     J19 14
 '@T6G_MB_LIB.T6G(SCH_1):PAGE88_I350@PURE_QUANTA.SCONN288_DDR506112002KQ(CHIPS)':
 'DQ4_A': CDS_PINID='DQ4_A';
NET_NAME
'M_D_CPU0_SA_DQ<5>'
 '@T6G_MB_LIB.T6G(SCH_1):M_D_CPU0_SA_DQ'<5>:
 C_SIGNAL='@t6g_mb_lib.t6g(sch_1):m_d_cpu0_sa_dq(5)';
NODE_NAME     U25 K58
 '@T6G_MB_LIB.T6G(SCH_1):PAGE13_I159@PURE_QUANTA.GENOA_SP5(CHIPS)':
 'MDA_DATA5': CDS_PINID='MDA_DATA5';
NODE_NAME     J19 16
 '@T6G_MB_LIB.T6G(SCH_1):PAGE88_I350@PURE_QUANTA.SCONN288_DDR506112002KQ(CHIPS)':
 'DQ5_A': CDS_PINID='DQ5_A';
NET_NAME
'M_D_CPU0_SA_DQ<6>'
 '@T6G_MB_LIB.T6G(SCH_1):M_D_CPU0_SA_DQ'<6>:
 C_SIGNAL='@t6g_mb_lib.t6g(sch_1):m_d_cpu0_sa_dq(6)';
NODE_NAME     U25 K60
 '@T6G_MB_LIB.T6G(SCH_1):PAGE13_I159@PURE_QUANTA.GENOA_SP5(CHIPS)':
 'MDA_DATA6': CDS_PINID='MDA_DATA6';
NODE_NAME     J19 159
 '@T6G_MB_LIB.T6G(SCH_1):PAGE88_I350@PURE_QUANTA.SCONN288_DDR506112002KQ(CHIPS)':
 'DQ6_A': CDS_PINID='DQ6_A';
NET_NAME
'M_D_CPU0_SA_DQ<7>'
 '@T6G_MB_LIB.T6G(SCH_1):M_D_CPU0_SA_DQ'<7>:
 C_SIGNAL='@t6g_mb_lib.t6g(sch_1):m_d_cpu0_sa_dq(7)';
NODE_NAME     U25 L59
 '@T6G_MB_LIB.T6G(SCH_1):PAGE13_I159@PURE_QUANTA.GENOA_SP5(CHIPS)':
 'MDA_DATA7': CDS_PINID='MDA_DATA7';
NODE_NAME     J19 161
 '@T6G_MB_LIB.T6G(SCH_1):PAGE88_I350@PURE_QUANTA.SCONN288_DDR506112002KQ(CHIPS)':
 'DQ7_A': CDS_PINID='DQ7_A';
NET_NAME
'M_D_CPU0_SA_DQ<8>'
 '@T6G_MB_LIB.T6G(SCH_1):M_D_CPU0_SA_DQ'<8>:
 C_SIGNAL='@t6g_mb_lib.t6g(sch_1):m_d_cpu0_sa_dq(8)';
NODE_NAME     U25 L60
 '@T6G_MB_LIB.T6G(SCH_1):PAGE13_I159@PURE_QUANTA.GENOA_SP5(CHIPS)':
 'MDA_DATA8': CDS_PINID='MDA_DATA8';
NODE_NAME     J19 18
 '@T6G_MB_LIB.T6G(SCH_1):PAGE88_I350@PURE_QUANTA.SCONN288_DDR506112002KQ(CHIPS)':
 'DQ8_A': CDS_PINID='DQ8_A';
NET_NAME
'M_D_CPU0_SA_DQ<9>'
 '@T6G_MB_LIB.T6G(SCH_1):M_D_CPU0_SA_DQ'<9>:
 C_SIGNAL='@t6g_mb_lib.t6g(sch_1):m_d_cpu0_sa_dq(9)';
NODE_NAME     U25 M58
 '@T6G_MB_LIB.T6G(SCH_1):PAGE13_I159@PURE_QUANTA.GENOA_SP5(CHIPS)':
 'MDA_DATA9': CDS_PINID='MDA_DATA9';
NODE_NAME     J19 20
 '@T6G_MB_LIB.T6G(SCH_1):PAGE88_I350@PURE_QUANTA.SCONN288_DDR506112002KQ(CHIPS)':
 'DQ9_A': CDS_PINID='DQ9_A';
NET_NAME
'M_D_CPU0_SA_DQS_DN<0>'
 '@T6G_MB_LIB.T6G(SCH_1):M_D_CPU0_SA_DQS_DN'<0>:
 C_SIGNAL='@t6g_mb_lib.t6g(sch_1):m_d_cpu0_sa_dqs_dn(0)';
NODE_NAME     U25 H60
 '@T6G_MB_LIB.T6G(SCH_1):PAGE13_I159@PURE_QUANTA.GENOA_SP5(CHIPS)':
 'MDA_DQS_L0': CDS_PINID='MDA_DQS_L0';
NODE_NAME     J19 12
 '@T6G_MB_LIB.T6G(SCH_1):PAGE88_I415@PURE_QUANTA.SCONN288_DDR506112002KQ(CHIPS)':
 'DQS0_A_C': CDS_PINID='DQS0_A_C';
NET_NAME
'M_D_CPU0_SA_DQS_DN<1>'
 '@T6G_MB_LIB.T6G(SCH_1):M_D_CPU0_SA_DQS_DN'<1>:
 C_SIGNAL='@t6g_mb_lib.t6g(sch_1):m_d_cpu0_sa_dqs_dn(1)';
NODE_NAME     U25 P60
 '@T6G_MB_LIB.T6G(SCH_1):PAGE13_I159@PURE_QUANTA.GENOA_SP5(CHIPS)':
 'MDA_DQS_L1': CDS_PINID='MDA_DQS_L1';
NODE_NAME     J19 23
 '@T6G_MB_LIB.T6G(SCH_1):PAGE88_I415@PURE_QUANTA.SCONN288_DDR506112002KQ(CHIPS)':
 'DQS1_A_C': CDS_PINID='DQS1_A_C';
NET_NAME
'M_D_CPU0_SA_DQS_DN<2>'
 '@T6G_MB_LIB.T6G(SCH_1):M_D_CPU0_SA_DQS_DN'<2>:
 C_SIGNAL='@t6g_mb_lib.t6g(sch_1):m_d_cpu0_sa_dqs_dn(2)';
NODE_NAME     U25 Y60
 '@T6G_MB_LIB.T6G(SCH_1):PAGE13_I159@PURE_QUANTA.GENOA_SP5(CHIPS)':
 'MDA_DQS_L2': CDS_PINID='MDA_DQS_L2';
NODE_NAME     J19 34
 '@T6G_MB_LIB.T6G(SCH_1):PAGE88_I415@PURE_QUANTA.SCONN288_DDR506112002KQ(CHIPS)':
 'DQS2_A_C': CDS_PINID='DQS2_A_C';
NET_NAME
'M_D_CPU0_SA_DQS_DN<3>'
 '@T6G_MB_LIB.T6G(SCH_1):M_D_CPU0_SA_DQS_DN'<3>:
 C_SIGNAL='@t6g_mb_lib.t6g(sch_1):m_d_cpu0_sa_dqs_dn(3)';
NODE_NAME     U25 AF60
 '@T6G_MB_LIB.T6G(SCH_1):PAGE13_I159@PURE_QUANTA.GENOA_SP5(CHIPS)':
 'MDA_DQS_L3': CDS_PINID='MDA_DQS_L3';
NODE_NAME     J19 45
 '@T6G_MB_LIB.T6G(SCH_1):PAGE88_I415@PURE_QUANTA.SCONN288_DDR506112002KQ(CHIPS)':
 'DQS3_A_C': CDS_PINID='DQS3_A_C';
NET_NAME
'M_D_CPU0_SA_DQS_DN<4>'
 '@T6G_MB_LIB.T6G(SCH_1):M_D_CPU0_SA_DQS_DN'<4>:
 C_SIGNAL='@t6g_mb_lib.t6g(sch_1):m_d_cpu0_sa_dqs_dn(4)';
NODE_NAME     U25 AM60
 '@T6G_MB_LIB.T6G(SCH_1):PAGE13_I159@PURE_QUANTA.GENOA_SP5(CHIPS)':
 'MDA_DQS_L4': CDS_PINID='MDA_DQS_L4';
NODE_NAME     J19 56
 '@T6G_MB_LIB.T6G(SCH_1):PAGE88_I415@PURE_QUANTA.SCONN288_DDR506112002KQ(CHIPS)':
 'DQS4_A_C': CDS_PINID='DQS4_A_C';
NET_NAME
'M_D_CPU0_SA_DQS_DN<5>'
 '@T6G_MB_LIB.T6G(SCH_1):M_D_CPU0_SA_DQS_DN'<5>:
 C_SIGNAL='@t6g_mb_lib.t6g(sch_1):m_d_cpu0_sa_dqs_dn(5)';
NODE_NAME     U25 H58
 '@T6G_MB_LIB.T6G(SCH_1):PAGE13_I159@PURE_QUANTA.GENOA_SP5(CHIPS)':
 'MDA_DQS_L5': CDS_PINID='MDA_DQS_L5';
NODE_NAME     J19 156
 '@T6G_MB_LIB.T6G(SCH_1):PAGE88_I415@PURE_QUANTA.SCONN288_DDR506112002KQ(CHIPS)':
 'DQS5_A_C||TDQS5_A_C||DQS5_A_T||TDQS5_A_T': CDS_PINID='\dqs5_a_c||tdqs5_a_c||dqs5_a_t||tdqs5_a_t\';
NET_NAME
'M_D_CPU0_SA_DQS_DN<6>'
 '@T6G_MB_LIB.T6G(SCH_1):M_D_CPU0_SA_DQS_DN'<6>:
 C_SIGNAL='@t6g_mb_lib.t6g(sch_1):m_d_cpu0_sa_dqs_dn(6)';
NODE_NAME     U25 P58
 '@T6G_MB_LIB.T6G(SCH_1):PAGE13_I159@PURE_QUANTA.GENOA_SP5(CHIPS)':
 'MDA_DQS_L6': CDS_PINID='MDA_DQS_L6';
NODE_NAME     J19 167
 '@T6G_MB_LIB.T6G(SCH_1):PAGE88_I415@PURE_QUANTA.SCONN288_DDR506112002KQ(CHIPS)':
 'DQS6_A_C||TDQS6_A_C||DQS6_A_T||TDQS6_A_T': CDS_PINID='\dqs6_a_c||tdqs6_a_c||dqs6_a_t||tdqs6_a_t\';
NET_NAME
'M_D_CPU0_SA_DQS_DN<7>'
 '@T6G_MB_LIB.T6G(SCH_1):M_D_CPU0_SA_DQS_DN'<7>:
 C_SIGNAL='@t6g_mb_lib.t6g(sch_1):m_d_cpu0_sa_dqs_dn(7)';
NODE_NAME     U25 Y58
 '@T6G_MB_LIB.T6G(SCH_1):PAGE13_I159@PURE_QUANTA.GENOA_SP5(CHIPS)':
 'MDA_DQS_L7': CDS_PINID='MDA_DQS_L7';
NODE_NAME     J19 178
 '@T6G_MB_LIB.T6G(SCH_1):PAGE88_I415@PURE_QUANTA.SCONN288_DDR506112002KQ(CHIPS)':
 'DQS7_A_C||TDQS7_A_C': CDS_PINID='\dqs7_a_c||tdqs7_a_c\';
NET_NAME
'M_D_CPU0_SA_DQS_DN<8>'
 '@T6G_MB_LIB.T6G(SCH_1):M_D_CPU0_SA_DQS_DN'<8>:
 C_SIGNAL='@t6g_mb_lib.t6g(sch_1):m_d_cpu0_sa_dqs_dn(8)';
NODE_NAME     U25 AF58
 '@T6G_MB_LIB.T6G(SCH_1):PAGE13_I159@PURE_QUANTA.GENOA_SP5(CHIPS)':
 'MDA_DQS_L8': CDS_PINID='MDA_DQS_L8';
NODE_NAME     J19 189
 '@T6G_MB_LIB.T6G(SCH_1):PAGE88_I415@PURE_QUANTA.SCONN288_DDR506112002KQ(CHIPS)':
 'DQS8_A_C||TDQS8_A_C': CDS_PINID='\dqs8_a_c||tdqs8_a_c\';
NET_NAME
'M_D_CPU0_SA_DQS_DN<9>'
 '@T6G_MB_LIB.T6G(SCH_1):M_D_CPU0_SA_DQS_DN'<9>:
 C_SIGNAL='@t6g_mb_lib.t6g(sch_1):m_d_cpu0_sa_dqs_dn(9)';
NODE_NAME     U25 AM58
 '@T6G_MB_LIB.T6G(SCH_1):PAGE13_I159@PURE_QUANTA.GENOA_SP5(CHIPS)':
 'MDA_DQS_L9': CDS_PINID='MDA_DQS_L9';
NODE_NAME     J19 200
 '@T6G_MB_LIB.T6G(SCH_1):PAGE88_I415@PURE_QUANTA.SCONN288_DDR506112002KQ(CHIPS)':
 'DQS9_A_C||TDQS9_A_C': CDS_PINID='\dqs9_a_c||tdqs9_a_c\';
NET_NAME
'M_D_CPU0_SA_DQS_DP<0>'
 '@T6G_MB_LIB.T6G(SCH_1):M_D_CPU0_SA_DQS_DP'<0>:
 C_SIGNAL='@t6g_mb_lib.t6g(sch_1):m_d_cpu0_sa_dqs_dp(0)';
NODE_NAME     U25 G60
 '@T6G_MB_LIB.T6G(SCH_1):PAGE13_I159@PURE_QUANTA.GENOA_SP5(CHIPS)':
 'MDA_DQS_H0': CDS_PINID='MDA_DQS_H0';
NODE_NAME     J19 11
 '@T6G_MB_LIB.T6G(SCH_1):PAGE88_I415@PURE_QUANTA.SCONN288_DDR506112002KQ(CHIPS)':
 'DQS0_A_T': CDS_PINID='DQS0_A_T';
NET_NAME
'M_D_CPU0_SA_DQS_DP<1>'
 '@T6G_MB_LIB.T6G(SCH_1):M_D_CPU0_SA_DQS_DP'<1>:
 C_SIGNAL='@t6g_mb_lib.t6g(sch_1):m_d_cpu0_sa_dqs_dp(1)';
NODE_NAME     U25 N60
 '@T6G_MB_LIB.T6G(SCH_1):PAGE13_I159@PURE_QUANTA.GENOA_SP5(CHIPS)':
 'MDA_DQS_H1': CDS_PINID='MDA_DQS_H1';
NODE_NAME     J19 22
 '@T6G_MB_LIB.T6G(SCH_1):PAGE88_I415@PURE_QUANTA.SCONN288_DDR506112002KQ(CHIPS)':
 'DQS1_A_T': CDS_PINID='DQS1_A_T';
NET_NAME
'M_D_CPU0_SA_DQS_DP<2>'
 '@T6G_MB_LIB.T6G(SCH_1):M_D_CPU0_SA_DQS_DP'<2>:
 C_SIGNAL='@t6g_mb_lib.t6g(sch_1):m_d_cpu0_sa_dqs_dp(2)';
NODE_NAME     U25 W60
 '@T6G_MB_LIB.T6G(SCH_1):PAGE13_I159@PURE_QUANTA.GENOA_SP5(CHIPS)':
 'MDA_DQS_H2': CDS_PINID='MDA_DQS_H2';
NODE_NAME     J19 33
 '@T6G_MB_LIB.T6G(SCH_1):PAGE88_I415@PURE_QUANTA.SCONN288_DDR506112002KQ(CHIPS)':
 'DQS2_A_T': CDS_PINID='DQS2_A_T';
NET_NAME
'M_D_CPU0_SA_DQS_DP<3>'
 '@T6G_MB_LIB.T6G(SCH_1):M_D_CPU0_SA_DQS_DP'<3>:
 C_SIGNAL='@t6g_mb_lib.t6g(sch_1):m_d_cpu0_sa_dqs_dp(3)';
NODE_NAME     U25 AE60
 '@T6G_MB_LIB.T6G(SCH_1):PAGE13_I159@PURE_QUANTA.GENOA_SP5(CHIPS)':
 'MDA_DQS_H3': CDS_PINID='MDA_DQS_H3';
NODE_NAME     J19 44
 '@T6G_MB_LIB.T6G(SCH_1):PAGE88_I415@PURE_QUANTA.SCONN288_DDR506112002KQ(CHIPS)':
 'DQS3_A_T': CDS_PINID='DQS3_A_T';
NET_NAME
'M_D_CPU0_SA_DQS_DP<4>'
 '@T6G_MB_LIB.T6G(SCH_1):M_D_CPU0_SA_DQS_DP'<4>:
 C_SIGNAL='@t6g_mb_lib.t6g(sch_1):m_d_cpu0_sa_dqs_dp(4)';
NODE_NAME     U25 AL60
 '@T6G_MB_LIB.T6G(SCH_1):PAGE13_I159@PURE_QUANTA.GENOA_SP5(CHIPS)':
 'MDA_DQS_H4': CDS_PINID='MDA_DQS_H4';
NODE_NAME     J19 55
 '@T6G_MB_LIB.T6G(SCH_1):PAGE88_I415@PURE_QUANTA.SCONN288_DDR506112002KQ(CHIPS)':
 'DQS4_A_T': CDS_PINID='DQS4_A_T';
NET_NAME
'M_D_CPU0_SA_DQS_DP<5>'
 '@T6G_MB_LIB.T6G(SCH_1):M_D_CPU0_SA_DQS_DP'<5>:
 C_SIGNAL='@t6g_mb_lib.t6g(sch_1):m_d_cpu0_sa_dqs_dp(5)';
NODE_NAME     U25 J59
 '@T6G_MB_LIB.T6G(SCH_1):PAGE13_I159@PURE_QUANTA.GENOA_SP5(CHIPS)':
 'MDA_DQS_H5': CDS_PINID='MDA_DQS_H5';
NODE_NAME     J19 157
 '@T6G_MB_LIB.T6G(SCH_1):PAGE88_I415@PURE_QUANTA.SCONN288_DDR506112002KQ(CHIPS)':
 'DQS5_A_T||TDQS5_A_T': CDS_PINID='\dqs5_a_t||tdqs5_a_t\';
NET_NAME
'M_D_CPU0_SA_DQS_DP<6>'
 '@T6G_MB_LIB.T6G(SCH_1):M_D_CPU0_SA_DQS_DP'<6>:
 C_SIGNAL='@t6g_mb_lib.t6g(sch_1):m_d_cpu0_sa_dqs_dp(6)';
NODE_NAME     U25 R59
 '@T6G_MB_LIB.T6G(SCH_1):PAGE13_I159@PURE_QUANTA.GENOA_SP5(CHIPS)':
 'MDA_DQS_H6': CDS_PINID='MDA_DQS_H6';
NODE_NAME     J19 168
 '@T6G_MB_LIB.T6G(SCH_1):PAGE88_I415@PURE_QUANTA.SCONN288_DDR506112002KQ(CHIPS)':
 'DQS6_A_T||TDQS6_A_T': CDS_PINID='\dqs6_a_t||tdqs6_a_t\';
NET_NAME
'M_D_CPU0_SA_DQS_DP<7>'
 '@T6G_MB_LIB.T6G(SCH_1):M_D_CPU0_SA_DQS_DP'<7>:
 C_SIGNAL='@t6g_mb_lib.t6g(sch_1):m_d_cpu0_sa_dqs_dp(7)';
NODE_NAME     U25 AA59
 '@T6G_MB_LIB.T6G(SCH_1):PAGE13_I159@PURE_QUANTA.GENOA_SP5(CHIPS)':
 'MDA_DQS_H7': CDS_PINID='MDA_DQS_H7';
NODE_NAME     J19 179
 '@T6G_MB_LIB.T6G(SCH_1):PAGE88_I415@PURE_QUANTA.SCONN288_DDR506112002KQ(CHIPS)':
 'DQS7_A_T||TDQS7_A_T': CDS_PINID='\dqs7_a_t||tdqs7_a_t\';
NET_NAME
'M_D_CPU0_SA_DQS_DP<8>'
 '@T6G_MB_LIB.T6G(SCH_1):M_D_CPU0_SA_DQS_DP'<8>:
 C_SIGNAL='@t6g_mb_lib.t6g(sch_1):m_d_cpu0_sa_dqs_dp(8)';
NODE_NAME     U25 AG59
 '@T6G_MB_LIB.T6G(SCH_1):PAGE13_I159@PURE_QUANTA.GENOA_SP5(CHIPS)':
 'MDA_DQS_H8': CDS_PINID='MDA_DQS_H8';
NODE_NAME     J19 190
 '@T6G_MB_LIB.T6G(SCH_1):PAGE88_I415@PURE_QUANTA.SCONN288_DDR506112002KQ(CHIPS)':
 'DQS8_A_T||TDQS8_A_T': CDS_PINID='\dqs8_a_t||tdqs8_a_t\';
NET_NAME
'M_D_CPU0_SA_DQS_DP<9>'
 '@T6G_MB_LIB.T6G(SCH_1):M_D_CPU0_SA_DQS_DP'<9>:
 C_SIGNAL='@t6g_mb_lib.t6g(sch_1):m_d_cpu0_sa_dqs_dp(9)';
NODE_NAME     U25 AN59
 '@T6G_MB_LIB.T6G(SCH_1):PAGE13_I159@PURE_QUANTA.GENOA_SP5(CHIPS)':
 'MDA_DQS_H9': CDS_PINID='MDA_DQS_H9';
NODE_NAME     J19 201
 '@T6G_MB_LIB.T6G(SCH_1):PAGE88_I415@PURE_QUANTA.SCONN288_DDR506112002KQ(CHIPS)':
 'DQS9_A_T||TDQS9_A_T': CDS_PINID='\dqs9_a_t||tdqs9_a_t\';
NET_NAME
'M_D_CPU0_SA_PAR'
 '@T6G_MB_LIB.T6G(SCH_1):M_D_CPU0_SA_PAR':
 C_SIGNAL='@t6g_mb_lib.t6g(sch_1):m_d_cpu0_sa_par';
NODE_NAME     U25 BC59
 '@T6G_MB_LIB.T6G(SCH_1):PAGE13_I159@PURE_QUANTA.GENOA_SP5(CHIPS)':
 'MDA_PAR': CDS_PINID='MDA_PAR';
NODE_NAME     J19 74
 '@T6G_MB_LIB.T6G(SCH_1):PAGE88_I350@PURE_QUANTA.SCONN288_DDR506112002KQ(CHIPS)':
 'PAR_A': CDS_PINID='PAR_A';
NET_NAME
'M_D_CPU0_SA_RSP<0>'
 '@T6G_MB_LIB.T6G(SCH_1):M_D_CPU0_SA_RSP'<0>:
 C_SIGNAL='@t6g_mb_lib.t6g(sch_1):m_d_cpu0_sa_rsp(0)';
NODE_NAME     U25 BN59
 '@T6G_MB_LIB.T6G(SCH_1):PAGE13_I159@PURE_QUANTA.GENOA_SP5(CHIPS)':
 'MDA0_RSP_L': CDS_PINID='MDA0_RSP_L';
NODE_NAME     J19 86
 '@T6G_MB_LIB.T6G(SCH_1):PAGE88_I350@PURE_QUANTA.SCONN288_DDR506112002KQ(CHIPS)':
 'LBD||RSP_A_N': CDS_PINID='\lbd||rsp_a_n\';
NET_NAME
'M_D_CPU0_SB_CA<0>'
 '@T6G_MB_LIB.T6G(SCH_1):M_D_CPU0_SB_CA'<0>:
 C_SIGNAL='@t6g_mb_lib.t6g(sch_1):m_d_cpu0_sb_ca(0)';
NODE_NAME     U25 BG59
 '@T6G_MB_LIB.T6G(SCH_1):PAGE13_I159@PURE_QUANTA.GENOA_SP5(CHIPS)':
 'MDB_CA0': CDS_PINID='MDB_CA0';
NODE_NAME     J19 76
 '@T6G_MB_LIB.T6G(SCH_1):PAGE88_I350@PURE_QUANTA.SCONN288_DDR506112002KQ(CHIPS)':
 'CA0_B': CDS_PINID='CA0_B';
NET_NAME
'M_D_CPU0_SB_CA<1>'
 '@T6G_MB_LIB.T6G(SCH_1):M_D_CPU0_SB_CA'<1>:
 C_SIGNAL='@t6g_mb_lib.t6g(sch_1):m_d_cpu0_sb_ca(1)';
NODE_NAME     U25 BH58
 '@T6G_MB_LIB.T6G(SCH_1):PAGE13_I159@PURE_QUANTA.GENOA_SP5(CHIPS)':
 'MDB_CA1': CDS_PINID='MDB_CA1';
NODE_NAME     J19 221
 '@T6G_MB_LIB.T6G(SCH_1):PAGE88_I350@PURE_QUANTA.SCONN288_DDR506112002KQ(CHIPS)':
 'CA1_B': CDS_PINID='CA1_B';
NET_NAME
'M_D_CPU0_SB_CA<2>'
 '@T6G_MB_LIB.T6G(SCH_1):M_D_CPU0_SB_CA'<2>:
 C_SIGNAL='@t6g_mb_lib.t6g(sch_1):m_d_cpu0_sb_ca(2)';
NODE_NAME     U25 BH60
 '@T6G_MB_LIB.T6G(SCH_1):PAGE13_I159@PURE_QUANTA.GENOA_SP5(CHIPS)':
 'MDB_CA2': CDS_PINID='MDB_CA2';
NODE_NAME     J19 78
 '@T6G_MB_LIB.T6G(SCH_1):PAGE88_I350@PURE_QUANTA.SCONN288_DDR506112002KQ(CHIPS)':
 'CA2_B': CDS_PINID='CA2_B';
NET_NAME
'M_D_CPU0_SB_CA<3>'
 '@T6G_MB_LIB.T6G(SCH_1):M_D_CPU0_SB_CA'<3>:
 C_SIGNAL='@t6g_mb_lib.t6g(sch_1):m_d_cpu0_sb_ca(3)';
NODE_NAME     U25 BJ60
 '@T6G_MB_LIB.T6G(SCH_1):PAGE13_I159@PURE_QUANTA.GENOA_SP5(CHIPS)':
 'MDB_CA3': CDS_PINID='MDB_CA3';
NODE_NAME     J19 223
 '@T6G_MB_LIB.T6G(SCH_1):PAGE88_I350@PURE_QUANTA.SCONN288_DDR506112002KQ(CHIPS)':
 'CA3_B': CDS_PINID='CA3_B';
NET_NAME
'M_D_CPU0_SB_CA<4>'
 '@T6G_MB_LIB.T6G(SCH_1):M_D_CPU0_SB_CA'<4>:
 C_SIGNAL='@t6g_mb_lib.t6g(sch_1):m_d_cpu0_sb_ca(4)';
NODE_NAME     U25 BJ59
 '@T6G_MB_LIB.T6G(SCH_1):PAGE13_I159@PURE_QUANTA.GENOA_SP5(CHIPS)':
 'MDB_CA4': CDS_PINID='MDB_CA4';
NODE_NAME     J19 80
 '@T6G_MB_LIB.T6G(SCH_1):PAGE88_I350@PURE_QUANTA.SCONN288_DDR506112002KQ(CHIPS)':
 'CA4_B': CDS_PINID='CA4_B';
NET_NAME
'M_D_CPU0_SB_CA<5>'
 '@T6G_MB_LIB.T6G(SCH_1):M_D_CPU0_SB_CA'<5>:
 C_SIGNAL='@t6g_mb_lib.t6g(sch_1):m_d_cpu0_sb_ca(5)';
NODE_NAME     U25 BK58
 '@T6G_MB_LIB.T6G(SCH_1):PAGE13_I159@PURE_QUANTA.GENOA_SP5(CHIPS)':
 'MDB_CA5': CDS_PINID='MDB_CA5';
NODE_NAME     J19 225
 '@T6G_MB_LIB.T6G(SCH_1):PAGE88_I350@PURE_QUANTA.SCONN288_DDR506112002KQ(CHIPS)':
 'CA5_B': CDS_PINID='CA5_B';
NET_NAME
'M_D_CPU0_SB_CA<6>'
 '@T6G_MB_LIB.T6G(SCH_1):M_D_CPU0_SB_CA'<6>:
 C_SIGNAL='@t6g_mb_lib.t6g(sch_1):m_d_cpu0_sb_ca(6)';
NODE_NAME     U25 BK60
 '@T6G_MB_LIB.T6G(SCH_1):PAGE13_I159@PURE_QUANTA.GENOA_SP5(CHIPS)':
 'MDB_CA6': CDS_PINID='MDB_CA6';
NODE_NAME     J19 82
 '@T6G_MB_LIB.T6G(SCH_1):PAGE88_I350@PURE_QUANTA.SCONN288_DDR506112002KQ(CHIPS)':
 'CA6_B': CDS_PINID='CA6_B';
NET_NAME
'M_D_CPU0_SB_CB<0>'
 '@T6G_MB_LIB.T6G(SCH_1):M_D_CPU0_SB_CB'<0>:
 C_SIGNAL='@t6g_mb_lib.t6g(sch_1):m_d_cpu0_sb_cb(0)';
NODE_NAME     U25 BY60
 '@T6G_MB_LIB.T6G(SCH_1):PAGE13_I159@PURE_QUANTA.GENOA_SP5(CHIPS)':
 'MDB_CHECK0': CDS_PINID='MDB_CHECK0';
NODE_NAME     J19 96
 '@T6G_MB_LIB.T6G(SCH_1):PAGE88_I350@PURE_QUANTA.SCONN288_DDR506112002KQ(CHIPS)':
 'CB0_B': CDS_PINID='CB0_B';
NET_NAME
'M_D_CPU0_SB_CB<1>'
 '@T6G_MB_LIB.T6G(SCH_1):M_D_CPU0_SB_CB'<1>:
 C_SIGNAL='@t6g_mb_lib.t6g(sch_1):m_d_cpu0_sb_cb(1)';
NODE_NAME     U25 CA59
 '@T6G_MB_LIB.T6G(SCH_1):PAGE13_I159@PURE_QUANTA.GENOA_SP5(CHIPS)':
 'MDB_CHECK1': CDS_PINID='MDB_CHECK1';
NODE_NAME     J19 98
 '@T6G_MB_LIB.T6G(SCH_1):PAGE88_I350@PURE_QUANTA.SCONN288_DDR506112002KQ(CHIPS)':
 'CB1_B': CDS_PINID='CB1_B';
NET_NAME
'M_D_CPU0_SB_CB<2>'
 '@T6G_MB_LIB.T6G(SCH_1):M_D_CPU0_SB_CB'<2>:
 C_SIGNAL='@t6g_mb_lib.t6g(sch_1):m_d_cpu0_sb_cb(2)';
NODE_NAME     U25 CA60
 '@T6G_MB_LIB.T6G(SCH_1):PAGE13_I159@PURE_QUANTA.GENOA_SP5(CHIPS)':
 'MDB_CHECK2': CDS_PINID='MDB_CHECK2';
NODE_NAME     J19 241
 '@T6G_MB_LIB.T6G(SCH_1):PAGE88_I350@PURE_QUANTA.SCONN288_DDR506112002KQ(CHIPS)':
 'CB2_B': CDS_PINID='CB2_B';
NET_NAME
'M_D_CPU0_SB_CB<3>'
 '@T6G_MB_LIB.T6G(SCH_1):M_D_CPU0_SB_CB'<3>:
 C_SIGNAL='@t6g_mb_lib.t6g(sch_1):m_d_cpu0_sb_cb(3)';
NODE_NAME     U25 CB58
 '@T6G_MB_LIB.T6G(SCH_1):PAGE13_I159@PURE_QUANTA.GENOA_SP5(CHIPS)':
 'MDB_CHECK3': CDS_PINID='MDB_CHECK3';
NODE_NAME     J19 243
 '@T6G_MB_LIB.T6G(SCH_1):PAGE88_I350@PURE_QUANTA.SCONN288_DDR506112002KQ(CHIPS)':
 'CB3_B': CDS_PINID='CB3_B';
NET_NAME
'M_D_CPU0_SB_CB<4>'
 '@T6G_MB_LIB.T6G(SCH_1):M_D_CPU0_SB_CB'<4>:
 C_SIGNAL='@t6g_mb_lib.t6g(sch_1):m_d_cpu0_sb_cb(4)';
NODE_NAME     U25 BT60
 '@T6G_MB_LIB.T6G(SCH_1):PAGE13_I159@PURE_QUANTA.GENOA_SP5(CHIPS)':
 'MDB_CHECK4': CDS_PINID='MDB_CHECK4';
NODE_NAME     J19 89
 '@T6G_MB_LIB.T6G(SCH_1):PAGE88_I350@PURE_QUANTA.SCONN288_DDR506112002KQ(CHIPS)':
 'CB4_B': CDS_PINID='CB4_B';
NET_NAME
'M_D_CPU0_SB_CB<5>'
 '@T6G_MB_LIB.T6G(SCH_1):M_D_CPU0_SB_CB'<5>:
 C_SIGNAL='@t6g_mb_lib.t6g(sch_1):m_d_cpu0_sb_cb(5)';
NODE_NAME     U25 BU59
 '@T6G_MB_LIB.T6G(SCH_1):PAGE13_I159@PURE_QUANTA.GENOA_SP5(CHIPS)':
 'MDB_CHECK5': CDS_PINID='MDB_CHECK5';
NODE_NAME     J19 91
 '@T6G_MB_LIB.T6G(SCH_1):PAGE88_I350@PURE_QUANTA.SCONN288_DDR506112002KQ(CHIPS)':
 'CB5_B': CDS_PINID='CB5_B';
NET_NAME
'M_D_CPU0_SB_CB<6>'
 '@T6G_MB_LIB.T6G(SCH_1):M_D_CPU0_SB_CB'<6>:
 C_SIGNAL='@t6g_mb_lib.t6g(sch_1):m_d_cpu0_sb_cb(6)';
NODE_NAME     U25 BU60
 '@T6G_MB_LIB.T6G(SCH_1):PAGE13_I159@PURE_QUANTA.GENOA_SP5(CHIPS)':
 'MDB_CHECK6': CDS_PINID='MDB_CHECK6';
NODE_NAME     J19 234
 '@T6G_MB_LIB.T6G(SCH_1):PAGE88_I350@PURE_QUANTA.SCONN288_DDR506112002KQ(CHIPS)':
 'CB6_B': CDS_PINID='CB6_B';
NET_NAME
'M_D_CPU0_SB_CB<7>'
 '@T6G_MB_LIB.T6G(SCH_1):M_D_CPU0_SB_CB'<7>:
 C_SIGNAL='@t6g_mb_lib.t6g(sch_1):m_d_cpu0_sb_cb(7)';
NODE_NAME     U25 BV58
 '@T6G_MB_LIB.T6G(SCH_1):PAGE13_I159@PURE_QUANTA.GENOA_SP5(CHIPS)':
 'MDB_CHECK7': CDS_PINID='MDB_CHECK7';
NODE_NAME     J19 236
 '@T6G_MB_LIB.T6G(SCH_1):PAGE88_I350@PURE_QUANTA.SCONN288_DDR506112002KQ(CHIPS)':
 'CB7_B': CDS_PINID='CB7_B';
NET_NAME
'M_D_CPU0_SB_CS_N<0>'
 '@T6G_MB_LIB.T6G(SCH_1):M_D_CPU0_SB_CS_N'<0>:
 C_SIGNAL='@t6g_mb_lib.t6g(sch_1):m_d_cpu0_sb_cs_n(0)';
NODE_NAME     U25 BM58
 '@T6G_MB_LIB.T6G(SCH_1):PAGE13_I159@PURE_QUANTA.GENOA_SP5(CHIPS)':
 'MDB0_CS_L0': CDS_PINID='MDB0_CS_L0';
NODE_NAME     J19 84
 '@T6G_MB_LIB.T6G(SCH_1):PAGE88_I350@PURE_QUANTA.SCONN288_DDR506112002KQ(CHIPS)':
 'CS0_B_N': CDS_PINID='CS0_B_N';
NET_NAME
'M_D_CPU0_SB_CS_N<1>'
 '@T6G_MB_LIB.T6G(SCH_1):M_D_CPU0_SB_CS_N'<1>:
 C_SIGNAL='@t6g_mb_lib.t6g(sch_1):m_d_cpu0_sb_cs_n(1)';
NODE_NAME     U25 BN60
 '@T6G_MB_LIB.T6G(SCH_1):PAGE13_I159@PURE_QUANTA.GENOA_SP5(CHIPS)':
 'MDB0_CS_L1': CDS_PINID='MDB0_CS_L1';
NODE_NAME     J19 229
 '@T6G_MB_LIB.T6G(SCH_1):PAGE88_I350@PURE_QUANTA.SCONN288_DDR506112002KQ(CHIPS)':
 'CS1_B_N': CDS_PINID='CS1_B_N';
NET_NAME
'M_D_CPU0_SB_DQ<0>'
 '@T6G_MB_LIB.T6G(SCH_1):M_D_CPU0_SB_DQ'<0>:
 C_SIGNAL='@t6g_mb_lib.t6g(sch_1):m_d_cpu0_sb_dq(0)';
NODE_NAME     U25 CB60
 '@T6G_MB_LIB.T6G(SCH_1):PAGE13_I159@PURE_QUANTA.GENOA_SP5(CHIPS)':
 'MDB_DATA0': CDS_PINID='MDB_DATA0';
NODE_NAME     J19 100
 '@T6G_MB_LIB.T6G(SCH_1):PAGE88_I350@PURE_QUANTA.SCONN288_DDR506112002KQ(CHIPS)':
 'DQ0_B': CDS_PINID='DQ0_B';
NET_NAME
'M_D_CPU0_SB_DQ<10>'
 '@T6G_MB_LIB.T6G(SCH_1):M_D_CPU0_SB_DQ'<10>:
 C_SIGNAL='@t6g_mb_lib.t6g(sch_1):m_d_cpu0_sb_dq(10)';
NODE_NAME     U25 CJ60
 '@T6G_MB_LIB.T6G(SCH_1):PAGE13_I159@PURE_QUANTA.GENOA_SP5(CHIPS)':
 'MDB_DATA10': CDS_PINID='MDB_DATA10';
NODE_NAME     J19 256
 '@T6G_MB_LIB.T6G(SCH_1):PAGE88_I350@PURE_QUANTA.SCONN288_DDR506112002KQ(CHIPS)':
 'DQ10_B': CDS_PINID='DQ10_B';
NET_NAME
'M_D_CPU0_SB_DQ<11>'
 '@T6G_MB_LIB.T6G(SCH_1):M_D_CPU0_SB_DQ'<11>:
 C_SIGNAL='@t6g_mb_lib.t6g(sch_1):m_d_cpu0_sb_dq(11)';
NODE_NAME     U25 CK58
 '@T6G_MB_LIB.T6G(SCH_1):PAGE13_I159@PURE_QUANTA.GENOA_SP5(CHIPS)':
 'MDB_DATA11': CDS_PINID='MDB_DATA11';
NODE_NAME     J19 258
 '@T6G_MB_LIB.T6G(SCH_1):PAGE88_I350@PURE_QUANTA.SCONN288_DDR506112002KQ(CHIPS)':
 'DQ11_B': CDS_PINID='DQ11_B';
NET_NAME
'M_D_CPU0_SB_DQ<12>'
 '@T6G_MB_LIB.T6G(SCH_1):M_D_CPU0_SB_DQ'<12>:
 C_SIGNAL='@t6g_mb_lib.t6g(sch_1):m_d_cpu0_sb_dq(12)';
NODE_NAME     U25 CM60
 '@T6G_MB_LIB.T6G(SCH_1):PAGE13_I159@PURE_QUANTA.GENOA_SP5(CHIPS)':
 'MDB_DATA12': CDS_PINID='MDB_DATA12';
NODE_NAME     J19 118
 '@T6G_MB_LIB.T6G(SCH_1):PAGE88_I350@PURE_QUANTA.SCONN288_DDR506112002KQ(CHIPS)':
 'DQ12_B': CDS_PINID='DQ12_B';
NET_NAME
'M_D_CPU0_SB_DQ<13>'
 '@T6G_MB_LIB.T6G(SCH_1):M_D_CPU0_SB_DQ'<13>:
 C_SIGNAL='@t6g_mb_lib.t6g(sch_1):m_d_cpu0_sb_dq(13)';
NODE_NAME     U25 CN59
 '@T6G_MB_LIB.T6G(SCH_1):PAGE13_I159@PURE_QUANTA.GENOA_SP5(CHIPS)':
 'MDB_DATA13': CDS_PINID='MDB_DATA13';
NODE_NAME     J19 120
 '@T6G_MB_LIB.T6G(SCH_1):PAGE88_I350@PURE_QUANTA.SCONN288_DDR506112002KQ(CHIPS)':
 'DQ13_B': CDS_PINID='DQ13_B';
NET_NAME
'M_D_CPU0_SB_DQ<14>'
 '@T6G_MB_LIB.T6G(SCH_1):M_D_CPU0_SB_DQ'<14>:
 C_SIGNAL='@t6g_mb_lib.t6g(sch_1):m_d_cpu0_sb_dq(14)';
NODE_NAME     U25 CN60
 '@T6G_MB_LIB.T6G(SCH_1):PAGE13_I159@PURE_QUANTA.GENOA_SP5(CHIPS)':
 'MDB_DATA14': CDS_PINID='MDB_DATA14';
NODE_NAME     J19 263
 '@T6G_MB_LIB.T6G(SCH_1):PAGE88_I350@PURE_QUANTA.SCONN288_DDR506112002KQ(CHIPS)':
 'DQ14_B': CDS_PINID='DQ14_B';
NET_NAME
'M_D_CPU0_SB_DQ<15>'
 '@T6G_MB_LIB.T6G(SCH_1):M_D_CPU0_SB_DQ'<15>:
 C_SIGNAL='@t6g_mb_lib.t6g(sch_1):m_d_cpu0_sb_dq(15)';
NODE_NAME     U25 CP58
 '@T6G_MB_LIB.T6G(SCH_1):PAGE13_I159@PURE_QUANTA.GENOA_SP5(CHIPS)':
 'MDB_DATA15': CDS_PINID='MDB_DATA15';
NODE_NAME     J19 265
 '@T6G_MB_LIB.T6G(SCH_1):PAGE88_I350@PURE_QUANTA.SCONN288_DDR506112002KQ(CHIPS)':
 'DQ15_B': CDS_PINID='DQ15_B';
NET_NAME
'M_D_CPU0_SB_DQ<16>'
 '@T6G_MB_LIB.T6G(SCH_1):M_D_CPU0_SB_DQ'<16>:
 C_SIGNAL='@t6g_mb_lib.t6g(sch_1):m_d_cpu0_sb_dq(16)';
NODE_NAME     U25 CP60
 '@T6G_MB_LIB.T6G(SCH_1):PAGE13_I159@PURE_QUANTA.GENOA_SP5(CHIPS)':
 'MDB_DATA16': CDS_PINID='MDB_DATA16';
NODE_NAME     J19 122
 '@T6G_MB_LIB.T6G(SCH_1):PAGE88_I350@PURE_QUANTA.SCONN288_DDR506112002KQ(CHIPS)':
 'DQ16_B': CDS_PINID='DQ16_B';
NET_NAME
'M_D_CPU0_SB_DQ<17>'
 '@T6G_MB_LIB.T6G(SCH_1):M_D_CPU0_SB_DQ'<17>:
 C_SIGNAL='@t6g_mb_lib.t6g(sch_1):m_d_cpu0_sb_dq(17)';
NODE_NAME     U25 CR59
 '@T6G_MB_LIB.T6G(SCH_1):PAGE13_I159@PURE_QUANTA.GENOA_SP5(CHIPS)':
 'MDB_DATA17': CDS_PINID='MDB_DATA17';
NODE_NAME     J19 124
 '@T6G_MB_LIB.T6G(SCH_1):PAGE88_I350@PURE_QUANTA.SCONN288_DDR506112002KQ(CHIPS)':
 'DQ17_B': CDS_PINID='DQ17_B';
NET_NAME
'M_D_CPU0_SB_DQ<18>'
 '@T6G_MB_LIB.T6G(SCH_1):M_D_CPU0_SB_DQ'<18>:
 C_SIGNAL='@t6g_mb_lib.t6g(sch_1):m_d_cpu0_sb_dq(18)';
NODE_NAME     U25 CR60
 '@T6G_MB_LIB.T6G(SCH_1):PAGE13_I159@PURE_QUANTA.GENOA_SP5(CHIPS)':
 'MDB_DATA18': CDS_PINID='MDB_DATA18';
NODE_NAME     J19 267
 '@T6G_MB_LIB.T6G(SCH_1):PAGE88_I350@PURE_QUANTA.SCONN288_DDR506112002KQ(CHIPS)':
 'DQ18_B': CDS_PINID='DQ18_B';
NET_NAME
'M_D_CPU0_SB_DQ<19>'
 '@T6G_MB_LIB.T6G(SCH_1):M_D_CPU0_SB_DQ'<19>:
 C_SIGNAL='@t6g_mb_lib.t6g(sch_1):m_d_cpu0_sb_dq(19)';
NODE_NAME     U25 CT58
 '@T6G_MB_LIB.T6G(SCH_1):PAGE13_I159@PURE_QUANTA.GENOA_SP5(CHIPS)':
 'MDB_DATA19': CDS_PINID='MDB_DATA19';
NODE_NAME     J19 269
 '@T6G_MB_LIB.T6G(SCH_1):PAGE88_I350@PURE_QUANTA.SCONN288_DDR506112002KQ(CHIPS)':
 'DQ19_B': CDS_PINID='DQ19_B';
NET_NAME
'M_D_CPU0_SB_DQ<1>'
 '@T6G_MB_LIB.T6G(SCH_1):M_D_CPU0_SB_DQ'<1>:
 C_SIGNAL='@t6g_mb_lib.t6g(sch_1):m_d_cpu0_sb_dq(1)';
NODE_NAME     U25 CC59
 '@T6G_MB_LIB.T6G(SCH_1):PAGE13_I159@PURE_QUANTA.GENOA_SP5(CHIPS)':
 'MDB_DATA1': CDS_PINID='MDB_DATA1';
NODE_NAME     J19 102
 '@T6G_MB_LIB.T6G(SCH_1):PAGE88_I350@PURE_QUANTA.SCONN288_DDR506112002KQ(CHIPS)':
 'DQ1_B': CDS_PINID='DQ1_B';
NET_NAME
'M_D_CPU0_SB_DQ<20>'
 '@T6G_MB_LIB.T6G(SCH_1):M_D_CPU0_SB_DQ'<20>:
 C_SIGNAL='@t6g_mb_lib.t6g(sch_1):m_d_cpu0_sb_dq(20)';
NODE_NAME     U25 CV60
 '@T6G_MB_LIB.T6G(SCH_1):PAGE13_I159@PURE_QUANTA.GENOA_SP5(CHIPS)':
 'MDB_DATA20': CDS_PINID='MDB_DATA20';
NODE_NAME     J19 129
 '@T6G_MB_LIB.T6G(SCH_1):PAGE88_I350@PURE_QUANTA.SCONN288_DDR506112002KQ(CHIPS)':
 'DQ20_B': CDS_PINID='DQ20_B';
NET_NAME
'M_D_CPU0_SB_DQ<21>'
 '@T6G_MB_LIB.T6G(SCH_1):M_D_CPU0_SB_DQ'<21>:
 C_SIGNAL='@t6g_mb_lib.t6g(sch_1):m_d_cpu0_sb_dq(21)';
NODE_NAME     U25 CW59
 '@T6G_MB_LIB.T6G(SCH_1):PAGE13_I159@PURE_QUANTA.GENOA_SP5(CHIPS)':
 'MDB_DATA21': CDS_PINID='MDB_DATA21';
NODE_NAME     J19 131
 '@T6G_MB_LIB.T6G(SCH_1):PAGE88_I350@PURE_QUANTA.SCONN288_DDR506112002KQ(CHIPS)':
 'DQ21_B': CDS_PINID='DQ21_B';
NET_NAME
'M_D_CPU0_SB_DQ<22>'
 '@T6G_MB_LIB.T6G(SCH_1):M_D_CPU0_SB_DQ'<22>:
 C_SIGNAL='@t6g_mb_lib.t6g(sch_1):m_d_cpu0_sb_dq(22)';
NODE_NAME     U25 CW60
 '@T6G_MB_LIB.T6G(SCH_1):PAGE13_I159@PURE_QUANTA.GENOA_SP5(CHIPS)':
 'MDB_DATA22': CDS_PINID='MDB_DATA22';
NODE_NAME     J19 274
 '@T6G_MB_LIB.T6G(SCH_1):PAGE88_I350@PURE_QUANTA.SCONN288_DDR506112002KQ(CHIPS)':
 'DQ22_B': CDS_PINID='DQ22_B';
NET_NAME
'M_D_CPU0_SB_DQ<23>'
 '@T6G_MB_LIB.T6G(SCH_1):M_D_CPU0_SB_DQ'<23>:
 C_SIGNAL='@t6g_mb_lib.t6g(sch_1):m_d_cpu0_sb_dq(23)';
NODE_NAME     U25 CY58
 '@T6G_MB_LIB.T6G(SCH_1):PAGE13_I159@PURE_QUANTA.GENOA_SP5(CHIPS)':
 'MDB_DATA23': CDS_PINID='MDB_DATA23';
NODE_NAME     J19 276
 '@T6G_MB_LIB.T6G(SCH_1):PAGE88_I350@PURE_QUANTA.SCONN288_DDR506112002KQ(CHIPS)':
 'DQ23_B': CDS_PINID='DQ23_B';
NET_NAME
'M_D_CPU0_SB_DQ<24>'
 '@T6G_MB_LIB.T6G(SCH_1):M_D_CPU0_SB_DQ'<24>:
 C_SIGNAL='@t6g_mb_lib.t6g(sch_1):m_d_cpu0_sb_dq(24)';
NODE_NAME     U25 CY60
 '@T6G_MB_LIB.T6G(SCH_1):PAGE13_I159@PURE_QUANTA.GENOA_SP5(CHIPS)':
 'MDB_DATA24': CDS_PINID='MDB_DATA24';
NODE_NAME     J19 133
 '@T6G_MB_LIB.T6G(SCH_1):PAGE88_I350@PURE_QUANTA.SCONN288_DDR506112002KQ(CHIPS)':
 'DQ24_B': CDS_PINID='DQ24_B';
NET_NAME
'M_D_CPU0_SB_DQ<25>'
 '@T6G_MB_LIB.T6G(SCH_1):M_D_CPU0_SB_DQ'<25>:
 C_SIGNAL='@t6g_mb_lib.t6g(sch_1):m_d_cpu0_sb_dq(25)';
NODE_NAME     U25 DA59
 '@T6G_MB_LIB.T6G(SCH_1):PAGE13_I159@PURE_QUANTA.GENOA_SP5(CHIPS)':
 'MDB_DATA25': CDS_PINID='MDB_DATA25';
NODE_NAME     J19 135
 '@T6G_MB_LIB.T6G(SCH_1):PAGE88_I350@PURE_QUANTA.SCONN288_DDR506112002KQ(CHIPS)':
 'DQ25_B': CDS_PINID='DQ25_B';
NET_NAME
'M_D_CPU0_SB_DQ<26>'
 '@T6G_MB_LIB.T6G(SCH_1):M_D_CPU0_SB_DQ'<26>:
 C_SIGNAL='@t6g_mb_lib.t6g(sch_1):m_d_cpu0_sb_dq(26)';
NODE_NAME     U25 DA60
 '@T6G_MB_LIB.T6G(SCH_1):PAGE13_I159@PURE_QUANTA.GENOA_SP5(CHIPS)':
 'MDB_DATA26': CDS_PINID='MDB_DATA26';
NODE_NAME     J19 278
 '@T6G_MB_LIB.T6G(SCH_1):PAGE88_I350@PURE_QUANTA.SCONN288_DDR506112002KQ(CHIPS)':
 'DQ26_B': CDS_PINID='DQ26_B';
NET_NAME
'M_D_CPU0_SB_DQ<27>'
 '@T6G_MB_LIB.T6G(SCH_1):M_D_CPU0_SB_DQ'<27>:
 C_SIGNAL='@t6g_mb_lib.t6g(sch_1):m_d_cpu0_sb_dq(27)';
NODE_NAME     U25 DB58
 '@T6G_MB_LIB.T6G(SCH_1):PAGE13_I159@PURE_QUANTA.GENOA_SP5(CHIPS)':
 'MDB_DATA27': CDS_PINID='MDB_DATA27';
NODE_NAME     J19 280
 '@T6G_MB_LIB.T6G(SCH_1):PAGE88_I350@PURE_QUANTA.SCONN288_DDR506112002KQ(CHIPS)':
 'DQ27_B': CDS_PINID='DQ27_B';
NET_NAME
'M_D_CPU0_SB_DQ<28>'
 '@T6G_MB_LIB.T6G(SCH_1):M_D_CPU0_SB_DQ'<28>:
 C_SIGNAL='@t6g_mb_lib.t6g(sch_1):m_d_cpu0_sb_dq(28)';
NODE_NAME     U25 DD60
 '@T6G_MB_LIB.T6G(SCH_1):PAGE13_I159@PURE_QUANTA.GENOA_SP5(CHIPS)':
 'MDB_DATA28': CDS_PINID='MDB_DATA28';
NODE_NAME     J19 140
 '@T6G_MB_LIB.T6G(SCH_1):PAGE88_I350@PURE_QUANTA.SCONN288_DDR506112002KQ(CHIPS)':
 'DQ28_B': CDS_PINID='DQ28_B';
NET_NAME
'M_D_CPU0_SB_DQ<29>'
 '@T6G_MB_LIB.T6G(SCH_1):M_D_CPU0_SB_DQ'<29>:
 C_SIGNAL='@t6g_mb_lib.t6g(sch_1):m_d_cpu0_sb_dq(29)';
NODE_NAME     U25 DE59
 '@T6G_MB_LIB.T6G(SCH_1):PAGE13_I159@PURE_QUANTA.GENOA_SP5(CHIPS)':
 'MDB_DATA29': CDS_PINID='MDB_DATA29';
NODE_NAME     J19 142
 '@T6G_MB_LIB.T6G(SCH_1):PAGE88_I350@PURE_QUANTA.SCONN288_DDR506112002KQ(CHIPS)':
 'DQ29_B': CDS_PINID='DQ29_B';
NET_NAME
'M_D_CPU0_SB_DQ<2>'
 '@T6G_MB_LIB.T6G(SCH_1):M_D_CPU0_SB_DQ'<2>:
 C_SIGNAL='@t6g_mb_lib.t6g(sch_1):m_d_cpu0_sb_dq(2)';
NODE_NAME     U25 CC60
 '@T6G_MB_LIB.T6G(SCH_1):PAGE13_I159@PURE_QUANTA.GENOA_SP5(CHIPS)':
 'MDB_DATA2': CDS_PINID='MDB_DATA2';
NODE_NAME     J19 245
 '@T6G_MB_LIB.T6G(SCH_1):PAGE88_I350@PURE_QUANTA.SCONN288_DDR506112002KQ(CHIPS)':
 'DQ2_B': CDS_PINID='DQ2_B';
NET_NAME
'M_D_CPU0_SB_DQ<30>'
 '@T6G_MB_LIB.T6G(SCH_1):M_D_CPU0_SB_DQ'<30>:
 C_SIGNAL='@t6g_mb_lib.t6g(sch_1):m_d_cpu0_sb_dq(30)';
NODE_NAME     U25 DE60
 '@T6G_MB_LIB.T6G(SCH_1):PAGE13_I159@PURE_QUANTA.GENOA_SP5(CHIPS)':
 'MDB_DATA30': CDS_PINID='MDB_DATA30';
NODE_NAME     J19 285
 '@T6G_MB_LIB.T6G(SCH_1):PAGE88_I350@PURE_QUANTA.SCONN288_DDR506112002KQ(CHIPS)':
 'DQ30_B': CDS_PINID='DQ30_B';
NET_NAME
'M_D_CPU0_SB_DQ<31>'
 '@T6G_MB_LIB.T6G(SCH_1):M_D_CPU0_SB_DQ'<31>:
 C_SIGNAL='@t6g_mb_lib.t6g(sch_1):m_d_cpu0_sb_dq(31)';
NODE_NAME     U25 DF60
 '@T6G_MB_LIB.T6G(SCH_1):PAGE13_I159@PURE_QUANTA.GENOA_SP5(CHIPS)':
 'MDB_DATA31': CDS_PINID='MDB_DATA31';
NODE_NAME     J19 287
 '@T6G_MB_LIB.T6G(SCH_1):PAGE88_I350@PURE_QUANTA.SCONN288_DDR506112002KQ(CHIPS)':
 'DQ31_B': CDS_PINID='DQ31_B';
NET_NAME
'M_D_CPU0_SB_DQ<3>'
 '@T6G_MB_LIB.T6G(SCH_1):M_D_CPU0_SB_DQ'<3>:
 C_SIGNAL='@t6g_mb_lib.t6g(sch_1):m_d_cpu0_sb_dq(3)';
NODE_NAME     U25 CD58
 '@T6G_MB_LIB.T6G(SCH_1):PAGE13_I159@PURE_QUANTA.GENOA_SP5(CHIPS)':
 'MDB_DATA3': CDS_PINID='MDB_DATA3';
NODE_NAME     J19 247
 '@T6G_MB_LIB.T6G(SCH_1):PAGE88_I350@PURE_QUANTA.SCONN288_DDR506112002KQ(CHIPS)':
 'DQ3_B': CDS_PINID='DQ3_B';
NET_NAME
'M_D_CPU0_SB_DQ<4>'
 '@T6G_MB_LIB.T6G(SCH_1):M_D_CPU0_SB_DQ'<4>:
 C_SIGNAL='@t6g_mb_lib.t6g(sch_1):m_d_cpu0_sb_dq(4)';
NODE_NAME     U25 CF60
 '@T6G_MB_LIB.T6G(SCH_1):PAGE13_I159@PURE_QUANTA.GENOA_SP5(CHIPS)':
 'MDB_DATA4': CDS_PINID='MDB_DATA4';
NODE_NAME     J19 107
 '@T6G_MB_LIB.T6G(SCH_1):PAGE88_I350@PURE_QUANTA.SCONN288_DDR506112002KQ(CHIPS)':
 'DQ4_B': CDS_PINID='DQ4_B';
NET_NAME
'M_D_CPU0_SB_DQ<5>'
 '@T6G_MB_LIB.T6G(SCH_1):M_D_CPU0_SB_DQ'<5>:
 C_SIGNAL='@t6g_mb_lib.t6g(sch_1):m_d_cpu0_sb_dq(5)';
NODE_NAME     U25 CG59
 '@T6G_MB_LIB.T6G(SCH_1):PAGE13_I159@PURE_QUANTA.GENOA_SP5(CHIPS)':
 'MDB_DATA5': CDS_PINID='MDB_DATA5';
NODE_NAME     J19 109
 '@T6G_MB_LIB.T6G(SCH_1):PAGE88_I350@PURE_QUANTA.SCONN288_DDR506112002KQ(CHIPS)':
 'DQ5_B': CDS_PINID='DQ5_B';
NET_NAME
'M_D_CPU0_SB_DQ<6>'
 '@T6G_MB_LIB.T6G(SCH_1):M_D_CPU0_SB_DQ'<6>:
 C_SIGNAL='@t6g_mb_lib.t6g(sch_1):m_d_cpu0_sb_dq(6)';
NODE_NAME     U25 CG60
 '@T6G_MB_LIB.T6G(SCH_1):PAGE13_I159@PURE_QUANTA.GENOA_SP5(CHIPS)':
 'MDB_DATA6': CDS_PINID='MDB_DATA6';
NODE_NAME     J19 252
 '@T6G_MB_LIB.T6G(SCH_1):PAGE88_I350@PURE_QUANTA.SCONN288_DDR506112002KQ(CHIPS)':
 'DQ6_B': CDS_PINID='DQ6_B';
NET_NAME
'M_D_CPU0_SB_DQ<7>'
 '@T6G_MB_LIB.T6G(SCH_1):M_D_CPU0_SB_DQ'<7>:
 C_SIGNAL='@t6g_mb_lib.t6g(sch_1):m_d_cpu0_sb_dq(7)';
NODE_NAME     U25 CH58
 '@T6G_MB_LIB.T6G(SCH_1):PAGE13_I159@PURE_QUANTA.GENOA_SP5(CHIPS)':
 'MDB_DATA7': CDS_PINID='MDB_DATA7';
NODE_NAME     J19 254
 '@T6G_MB_LIB.T6G(SCH_1):PAGE88_I350@PURE_QUANTA.SCONN288_DDR506112002KQ(CHIPS)':
 'DQ7_B': CDS_PINID='DQ7_B';
NET_NAME
'M_D_CPU0_SB_DQ<8>'
 '@T6G_MB_LIB.T6G(SCH_1):M_D_CPU0_SB_DQ'<8>:
 C_SIGNAL='@t6g_mb_lib.t6g(sch_1):m_d_cpu0_sb_dq(8)';
NODE_NAME     U25 CH60
 '@T6G_MB_LIB.T6G(SCH_1):PAGE13_I159@PURE_QUANTA.GENOA_SP5(CHIPS)':
 'MDB_DATA8': CDS_PINID='MDB_DATA8';
NODE_NAME     J19 111
 '@T6G_MB_LIB.T6G(SCH_1):PAGE88_I350@PURE_QUANTA.SCONN288_DDR506112002KQ(CHIPS)':
 'DQ8_B': CDS_PINID='DQ8_B';
NET_NAME
'M_D_CPU0_SB_DQ<9>'
 '@T6G_MB_LIB.T6G(SCH_1):M_D_CPU0_SB_DQ'<9>:
 C_SIGNAL='@t6g_mb_lib.t6g(sch_1):m_d_cpu0_sb_dq(9)';
NODE_NAME     U25 CJ59
 '@T6G_MB_LIB.T6G(SCH_1):PAGE13_I159@PURE_QUANTA.GENOA_SP5(CHIPS)':
 'MDB_DATA9': CDS_PINID='MDB_DATA9';
NODE_NAME     J19 113
 '@T6G_MB_LIB.T6G(SCH_1):PAGE88_I350@PURE_QUANTA.SCONN288_DDR506112002KQ(CHIPS)':
 'DQ9_B': CDS_PINID='DQ9_B';
NET_NAME
'M_D_CPU0_SB_DQS_DN<0>'
 '@T6G_MB_LIB.T6G(SCH_1):M_D_CPU0_SB_DQS_DN'<0>:
 C_SIGNAL='@t6g_mb_lib.t6g(sch_1):m_d_cpu0_sb_dqs_dn(0)';
NODE_NAME     U25 CE60
 '@T6G_MB_LIB.T6G(SCH_1):PAGE13_I159@PURE_QUANTA.GENOA_SP5(CHIPS)':
 'MDB_DQS_L0': CDS_PINID='MDB_DQS_L0';
NODE_NAME     J19 105
 '@T6G_MB_LIB.T6G(SCH_1):PAGE88_I415@PURE_QUANTA.SCONN288_DDR506112002KQ(CHIPS)':
 'DQS0_B_C': CDS_PINID='DQS0_B_C';
NET_NAME
'M_D_CPU0_SB_DQS_DN<1>'
 '@T6G_MB_LIB.T6G(SCH_1):M_D_CPU0_SB_DQS_DN'<1>:
 C_SIGNAL='@t6g_mb_lib.t6g(sch_1):m_d_cpu0_sb_dqs_dn(1)';
NODE_NAME     U25 CL60
 '@T6G_MB_LIB.T6G(SCH_1):PAGE13_I159@PURE_QUANTA.GENOA_SP5(CHIPS)':
 'MDB_DQS_L1': CDS_PINID='MDB_DQS_L1';
NODE_NAME     J19 116
 '@T6G_MB_LIB.T6G(SCH_1):PAGE88_I415@PURE_QUANTA.SCONN288_DDR506112002KQ(CHIPS)':
 'DQS1_B_C': CDS_PINID='DQS1_B_C';
NET_NAME
'M_D_CPU0_SB_DQS_DN<2>'
 '@T6G_MB_LIB.T6G(SCH_1):M_D_CPU0_SB_DQS_DN'<2>:
 C_SIGNAL='@t6g_mb_lib.t6g(sch_1):m_d_cpu0_sb_dqs_dn(2)';
NODE_NAME     U25 CU60
 '@T6G_MB_LIB.T6G(SCH_1):PAGE13_I159@PURE_QUANTA.GENOA_SP5(CHIPS)':
 'MDB_DQS_L2': CDS_PINID='MDB_DQS_L2';
NODE_NAME     J19 127
 '@T6G_MB_LIB.T6G(SCH_1):PAGE88_I415@PURE_QUANTA.SCONN288_DDR506112002KQ(CHIPS)':
 'DQS2_B_C': CDS_PINID='DQS2_B_C';
NET_NAME
'M_D_CPU0_SB_DQS_DN<3>'
 '@T6G_MB_LIB.T6G(SCH_1):M_D_CPU0_SB_DQS_DN'<3>:
 C_SIGNAL='@t6g_mb_lib.t6g(sch_1):m_d_cpu0_sb_dqs_dn(3)';
NODE_NAME     U25 DC60
 '@T6G_MB_LIB.T6G(SCH_1):PAGE13_I159@PURE_QUANTA.GENOA_SP5(CHIPS)':
 'MDB_DQS_L3': CDS_PINID='MDB_DQS_L3';
NODE_NAME     J19 138
 '@T6G_MB_LIB.T6G(SCH_1):PAGE88_I415@PURE_QUANTA.SCONN288_DDR506112002KQ(CHIPS)':
 'DQS3_B_C': CDS_PINID='DQS3_B_C';
NET_NAME
'M_D_CPU0_SB_DQS_DN<4>'
 '@T6G_MB_LIB.T6G(SCH_1):M_D_CPU0_SB_DQS_DN'<4>:
 C_SIGNAL='@t6g_mb_lib.t6g(sch_1):m_d_cpu0_sb_dqs_dn(4)';
NODE_NAME     U25 BW59
 '@T6G_MB_LIB.T6G(SCH_1):PAGE13_I159@PURE_QUANTA.GENOA_SP5(CHIPS)':
 'MDB_DQS_L4': CDS_PINID='MDB_DQS_L4';
NODE_NAME     J19 238
 '@T6G_MB_LIB.T6G(SCH_1):PAGE88_I415@PURE_QUANTA.SCONN288_DDR506112002KQ(CHIPS)':
 'DQS4_B_C': CDS_PINID='DQS4_B_C';
NET_NAME
'M_D_CPU0_SB_DQS_DN<5>'
 '@T6G_MB_LIB.T6G(SCH_1):M_D_CPU0_SB_DQS_DN'<5>:
 C_SIGNAL='@t6g_mb_lib.t6g(sch_1):m_d_cpu0_sb_dqs_dn(5)';
NODE_NAME     U25 CE59
 '@T6G_MB_LIB.T6G(SCH_1):PAGE13_I159@PURE_QUANTA.GENOA_SP5(CHIPS)':
 'MDB_DQS_L5': CDS_PINID='MDB_DQS_L5';
NODE_NAME     J19 249
 '@T6G_MB_LIB.T6G(SCH_1):PAGE88_I415@PURE_QUANTA.SCONN288_DDR506112002KQ(CHIPS)':
 'DQS5_B_C||TDQS5_B_C': CDS_PINID='\dqs5_b_c||tdqs5_b_c\';
NET_NAME
'M_D_CPU0_SB_DQS_DN<6>'
 '@T6G_MB_LIB.T6G(SCH_1):M_D_CPU0_SB_DQS_DN'<6>:
 C_SIGNAL='@t6g_mb_lib.t6g(sch_1):m_d_cpu0_sb_dqs_dn(6)';
NODE_NAME     U25 CL59
 '@T6G_MB_LIB.T6G(SCH_1):PAGE13_I159@PURE_QUANTA.GENOA_SP5(CHIPS)':
 'MDB_DQS_L6': CDS_PINID='MDB_DQS_L6';
NODE_NAME     J19 260
 '@T6G_MB_LIB.T6G(SCH_1):PAGE88_I415@PURE_QUANTA.SCONN288_DDR506112002KQ(CHIPS)':
 'DQS6_B_C||TDQS6_B_C': CDS_PINID='\dqs6_b_c||tdqs6_b_c\';
NET_NAME
'M_D_CPU0_SB_DQS_DN<7>'
 '@T6G_MB_LIB.T6G(SCH_1):M_D_CPU0_SB_DQS_DN'<7>:
 C_SIGNAL='@t6g_mb_lib.t6g(sch_1):m_d_cpu0_sb_dqs_dn(7)';
NODE_NAME     U25 CU59
 '@T6G_MB_LIB.T6G(SCH_1):PAGE13_I159@PURE_QUANTA.GENOA_SP5(CHIPS)':
 'MDB_DQS_L7': CDS_PINID='MDB_DQS_L7';
NODE_NAME     J19 271
 '@T6G_MB_LIB.T6G(SCH_1):PAGE88_I415@PURE_QUANTA.SCONN288_DDR506112002KQ(CHIPS)':
 'DQS7_B_C||TDQS7_B_C': CDS_PINID='\dqs7_b_c||tdqs7_b_c\';
NET_NAME
'M_D_CPU0_SB_DQS_DN<8>'
 '@T6G_MB_LIB.T6G(SCH_1):M_D_CPU0_SB_DQS_DN'<8>:
 C_SIGNAL='@t6g_mb_lib.t6g(sch_1):m_d_cpu0_sb_dqs_dn(8)';
NODE_NAME     U25 DC59
 '@T6G_MB_LIB.T6G(SCH_1):PAGE13_I159@PURE_QUANTA.GENOA_SP5(CHIPS)':
 'MDB_DQS_L8': CDS_PINID='MDB_DQS_L8';
NODE_NAME     J19 282
 '@T6G_MB_LIB.T6G(SCH_1):PAGE88_I415@PURE_QUANTA.SCONN288_DDR506112002KQ(CHIPS)':
 'DQS8_B_C||TDQS8_B_C': CDS_PINID='\dqs8_b_c||tdqs8_b_c\';
NET_NAME
'M_D_CPU0_SB_DQS_DN<9>'
 '@T6G_MB_LIB.T6G(SCH_1):M_D_CPU0_SB_DQS_DN'<9>:
 C_SIGNAL='@t6g_mb_lib.t6g(sch_1):m_d_cpu0_sb_dqs_dn(9)';
NODE_NAME     U25 BW60
 '@T6G_MB_LIB.T6G(SCH_1):PAGE13_I159@PURE_QUANTA.GENOA_SP5(CHIPS)':
 'MDB_DQS_L9': CDS_PINID='MDB_DQS_L9';
NODE_NAME     J19 94
 '@T6G_MB_LIB.T6G(SCH_1):PAGE88_I415@PURE_QUANTA.SCONN288_DDR506112002KQ(CHIPS)':
 'DQS9_B_C||TDQS9_B_C': CDS_PINID='\dqs9_b_c||tdqs9_b_c\';
NET_NAME
'M_D_CPU0_SB_DQS_DP<0>'
 '@T6G_MB_LIB.T6G(SCH_1):M_D_CPU0_SB_DQS_DP'<0>:
 C_SIGNAL='@t6g_mb_lib.t6g(sch_1):m_d_cpu0_sb_dqs_dp(0)';
NODE_NAME     U25 CD60
 '@T6G_MB_LIB.T6G(SCH_1):PAGE13_I159@PURE_QUANTA.GENOA_SP5(CHIPS)':
 'MDB_DQS_H0': CDS_PINID='MDB_DQS_H0';
NODE_NAME     J19 104
 '@T6G_MB_LIB.T6G(SCH_1):PAGE88_I415@PURE_QUANTA.SCONN288_DDR506112002KQ(CHIPS)':
 'DQS0_B_T': CDS_PINID='DQS0_B_T';
NET_NAME
'M_D_CPU0_SB_DQS_DP<1>'
 '@T6G_MB_LIB.T6G(SCH_1):M_D_CPU0_SB_DQS_DP'<1>:
 C_SIGNAL='@t6g_mb_lib.t6g(sch_1):m_d_cpu0_sb_dqs_dp(1)';
NODE_NAME     U25 CK60
 '@T6G_MB_LIB.T6G(SCH_1):PAGE13_I159@PURE_QUANTA.GENOA_SP5(CHIPS)':
 'MDB_DQS_H1': CDS_PINID='MDB_DQS_H1';
NODE_NAME     J19 115
 '@T6G_MB_LIB.T6G(SCH_1):PAGE88_I415@PURE_QUANTA.SCONN288_DDR506112002KQ(CHIPS)':
 'DQS1_B_T': CDS_PINID='DQS1_B_T';
NET_NAME
'M_D_CPU0_SB_DQS_DP<2>'
 '@T6G_MB_LIB.T6G(SCH_1):M_D_CPU0_SB_DQS_DP'<2>:
 C_SIGNAL='@t6g_mb_lib.t6g(sch_1):m_d_cpu0_sb_dqs_dp(2)';
NODE_NAME     U25 CT60
 '@T6G_MB_LIB.T6G(SCH_1):PAGE13_I159@PURE_QUANTA.GENOA_SP5(CHIPS)':
 'MDB_DQS_H2': CDS_PINID='MDB_DQS_H2';
NODE_NAME     J19 126
 '@T6G_MB_LIB.T6G(SCH_1):PAGE88_I415@PURE_QUANTA.SCONN288_DDR506112002KQ(CHIPS)':
 'DQS2_B_T': CDS_PINID='DQS2_B_T';
NET_NAME
'M_D_CPU0_SB_DQS_DP<3>'
 '@T6G_MB_LIB.T6G(SCH_1):M_D_CPU0_SB_DQS_DP'<3>:
 C_SIGNAL='@t6g_mb_lib.t6g(sch_1):m_d_cpu0_sb_dqs_dp(3)';
NODE_NAME     U25 DB60
 '@T6G_MB_LIB.T6G(SCH_1):PAGE13_I159@PURE_QUANTA.GENOA_SP5(CHIPS)':
 'MDB_DQS_H3': CDS_PINID='MDB_DQS_H3';
NODE_NAME     J19 137
 '@T6G_MB_LIB.T6G(SCH_1):PAGE88_I415@PURE_QUANTA.SCONN288_DDR506112002KQ(CHIPS)':
 'DQS3_B_T': CDS_PINID='DQS3_B_T';
NET_NAME
'M_D_CPU0_SB_DQS_DP<4>'
 '@T6G_MB_LIB.T6G(SCH_1):M_D_CPU0_SB_DQS_DP'<4>:
 C_SIGNAL='@t6g_mb_lib.t6g(sch_1):m_d_cpu0_sb_dqs_dp(4)';
NODE_NAME     U25 BY58
 '@T6G_MB_LIB.T6G(SCH_1):PAGE13_I159@PURE_QUANTA.GENOA_SP5(CHIPS)':
 'MDB_DQS_H4': CDS_PINID='MDB_DQS_H4';
NODE_NAME     J19 239
 '@T6G_MB_LIB.T6G(SCH_1):PAGE88_I415@PURE_QUANTA.SCONN288_DDR506112002KQ(CHIPS)':
 'DQS4_B_T': CDS_PINID='DQS4_B_T';
NET_NAME
'M_D_CPU0_SB_DQS_DP<5>'
 '@T6G_MB_LIB.T6G(SCH_1):M_D_CPU0_SB_DQS_DP'<5>:
 C_SIGNAL='@t6g_mb_lib.t6g(sch_1):m_d_cpu0_sb_dqs_dp(5)';
NODE_NAME     U25 CF58
 '@T6G_MB_LIB.T6G(SCH_1):PAGE13_I159@PURE_QUANTA.GENOA_SP5(CHIPS)':
 'MDB_DQS_H5': CDS_PINID='MDB_DQS_H5';
NODE_NAME     J19 250
 '@T6G_MB_LIB.T6G(SCH_1):PAGE88_I415@PURE_QUANTA.SCONN288_DDR506112002KQ(CHIPS)':
 'DQS5_B_T||TDQS5_B_T': CDS_PINID='\dqs5_b_t||tdqs5_b_t\';
NET_NAME
'M_D_CPU0_SB_DQS_DP<6>'
 '@T6G_MB_LIB.T6G(SCH_1):M_D_CPU0_SB_DQS_DP'<6>:
 C_SIGNAL='@t6g_mb_lib.t6g(sch_1):m_d_cpu0_sb_dqs_dp(6)';
NODE_NAME     U25 CM58
 '@T6G_MB_LIB.T6G(SCH_1):PAGE13_I159@PURE_QUANTA.GENOA_SP5(CHIPS)':
 'MDB_DQS_H6': CDS_PINID='MDB_DQS_H6';
NODE_NAME     J19 261
 '@T6G_MB_LIB.T6G(SCH_1):PAGE88_I415@PURE_QUANTA.SCONN288_DDR506112002KQ(CHIPS)':
 'DQS6_B_T||TDQS6_B_T': CDS_PINID='\dqs6_b_t||tdqs6_b_t\';
NET_NAME
'M_D_CPU0_SB_DQS_DP<7>'
 '@T6G_MB_LIB.T6G(SCH_1):M_D_CPU0_SB_DQS_DP'<7>:
 C_SIGNAL='@t6g_mb_lib.t6g(sch_1):m_d_cpu0_sb_dqs_dp(7)';
NODE_NAME     U25 CV58
 '@T6G_MB_LIB.T6G(SCH_1):PAGE13_I159@PURE_QUANTA.GENOA_SP5(CHIPS)':
 'MDB_DQS_H7': CDS_PINID='MDB_DQS_H7';
NODE_NAME     J19 272
 '@T6G_MB_LIB.T6G(SCH_1):PAGE88_I415@PURE_QUANTA.SCONN288_DDR506112002KQ(CHIPS)':
 'DQS7_B_T||TDQS7_B_T': CDS_PINID='\dqs7_b_t||tdqs7_b_t\';
NET_NAME
'M_D_CPU0_SB_DQS_DP<8>'
 '@T6G_MB_LIB.T6G(SCH_1):M_D_CPU0_SB_DQS_DP'<8>:
 C_SIGNAL='@t6g_mb_lib.t6g(sch_1):m_d_cpu0_sb_dqs_dp(8)';
NODE_NAME     U25 DD58
 '@T6G_MB_LIB.T6G(SCH_1):PAGE13_I159@PURE_QUANTA.GENOA_SP5(CHIPS)':
 'MDB_DQS_H8': CDS_PINID='MDB_DQS_H8';
NODE_NAME     J19 283
 '@T6G_MB_LIB.T6G(SCH_1):PAGE88_I415@PURE_QUANTA.SCONN288_DDR506112002KQ(CHIPS)':
 'DQS8_B_T||TDQS8_B_T': CDS_PINID='\dqs8_b_t||tdqs8_b_t\';
NET_NAME
'M_D_CPU0_SB_DQS_DP<9>'
 '@T6G_MB_LIB.T6G(SCH_1):M_D_CPU0_SB_DQS_DP'<9>:
 C_SIGNAL='@t6g_mb_lib.t6g(sch_1):m_d_cpu0_sb_dqs_dp(9)';
NODE_NAME     U25 BV60
 '@T6G_MB_LIB.T6G(SCH_1):PAGE13_I159@PURE_QUANTA.GENOA_SP5(CHIPS)':
 'MDB_DQS_H9': CDS_PINID='MDB_DQS_H9';
NODE_NAME     J19 93
 '@T6G_MB_LIB.T6G(SCH_1):PAGE88_I415@PURE_QUANTA.SCONN288_DDR506112002KQ(CHIPS)':
 'DQS9_B_T||TDQS9_B_T||DBI4_B_N': CDS_PINID='\dqs9_b_t||tdqs9_b_t||dbi4_b_n\';
NET_NAME
'M_D_CPU0_SB_PAR'
 '@T6G_MB_LIB.T6G(SCH_1):M_D_CPU0_SB_PAR':
 C_SIGNAL='@t6g_mb_lib.t6g(sch_1):m_d_cpu0_sb_par';
NODE_NAME     U25 BL60
 '@T6G_MB_LIB.T6G(SCH_1):PAGE13_I159@PURE_QUANTA.GENOA_SP5(CHIPS)':
 'MDB_PAR': CDS_PINID='MDB_PAR';
NODE_NAME     J19 227
 '@T6G_MB_LIB.T6G(SCH_1):PAGE88_I350@PURE_QUANTA.SCONN288_DDR506112002KQ(CHIPS)':
 'PAR_B': CDS_PINID='PAR_B';
NET_NAME
'M_D_CPU0_SB_RSP<0>'
 '@T6G_MB_LIB.T6G(SCH_1):M_D_CPU0_SB_RSP'<0>:
 C_SIGNAL='@t6g_mb_lib.t6g(sch_1):m_d_cpu0_sb_rsp(0)';
NODE_NAME     U25 BP60
 '@T6G_MB_LIB.T6G(SCH_1):PAGE13_I159@PURE_QUANTA.GENOA_SP5(CHIPS)':
 'MDB0_RSP_L': CDS_PINID='MDB0_RSP_L';
NODE_NAME     J19 87
 '@T6G_MB_LIB.T6G(SCH_1):PAGE88_I350@PURE_QUANTA.SCONN288_DDR506112002KQ(CHIPS)':
 'LBS||RSP_B_N': CDS_PINID='\lbs||rsp_b_n\';
NET_NAME
'M_D_CPU1_ALERT_N'
 '@T6G_MB_LIB.T6G(SCH_1):M_D_CPU1_ALERT_N':
 C_SIGNAL='@t6g_mb_lib.t6g(sch_1):m_d_cpu1_alert_n';
NODE_NAME     R503 1
 '@T6G_MB_LIB.T6G(SCH_1):PAGE40_I314@PURE_QUANTA.Q_RES(CHIPS)':
 'A': CDS_PINID='A';
NODE_NAME     J30 62
 '@T6G_MB_LIB.T6G(SCH_1):PAGE100_I52@PURE_QUANTA.SCONN288_DDR506112002KQ(CHIPS)':
 'ALERT_N': CDS_PINID='ALERT_N';
NET_NAME
'M_D_CPU1_ALERT_R_N'
 '@T6G_MB_LIB.T6G(SCH_1):M_D_CPU1_ALERT_R_N':
 C_SIGNAL='@t6g_mb_lib.t6g(sch_1):m_d_cpu1_alert_r_n';
NODE_NAME     U26 AT58
 '@T6G_MB_LIB.T6G(SCH_1):PAGE40_I159@PURE_QUANTA.GENOA_SP5(CHIPS)':
 'MD_ALERT_L': CDS_PINID='MD_ALERT_L';
NODE_NAME     R503 2
 '@T6G_MB_LIB.T6G(SCH_1):PAGE40_I314@PURE_QUANTA.Q_RES(CHIPS)':
 'B': CDS_PINID='B';
NET_NAME
'M_D_CPU1_CLK_DN<0>'
 '@T6G_MB_LIB.T6G(SCH_1):M_D_CPU1_CLK_DN'<0>:
 C_SIGNAL='@t6g_mb_lib.t6g(sch_1):m_d_cpu1_clk_dn(0)';
NODE_NAME     U26 BD60
 '@T6G_MB_LIB.T6G(SCH_1):PAGE40_I159@PURE_QUANTA.GENOA_SP5(CHIPS)':
 'MD0_CLK_L': CDS_PINID='MD0_CLK_L';
NODE_NAME     J30 218
 '@T6G_MB_LIB.T6G(SCH_1):PAGE100_I52@PURE_QUANTA.SCONN288_DDR506112002KQ(CHIPS)':
 'CK_C': CDS_PINID='CK_C';
NET_NAME
'M_D_CPU1_CLK_DP<0>'
 '@T6G_MB_LIB.T6G(SCH_1):M_D_CPU1_CLK_DP'<0>:
 C_SIGNAL='@t6g_mb_lib.t6g(sch_1):m_d_cpu1_clk_dp(0)';
NODE_NAME     U26 BC60
 '@T6G_MB_LIB.T6G(SCH_1):PAGE40_I159@PURE_QUANTA.GENOA_SP5(CHIPS)':
 'MD0_CLK_H': CDS_PINID='MD0_CLK_H';
NODE_NAME     J30 217
 '@T6G_MB_LIB.T6G(SCH_1):PAGE100_I52@PURE_QUANTA.SCONN288_DDR506112002KQ(CHIPS)':
 'CK_T': CDS_PINID='CK_T';
NET_NAME
'M_D_CPU1_RESET_N'
 '@T6G_MB_LIB.T6G(SCH_1):M_D_CPU1_RESET_N':
 C_SIGNAL='@t6g_mb_lib.t6g(sch_1):m_d_cpu1_reset_n';
NODE_NAME     U26 AU59
 '@T6G_MB_LIB.T6G(SCH_1):PAGE40_I159@PURE_QUANTA.GENOA_SP5(CHIPS)':
 'MD_RESET_L': CDS_PINID='MD_RESET_L';
NODE_NAME     J30 207
 '@T6G_MB_LIB.T6G(SCH_1):PAGE100_I52@PURE_QUANTA.SCONN288_DDR506112002KQ(CHIPS)':
 'RESET_N': CDS_PINID='RESET_N';
NET_NAME
'M_D_CPU1_SA_CA<0>'
 '@T6G_MB_LIB.T6G(SCH_1):M_D_CPU1_SA_CA'<0>:
 C_SIGNAL='@t6g_mb_lib.t6g(sch_1):m_d_cpu1_sa_ca(0)';
NODE_NAME     U26 AW60
 '@T6G_MB_LIB.T6G(SCH_1):PAGE40_I159@PURE_QUANTA.GENOA_SP5(CHIPS)':
 'MDA_CA0': CDS_PINID='MDA_CA0';
NODE_NAME     J30 66
 '@T6G_MB_LIB.T6G(SCH_1):PAGE100_I52@PURE_QUANTA.SCONN288_DDR506112002KQ(CHIPS)':
 'CA0_A': CDS_PINID='CA0_A';
NET_NAME
'M_D_CPU1_SA_CA<1>'
 '@T6G_MB_LIB.T6G(SCH_1):M_D_CPU1_SA_CA'<1>:
 C_SIGNAL='@t6g_mb_lib.t6g(sch_1):m_d_cpu1_sa_ca(1)';
NODE_NAME     U26 AY60
 '@T6G_MB_LIB.T6G(SCH_1):PAGE40_I159@PURE_QUANTA.GENOA_SP5(CHIPS)':
 'MDA_CA1': CDS_PINID='MDA_CA1';
NODE_NAME     J30 211
 '@T6G_MB_LIB.T6G(SCH_1):PAGE100_I52@PURE_QUANTA.SCONN288_DDR506112002KQ(CHIPS)':
 'CA1_A': CDS_PINID='CA1_A';
NET_NAME
'M_D_CPU1_SA_CA<2>'
 '@T6G_MB_LIB.T6G(SCH_1):M_D_CPU1_SA_CA'<2>:
 C_SIGNAL='@t6g_mb_lib.t6g(sch_1):m_d_cpu1_sa_ca(2)';
NODE_NAME     U26 AY58
 '@T6G_MB_LIB.T6G(SCH_1):PAGE40_I159@PURE_QUANTA.GENOA_SP5(CHIPS)':
 'MDA_CA2': CDS_PINID='MDA_CA2';
NODE_NAME     J30 68
 '@T6G_MB_LIB.T6G(SCH_1):PAGE100_I52@PURE_QUANTA.SCONN288_DDR506112002KQ(CHIPS)':
 'CA2_A': CDS_PINID='CA2_A';
NET_NAME
'M_D_CPU1_SA_CA<3>'
 '@T6G_MB_LIB.T6G(SCH_1):M_D_CPU1_SA_CA'<3>:
 C_SIGNAL='@t6g_mb_lib.t6g(sch_1):m_d_cpu1_sa_ca(3)';
NODE_NAME     U26 BA59
 '@T6G_MB_LIB.T6G(SCH_1):PAGE40_I159@PURE_QUANTA.GENOA_SP5(CHIPS)':
 'MDA_CA3': CDS_PINID='MDA_CA3';
NODE_NAME     J30 213
 '@T6G_MB_LIB.T6G(SCH_1):PAGE100_I52@PURE_QUANTA.SCONN288_DDR506112002KQ(CHIPS)':
 'CA3_A': CDS_PINID='CA3_A';
NET_NAME
'M_D_CPU1_SA_CA<4>'
 '@T6G_MB_LIB.T6G(SCH_1):M_D_CPU1_SA_CA'<4>:
 C_SIGNAL='@t6g_mb_lib.t6g(sch_1):m_d_cpu1_sa_ca(4)';
NODE_NAME     U26 BA60
 '@T6G_MB_LIB.T6G(SCH_1):PAGE40_I159@PURE_QUANTA.GENOA_SP5(CHIPS)':
 'MDA_CA4': CDS_PINID='MDA_CA4';
NODE_NAME     J30 70
 '@T6G_MB_LIB.T6G(SCH_1):PAGE100_I52@PURE_QUANTA.SCONN288_DDR506112002KQ(CHIPS)':
 'CA4_A': CDS_PINID='CA4_A';
NET_NAME
'M_D_CPU1_SA_CA<5>'
 '@T6G_MB_LIB.T6G(SCH_1):M_D_CPU1_SA_CA'<5>:
 C_SIGNAL='@t6g_mb_lib.t6g(sch_1):m_d_cpu1_sa_ca(5)';
NODE_NAME     U26 BB60
 '@T6G_MB_LIB.T6G(SCH_1):PAGE40_I159@PURE_QUANTA.GENOA_SP5(CHIPS)':
 'MDA_CA5': CDS_PINID='MDA_CA5';
NODE_NAME     J30 215
 '@T6G_MB_LIB.T6G(SCH_1):PAGE100_I52@PURE_QUANTA.SCONN288_DDR506112002KQ(CHIPS)':
 'CA5_A': CDS_PINID='CA5_A';
NET_NAME
'M_D_CPU1_SA_CA<6>'
 '@T6G_MB_LIB.T6G(SCH_1):M_D_CPU1_SA_CA'<6>:
 C_SIGNAL='@t6g_mb_lib.t6g(sch_1):m_d_cpu1_sa_ca(6)';
NODE_NAME     U26 BB58
 '@T6G_MB_LIB.T6G(SCH_1):PAGE40_I159@PURE_QUANTA.GENOA_SP5(CHIPS)':
 'MDA_CA6': CDS_PINID='MDA_CA6';
NODE_NAME     J30 72
 '@T6G_MB_LIB.T6G(SCH_1):PAGE100_I52@PURE_QUANTA.SCONN288_DDR506112002KQ(CHIPS)':
 'CA6_A': CDS_PINID='CA6_A';
NET_NAME
'M_D_CPU1_SA_CB<0>'
 '@T6G_MB_LIB.T6G(SCH_1):M_D_CPU1_SA_CB'<0>:
 C_SIGNAL='@t6g_mb_lib.t6g(sch_1):m_d_cpu1_sa_cb(0)';
NODE_NAME     U26 AJ60
 '@T6G_MB_LIB.T6G(SCH_1):PAGE40_I159@PURE_QUANTA.GENOA_SP5(CHIPS)':
 'MDA_CHECK0': CDS_PINID='MDA_CHECK0';
NODE_NAME     J30 51
 '@T6G_MB_LIB.T6G(SCH_1):PAGE100_I52@PURE_QUANTA.SCONN288_DDR506112002KQ(CHIPS)':
 'CB0_A': CDS_PINID='CB0_A';
NET_NAME
'M_D_CPU1_SA_CB<1>'
 '@T6G_MB_LIB.T6G(SCH_1):M_D_CPU1_SA_CB'<1>:
 C_SIGNAL='@t6g_mb_lib.t6g(sch_1):m_d_cpu1_sa_cb(1)';
NODE_NAME     U26 AK58
 '@T6G_MB_LIB.T6G(SCH_1):PAGE40_I159@PURE_QUANTA.GENOA_SP5(CHIPS)':
 'MDA_CHECK1': CDS_PINID='MDA_CHECK1';
NODE_NAME     J30 53
 '@T6G_MB_LIB.T6G(SCH_1):PAGE100_I52@PURE_QUANTA.SCONN288_DDR506112002KQ(CHIPS)':
 'CB1_A': CDS_PINID='CB1_A';
NET_NAME
'M_D_CPU1_SA_CB<2>'
 '@T6G_MB_LIB.T6G(SCH_1):M_D_CPU1_SA_CB'<2>:
 C_SIGNAL='@t6g_mb_lib.t6g(sch_1):m_d_cpu1_sa_cb(2)';
NODE_NAME     U26 AK60
 '@T6G_MB_LIB.T6G(SCH_1):PAGE40_I159@PURE_QUANTA.GENOA_SP5(CHIPS)':
 'MDA_CHECK2': CDS_PINID='MDA_CHECK2';
NODE_NAME     J30 196
 '@T6G_MB_LIB.T6G(SCH_1):PAGE100_I52@PURE_QUANTA.SCONN288_DDR506112002KQ(CHIPS)':
 'CB2_A': CDS_PINID='CB2_A';
NET_NAME
'M_D_CPU1_SA_CB<3>'
 '@T6G_MB_LIB.T6G(SCH_1):M_D_CPU1_SA_CB'<3>:
 C_SIGNAL='@t6g_mb_lib.t6g(sch_1):m_d_cpu1_sa_cb(3)';
NODE_NAME     U26 AL59
 '@T6G_MB_LIB.T6G(SCH_1):PAGE40_I159@PURE_QUANTA.GENOA_SP5(CHIPS)':
 'MDA_CHECK3': CDS_PINID='MDA_CHECK3';
NODE_NAME     J30 198
 '@T6G_MB_LIB.T6G(SCH_1):PAGE100_I52@PURE_QUANTA.SCONN288_DDR506112002KQ(CHIPS)':
 'CB3_A': CDS_PINID='CB3_A';
NET_NAME
'M_D_CPU1_SA_CB<4>'
 '@T6G_MB_LIB.T6G(SCH_1):M_D_CPU1_SA_CB'<4>:
 C_SIGNAL='@t6g_mb_lib.t6g(sch_1):m_d_cpu1_sa_cb(4)';
NODE_NAME     U26 AN60
 '@T6G_MB_LIB.T6G(SCH_1):PAGE40_I159@PURE_QUANTA.GENOA_SP5(CHIPS)':
 'MDA_CHECK4': CDS_PINID='MDA_CHECK4';
NODE_NAME     J30 58
 '@T6G_MB_LIB.T6G(SCH_1):PAGE100_I52@PURE_QUANTA.SCONN288_DDR506112002KQ(CHIPS)':
 'CB4_A': CDS_PINID='CB4_A';
NET_NAME
'M_D_CPU1_SA_CB<5>'
 '@T6G_MB_LIB.T6G(SCH_1):M_D_CPU1_SA_CB'<5>:
 C_SIGNAL='@t6g_mb_lib.t6g(sch_1):m_d_cpu1_sa_cb(5)';
NODE_NAME     U26 AP58
 '@T6G_MB_LIB.T6G(SCH_1):PAGE40_I159@PURE_QUANTA.GENOA_SP5(CHIPS)':
 'MDA_CHECK5': CDS_PINID='MDA_CHECK5';
NODE_NAME     J30 60
 '@T6G_MB_LIB.T6G(SCH_1):PAGE100_I52@PURE_QUANTA.SCONN288_DDR506112002KQ(CHIPS)':
 'CB5_A': CDS_PINID='CB5_A';
NET_NAME
'M_D_CPU1_SA_CB<6>'
 '@T6G_MB_LIB.T6G(SCH_1):M_D_CPU1_SA_CB'<6>:
 C_SIGNAL='@t6g_mb_lib.t6g(sch_1):m_d_cpu1_sa_cb(6)';
NODE_NAME     U26 AP60
 '@T6G_MB_LIB.T6G(SCH_1):PAGE40_I159@PURE_QUANTA.GENOA_SP5(CHIPS)':
 'MDA_CHECK6': CDS_PINID='MDA_CHECK6';
NODE_NAME     J30 203
 '@T6G_MB_LIB.T6G(SCH_1):PAGE100_I52@PURE_QUANTA.SCONN288_DDR506112002KQ(CHIPS)':
 'CB6_A': CDS_PINID='CB6_A';
NET_NAME
'M_D_CPU1_SA_CB<7>'
 '@T6G_MB_LIB.T6G(SCH_1):M_D_CPU1_SA_CB'<7>:
 C_SIGNAL='@t6g_mb_lib.t6g(sch_1):m_d_cpu1_sa_cb(7)';
NODE_NAME     U26 AR59
 '@T6G_MB_LIB.T6G(SCH_1):PAGE40_I159@PURE_QUANTA.GENOA_SP5(CHIPS)':
 'MDA_CHECK7': CDS_PINID='MDA_CHECK7';
NODE_NAME     J30 205
 '@T6G_MB_LIB.T6G(SCH_1):PAGE100_I52@PURE_QUANTA.SCONN288_DDR506112002KQ(CHIPS)':
 'CB7_A': CDS_PINID='CB7_A';
NET_NAME
'M_D_CPU1_SA_CS_N<0>'
 '@T6G_MB_LIB.T6G(SCH_1):M_D_CPU1_SA_CS_N'<0>:
 C_SIGNAL='@t6g_mb_lib.t6g(sch_1):m_d_cpu1_sa_cs_n(0)';
NODE_NAME     U26 AV60
 '@T6G_MB_LIB.T6G(SCH_1):PAGE40_I159@PURE_QUANTA.GENOA_SP5(CHIPS)':
 'MDA0_CS_L0': CDS_PINID='MDA0_CS_L0';
NODE_NAME     J30 64
 '@T6G_MB_LIB.T6G(SCH_1):PAGE100_I52@PURE_QUANTA.SCONN288_DDR506112002KQ(CHIPS)':
 'CS0_A_N': CDS_PINID='CS0_A_N';
NET_NAME
'M_D_CPU1_SA_CS_N<1>'
 '@T6G_MB_LIB.T6G(SCH_1):M_D_CPU1_SA_CS_N'<1>:
 C_SIGNAL='@t6g_mb_lib.t6g(sch_1):m_d_cpu1_sa_cs_n(1)';
NODE_NAME     U26 AW59
 '@T6G_MB_LIB.T6G(SCH_1):PAGE40_I159@PURE_QUANTA.GENOA_SP5(CHIPS)':
 'MDA0_CS_L1': CDS_PINID='MDA0_CS_L1';
NODE_NAME     J30 209
 '@T6G_MB_LIB.T6G(SCH_1):PAGE100_I52@PURE_QUANTA.SCONN288_DDR506112002KQ(CHIPS)':
 'CS1_A_N': CDS_PINID='CS1_A_N';
NET_NAME
'M_D_CPU1_SA_DQ<0>'
 '@T6G_MB_LIB.T6G(SCH_1):M_D_CPU1_SA_DQ'<0>:
 C_SIGNAL='@t6g_mb_lib.t6g(sch_1):m_d_cpu1_sa_dq(0)';
NODE_NAME     U26 E60
 '@T6G_MB_LIB.T6G(SCH_1):PAGE40_I159@PURE_QUANTA.GENOA_SP5(CHIPS)':
 'MDA_DATA0': CDS_PINID='MDA_DATA0';
NODE_NAME     J30 7
 '@T6G_MB_LIB.T6G(SCH_1):PAGE100_I52@PURE_QUANTA.SCONN288_DDR506112002KQ(CHIPS)':
 'DQ0_A': CDS_PINID='DQ0_A';
NET_NAME
'M_D_CPU1_SA_DQ<10>'
 '@T6G_MB_LIB.T6G(SCH_1):M_D_CPU1_SA_DQ'<10>:
 C_SIGNAL='@t6g_mb_lib.t6g(sch_1):m_d_cpu1_sa_dq(10)';
NODE_NAME     U26 M60
 '@T6G_MB_LIB.T6G(SCH_1):PAGE40_I159@PURE_QUANTA.GENOA_SP5(CHIPS)':
 'MDA_DATA10': CDS_PINID='MDA_DATA10';
NODE_NAME     J30 163
 '@T6G_MB_LIB.T6G(SCH_1):PAGE100_I52@PURE_QUANTA.SCONN288_DDR506112002KQ(CHIPS)':
 'DQ10_A': CDS_PINID='DQ10_A';
NET_NAME
'M_D_CPU1_SA_DQ<11>'
 '@T6G_MB_LIB.T6G(SCH_1):M_D_CPU1_SA_DQ'<11>:
 C_SIGNAL='@t6g_mb_lib.t6g(sch_1):m_d_cpu1_sa_dq(11)';
NODE_NAME     U26 N59
 '@T6G_MB_LIB.T6G(SCH_1):PAGE40_I159@PURE_QUANTA.GENOA_SP5(CHIPS)':
 'MDA_DATA11': CDS_PINID='MDA_DATA11';
NODE_NAME     J30 165
 '@T6G_MB_LIB.T6G(SCH_1):PAGE100_I52@PURE_QUANTA.SCONN288_DDR506112002KQ(CHIPS)':
 'DQ11_A': CDS_PINID='DQ11_A';
NET_NAME
'M_D_CPU1_SA_DQ<12>'
 '@T6G_MB_LIB.T6G(SCH_1):M_D_CPU1_SA_DQ'<12>:
 C_SIGNAL='@t6g_mb_lib.t6g(sch_1):m_d_cpu1_sa_dq(12)';
NODE_NAME     U26 R60
 '@T6G_MB_LIB.T6G(SCH_1):PAGE40_I159@PURE_QUANTA.GENOA_SP5(CHIPS)':
 'MDA_DATA12': CDS_PINID='MDA_DATA12';
NODE_NAME     J30 25
 '@T6G_MB_LIB.T6G(SCH_1):PAGE100_I52@PURE_QUANTA.SCONN288_DDR506112002KQ(CHIPS)':
 'DQ12_A': CDS_PINID='DQ12_A';
NET_NAME
'M_D_CPU1_SA_DQ<13>'
 '@T6G_MB_LIB.T6G(SCH_1):M_D_CPU1_SA_DQ'<13>:
 C_SIGNAL='@t6g_mb_lib.t6g(sch_1):m_d_cpu1_sa_dq(13)';
NODE_NAME     U26 T58
 '@T6G_MB_LIB.T6G(SCH_1):PAGE40_I159@PURE_QUANTA.GENOA_SP5(CHIPS)':
 'MDA_DATA13': CDS_PINID='MDA_DATA13';
NODE_NAME     J30 27
 '@T6G_MB_LIB.T6G(SCH_1):PAGE100_I52@PURE_QUANTA.SCONN288_DDR506112002KQ(CHIPS)':
 'DQ13_A': CDS_PINID='DQ13_A';
NET_NAME
'M_D_CPU1_SA_DQ<14>'
 '@T6G_MB_LIB.T6G(SCH_1):M_D_CPU1_SA_DQ'<14>:
 C_SIGNAL='@t6g_mb_lib.t6g(sch_1):m_d_cpu1_sa_dq(14)';
NODE_NAME     U26 T60
 '@T6G_MB_LIB.T6G(SCH_1):PAGE40_I159@PURE_QUANTA.GENOA_SP5(CHIPS)':
 'MDA_DATA14': CDS_PINID='MDA_DATA14';
NODE_NAME     J30 170
 '@T6G_MB_LIB.T6G(SCH_1):PAGE100_I52@PURE_QUANTA.SCONN288_DDR506112002KQ(CHIPS)':
 'DQ14_A': CDS_PINID='DQ14_A';
NET_NAME
'M_D_CPU1_SA_DQ<15>'
 '@T6G_MB_LIB.T6G(SCH_1):M_D_CPU1_SA_DQ'<15>:
 C_SIGNAL='@t6g_mb_lib.t6g(sch_1):m_d_cpu1_sa_dq(15)';
NODE_NAME     U26 U59
 '@T6G_MB_LIB.T6G(SCH_1):PAGE40_I159@PURE_QUANTA.GENOA_SP5(CHIPS)':
 'MDA_DATA15': CDS_PINID='MDA_DATA15';
NODE_NAME     J30 172
 '@T6G_MB_LIB.T6G(SCH_1):PAGE100_I52@PURE_QUANTA.SCONN288_DDR506112002KQ(CHIPS)':
 'DQ15_A': CDS_PINID='DQ15_A';
NET_NAME
'M_D_CPU1_SA_DQ<16>'
 '@T6G_MB_LIB.T6G(SCH_1):M_D_CPU1_SA_DQ'<16>:
 C_SIGNAL='@t6g_mb_lib.t6g(sch_1):m_d_cpu1_sa_dq(16)';
NODE_NAME     U26 U60
 '@T6G_MB_LIB.T6G(SCH_1):PAGE40_I159@PURE_QUANTA.GENOA_SP5(CHIPS)':
 'MDA_DATA16': CDS_PINID='MDA_DATA16';
NODE_NAME     J30 29
 '@T6G_MB_LIB.T6G(SCH_1):PAGE100_I52@PURE_QUANTA.SCONN288_DDR506112002KQ(CHIPS)':
 'DQ16_A': CDS_PINID='DQ16_A';
NET_NAME
'M_D_CPU1_SA_DQ<17>'
 '@T6G_MB_LIB.T6G(SCH_1):M_D_CPU1_SA_DQ'<17>:
 C_SIGNAL='@t6g_mb_lib.t6g(sch_1):m_d_cpu1_sa_dq(17)';
NODE_NAME     U26 V58
 '@T6G_MB_LIB.T6G(SCH_1):PAGE40_I159@PURE_QUANTA.GENOA_SP5(CHIPS)':
 'MDA_DATA17': CDS_PINID='MDA_DATA17';
NODE_NAME     J30 31
 '@T6G_MB_LIB.T6G(SCH_1):PAGE100_I52@PURE_QUANTA.SCONN288_DDR506112002KQ(CHIPS)':
 'DQ17_A': CDS_PINID='DQ17_A';
NET_NAME
'M_D_CPU1_SA_DQ<18>'
 '@T6G_MB_LIB.T6G(SCH_1):M_D_CPU1_SA_DQ'<18>:
 C_SIGNAL='@t6g_mb_lib.t6g(sch_1):m_d_cpu1_sa_dq(18)';
NODE_NAME     U26 V60
 '@T6G_MB_LIB.T6G(SCH_1):PAGE40_I159@PURE_QUANTA.GENOA_SP5(CHIPS)':
 'MDA_DATA18': CDS_PINID='MDA_DATA18';
NODE_NAME     J30 174
 '@T6G_MB_LIB.T6G(SCH_1):PAGE100_I52@PURE_QUANTA.SCONN288_DDR506112002KQ(CHIPS)':
 'DQ18_A': CDS_PINID='DQ18_A';
NET_NAME
'M_D_CPU1_SA_DQ<19>'
 '@T6G_MB_LIB.T6G(SCH_1):M_D_CPU1_SA_DQ'<19>:
 C_SIGNAL='@t6g_mb_lib.t6g(sch_1):m_d_cpu1_sa_dq(19)';
NODE_NAME     U26 W59
 '@T6G_MB_LIB.T6G(SCH_1):PAGE40_I159@PURE_QUANTA.GENOA_SP5(CHIPS)':
 'MDA_DATA19': CDS_PINID='MDA_DATA19';
NODE_NAME     J30 176
 '@T6G_MB_LIB.T6G(SCH_1):PAGE100_I52@PURE_QUANTA.SCONN288_DDR506112002KQ(CHIPS)':
 'DQ19_A': CDS_PINID='DQ19_A';
NET_NAME
'M_D_CPU1_SA_DQ<1>'
 '@T6G_MB_LIB.T6G(SCH_1):M_D_CPU1_SA_DQ'<1>:
 C_SIGNAL='@t6g_mb_lib.t6g(sch_1):m_d_cpu1_sa_dq(1)';
NODE_NAME     U26 F58
 '@T6G_MB_LIB.T6G(SCH_1):PAGE40_I159@PURE_QUANTA.GENOA_SP5(CHIPS)':
 'MDA_DATA1': CDS_PINID='MDA_DATA1';
NODE_NAME     J30 9
 '@T6G_MB_LIB.T6G(SCH_1):PAGE100_I52@PURE_QUANTA.SCONN288_DDR506112002KQ(CHIPS)':
 'DQ1_A': CDS_PINID='DQ1_A';
NET_NAME
'M_D_CPU1_SA_DQ<20>'
 '@T6G_MB_LIB.T6G(SCH_1):M_D_CPU1_SA_DQ'<20>:
 C_SIGNAL='@t6g_mb_lib.t6g(sch_1):m_d_cpu1_sa_dq(20)';
NODE_NAME     U26 AA60
 '@T6G_MB_LIB.T6G(SCH_1):PAGE40_I159@PURE_QUANTA.GENOA_SP5(CHIPS)':
 'MDA_DATA20': CDS_PINID='MDA_DATA20';
NODE_NAME     J30 36
 '@T6G_MB_LIB.T6G(SCH_1):PAGE100_I52@PURE_QUANTA.SCONN288_DDR506112002KQ(CHIPS)':
 'DQ20_A': CDS_PINID='DQ20_A';
NET_NAME
'M_D_CPU1_SA_DQ<21>'
 '@T6G_MB_LIB.T6G(SCH_1):M_D_CPU1_SA_DQ'<21>:
 C_SIGNAL='@t6g_mb_lib.t6g(sch_1):m_d_cpu1_sa_dq(21)';
NODE_NAME     U26 AB58
 '@T6G_MB_LIB.T6G(SCH_1):PAGE40_I159@PURE_QUANTA.GENOA_SP5(CHIPS)':
 'MDA_DATA21': CDS_PINID='MDA_DATA21';
NODE_NAME     J30 38
 '@T6G_MB_LIB.T6G(SCH_1):PAGE100_I52@PURE_QUANTA.SCONN288_DDR506112002KQ(CHIPS)':
 'DQ21_A': CDS_PINID='DQ21_A';
NET_NAME
'M_D_CPU1_SA_DQ<22>'
 '@T6G_MB_LIB.T6G(SCH_1):M_D_CPU1_SA_DQ'<22>:
 C_SIGNAL='@t6g_mb_lib.t6g(sch_1):m_d_cpu1_sa_dq(22)';
NODE_NAME     U26 AB60
 '@T6G_MB_LIB.T6G(SCH_1):PAGE40_I159@PURE_QUANTA.GENOA_SP5(CHIPS)':
 'MDA_DATA22': CDS_PINID='MDA_DATA22';
NODE_NAME     J30 181
 '@T6G_MB_LIB.T6G(SCH_1):PAGE100_I52@PURE_QUANTA.SCONN288_DDR506112002KQ(CHIPS)':
 'DQ22_A': CDS_PINID='DQ22_A';
NET_NAME
'M_D_CPU1_SA_DQ<23>'
 '@T6G_MB_LIB.T6G(SCH_1):M_D_CPU1_SA_DQ'<23>:
 C_SIGNAL='@t6g_mb_lib.t6g(sch_1):m_d_cpu1_sa_dq(23)';
NODE_NAME     U26 AC59
 '@T6G_MB_LIB.T6G(SCH_1):PAGE40_I159@PURE_QUANTA.GENOA_SP5(CHIPS)':
 'MDA_DATA23': CDS_PINID='MDA_DATA23';
NODE_NAME     J30 183
 '@T6G_MB_LIB.T6G(SCH_1):PAGE100_I52@PURE_QUANTA.SCONN288_DDR506112002KQ(CHIPS)':
 'DQ23_A': CDS_PINID='DQ23_A';
NET_NAME
'M_D_CPU1_SA_DQ<24>'
 '@T6G_MB_LIB.T6G(SCH_1):M_D_CPU1_SA_DQ'<24>:
 C_SIGNAL='@t6g_mb_lib.t6g(sch_1):m_d_cpu1_sa_dq(24)';
NODE_NAME     U26 AC60
 '@T6G_MB_LIB.T6G(SCH_1):PAGE40_I159@PURE_QUANTA.GENOA_SP5(CHIPS)':
 'MDA_DATA24': CDS_PINID='MDA_DATA24';
NODE_NAME     J30 40
 '@T6G_MB_LIB.T6G(SCH_1):PAGE100_I52@PURE_QUANTA.SCONN288_DDR506112002KQ(CHIPS)':
 'DQ24_A': CDS_PINID='DQ24_A';
NET_NAME
'M_D_CPU1_SA_DQ<25>'
 '@T6G_MB_LIB.T6G(SCH_1):M_D_CPU1_SA_DQ'<25>:
 C_SIGNAL='@t6g_mb_lib.t6g(sch_1):m_d_cpu1_sa_dq(25)';
NODE_NAME     U26 AD58
 '@T6G_MB_LIB.T6G(SCH_1):PAGE40_I159@PURE_QUANTA.GENOA_SP5(CHIPS)':
 'MDA_DATA25': CDS_PINID='MDA_DATA25';
NODE_NAME     J30 42
 '@T6G_MB_LIB.T6G(SCH_1):PAGE100_I52@PURE_QUANTA.SCONN288_DDR506112002KQ(CHIPS)':
 'DQ25_A': CDS_PINID='DQ25_A';
NET_NAME
'M_D_CPU1_SA_DQ<26>'
 '@T6G_MB_LIB.T6G(SCH_1):M_D_CPU1_SA_DQ'<26>:
 C_SIGNAL='@t6g_mb_lib.t6g(sch_1):m_d_cpu1_sa_dq(26)';
NODE_NAME     U26 AD60
 '@T6G_MB_LIB.T6G(SCH_1):PAGE40_I159@PURE_QUANTA.GENOA_SP5(CHIPS)':
 'MDA_DATA26': CDS_PINID='MDA_DATA26';
NODE_NAME     J30 185
 '@T6G_MB_LIB.T6G(SCH_1):PAGE100_I52@PURE_QUANTA.SCONN288_DDR506112002KQ(CHIPS)':
 'DQ26_A': CDS_PINID='DQ26_A';
NET_NAME
'M_D_CPU1_SA_DQ<27>'
 '@T6G_MB_LIB.T6G(SCH_1):M_D_CPU1_SA_DQ'<27>:
 C_SIGNAL='@t6g_mb_lib.t6g(sch_1):m_d_cpu1_sa_dq(27)';
NODE_NAME     U26 AE59
 '@T6G_MB_LIB.T6G(SCH_1):PAGE40_I159@PURE_QUANTA.GENOA_SP5(CHIPS)':
 'MDA_DATA27': CDS_PINID='MDA_DATA27';
NODE_NAME     J30 187
 '@T6G_MB_LIB.T6G(SCH_1):PAGE100_I52@PURE_QUANTA.SCONN288_DDR506112002KQ(CHIPS)':
 'DQ27_A': CDS_PINID='DQ27_A';
NET_NAME
'M_D_CPU1_SA_DQ<28>'
 '@T6G_MB_LIB.T6G(SCH_1):M_D_CPU1_SA_DQ'<28>:
 C_SIGNAL='@t6g_mb_lib.t6g(sch_1):m_d_cpu1_sa_dq(28)';
NODE_NAME     U26 AG60
 '@T6G_MB_LIB.T6G(SCH_1):PAGE40_I159@PURE_QUANTA.GENOA_SP5(CHIPS)':
 'MDA_DATA28': CDS_PINID='MDA_DATA28';
NODE_NAME     J30 47
 '@T6G_MB_LIB.T6G(SCH_1):PAGE100_I52@PURE_QUANTA.SCONN288_DDR506112002KQ(CHIPS)':
 'DQ28_A': CDS_PINID='DQ28_A';
NET_NAME
'M_D_CPU1_SA_DQ<29>'
 '@T6G_MB_LIB.T6G(SCH_1):M_D_CPU1_SA_DQ'<29>:
 C_SIGNAL='@t6g_mb_lib.t6g(sch_1):m_d_cpu1_sa_dq(29)';
NODE_NAME     U26 AH58
 '@T6G_MB_LIB.T6G(SCH_1):PAGE40_I159@PURE_QUANTA.GENOA_SP5(CHIPS)':
 'MDA_DATA29': CDS_PINID='MDA_DATA29';
NODE_NAME     J30 49
 '@T6G_MB_LIB.T6G(SCH_1):PAGE100_I52@PURE_QUANTA.SCONN288_DDR506112002KQ(CHIPS)':
 'DQ29_A': CDS_PINID='DQ29_A';
NET_NAME
'M_D_CPU1_SA_DQ<2>'
 '@T6G_MB_LIB.T6G(SCH_1):M_D_CPU1_SA_DQ'<2>:
 C_SIGNAL='@t6g_mb_lib.t6g(sch_1):m_d_cpu1_sa_dq(2)';
NODE_NAME     U26 F60
 '@T6G_MB_LIB.T6G(SCH_1):PAGE40_I159@PURE_QUANTA.GENOA_SP5(CHIPS)':
 'MDA_DATA2': CDS_PINID='MDA_DATA2';
NODE_NAME     J30 152
 '@T6G_MB_LIB.T6G(SCH_1):PAGE100_I52@PURE_QUANTA.SCONN288_DDR506112002KQ(CHIPS)':
 'DQ2_A': CDS_PINID='DQ2_A';
NET_NAME
'M_D_CPU1_SA_DQ<30>'
 '@T6G_MB_LIB.T6G(SCH_1):M_D_CPU1_SA_DQ'<30>:
 C_SIGNAL='@t6g_mb_lib.t6g(sch_1):m_d_cpu1_sa_dq(30)';
NODE_NAME     U26 AH60
 '@T6G_MB_LIB.T6G(SCH_1):PAGE40_I159@PURE_QUANTA.GENOA_SP5(CHIPS)':
 'MDA_DATA30': CDS_PINID='MDA_DATA30';
NODE_NAME     J30 192
 '@T6G_MB_LIB.T6G(SCH_1):PAGE100_I52@PURE_QUANTA.SCONN288_DDR506112002KQ(CHIPS)':
 'DQ30_A': CDS_PINID='DQ30_A';
NET_NAME
'M_D_CPU1_SA_DQ<31>'
 '@T6G_MB_LIB.T6G(SCH_1):M_D_CPU1_SA_DQ'<31>:
 C_SIGNAL='@t6g_mb_lib.t6g(sch_1):m_d_cpu1_sa_dq(31)';
NODE_NAME     U26 AJ59
 '@T6G_MB_LIB.T6G(SCH_1):PAGE40_I159@PURE_QUANTA.GENOA_SP5(CHIPS)':
 'MDA_DATA31': CDS_PINID='MDA_DATA31';
NODE_NAME     J30 194
 '@T6G_MB_LIB.T6G(SCH_1):PAGE100_I52@PURE_QUANTA.SCONN288_DDR506112002KQ(CHIPS)':
 'DQ31_A': CDS_PINID='DQ31_A';
NET_NAME
'M_D_CPU1_SA_DQ<3>'
 '@T6G_MB_LIB.T6G(SCH_1):M_D_CPU1_SA_DQ'<3>:
 C_SIGNAL='@t6g_mb_lib.t6g(sch_1):m_d_cpu1_sa_dq(3)';
NODE_NAME     U26 G59
 '@T6G_MB_LIB.T6G(SCH_1):PAGE40_I159@PURE_QUANTA.GENOA_SP5(CHIPS)':
 'MDA_DATA3': CDS_PINID='MDA_DATA3';
NODE_NAME     J30 154
 '@T6G_MB_LIB.T6G(SCH_1):PAGE100_I52@PURE_QUANTA.SCONN288_DDR506112002KQ(CHIPS)':
 'DQ3_A': CDS_PINID='DQ3_A';
NET_NAME
'M_D_CPU1_SA_DQ<4>'
 '@T6G_MB_LIB.T6G(SCH_1):M_D_CPU1_SA_DQ'<4>:
 C_SIGNAL='@t6g_mb_lib.t6g(sch_1):m_d_cpu1_sa_dq(4)';
NODE_NAME     U26 J60
 '@T6G_MB_LIB.T6G(SCH_1):PAGE40_I159@PURE_QUANTA.GENOA_SP5(CHIPS)':
 'MDA_DATA4': CDS_PINID='MDA_DATA4';
NODE_NAME     J30 14
 '@T6G_MB_LIB.T6G(SCH_1):PAGE100_I52@PURE_QUANTA.SCONN288_DDR506112002KQ(CHIPS)':
 'DQ4_A': CDS_PINID='DQ4_A';
NET_NAME
'M_D_CPU1_SA_DQ<5>'
 '@T6G_MB_LIB.T6G(SCH_1):M_D_CPU1_SA_DQ'<5>:
 C_SIGNAL='@t6g_mb_lib.t6g(sch_1):m_d_cpu1_sa_dq(5)';
NODE_NAME     U26 K58
 '@T6G_MB_LIB.T6G(SCH_1):PAGE40_I159@PURE_QUANTA.GENOA_SP5(CHIPS)':
 'MDA_DATA5': CDS_PINID='MDA_DATA5';
NODE_NAME     J30 16
 '@T6G_MB_LIB.T6G(SCH_1):PAGE100_I52@PURE_QUANTA.SCONN288_DDR506112002KQ(CHIPS)':
 'DQ5_A': CDS_PINID='DQ5_A';
NET_NAME
'M_D_CPU1_SA_DQ<6>'
 '@T6G_MB_LIB.T6G(SCH_1):M_D_CPU1_SA_DQ'<6>:
 C_SIGNAL='@t6g_mb_lib.t6g(sch_1):m_d_cpu1_sa_dq(6)';
NODE_NAME     U26 K60
 '@T6G_MB_LIB.T6G(SCH_1):PAGE40_I159@PURE_QUANTA.GENOA_SP5(CHIPS)':
 'MDA_DATA6': CDS_PINID='MDA_DATA6';
NODE_NAME     J30 159
 '@T6G_MB_LIB.T6G(SCH_1):PAGE100_I52@PURE_QUANTA.SCONN288_DDR506112002KQ(CHIPS)':
 'DQ6_A': CDS_PINID='DQ6_A';
NET_NAME
'M_D_CPU1_SA_DQ<7>'
 '@T6G_MB_LIB.T6G(SCH_1):M_D_CPU1_SA_DQ'<7>:
 C_SIGNAL='@t6g_mb_lib.t6g(sch_1):m_d_cpu1_sa_dq(7)';
NODE_NAME     U26 L59
 '@T6G_MB_LIB.T6G(SCH_1):PAGE40_I159@PURE_QUANTA.GENOA_SP5(CHIPS)':
 'MDA_DATA7': CDS_PINID='MDA_DATA7';
NODE_NAME     J30 161
 '@T6G_MB_LIB.T6G(SCH_1):PAGE100_I52@PURE_QUANTA.SCONN288_DDR506112002KQ(CHIPS)':
 'DQ7_A': CDS_PINID='DQ7_A';
NET_NAME
'M_D_CPU1_SA_DQ<8>'
 '@T6G_MB_LIB.T6G(SCH_1):M_D_CPU1_SA_DQ'<8>:
 C_SIGNAL='@t6g_mb_lib.t6g(sch_1):m_d_cpu1_sa_dq(8)';
NODE_NAME     U26 L60
 '@T6G_MB_LIB.T6G(SCH_1):PAGE40_I159@PURE_QUANTA.GENOA_SP5(CHIPS)':
 'MDA_DATA8': CDS_PINID='MDA_DATA8';
NODE_NAME     J30 18
 '@T6G_MB_LIB.T6G(SCH_1):PAGE100_I52@PURE_QUANTA.SCONN288_DDR506112002KQ(CHIPS)':
 'DQ8_A': CDS_PINID='DQ8_A';
NET_NAME
'M_D_CPU1_SA_DQ<9>'
 '@T6G_MB_LIB.T6G(SCH_1):M_D_CPU1_SA_DQ'<9>:
 C_SIGNAL='@t6g_mb_lib.t6g(sch_1):m_d_cpu1_sa_dq(9)';
NODE_NAME     U26 M58
 '@T6G_MB_LIB.T6G(SCH_1):PAGE40_I159@PURE_QUANTA.GENOA_SP5(CHIPS)':
 'MDA_DATA9': CDS_PINID='MDA_DATA9';
NODE_NAME     J30 20
 '@T6G_MB_LIB.T6G(SCH_1):PAGE100_I52@PURE_QUANTA.SCONN288_DDR506112002KQ(CHIPS)':
 'DQ9_A': CDS_PINID='DQ9_A';
NET_NAME
'M_D_CPU1_SA_DQS_DN<0>'
 '@T6G_MB_LIB.T6G(SCH_1):M_D_CPU1_SA_DQS_DN'<0>:
 C_SIGNAL='@t6g_mb_lib.t6g(sch_1):m_d_cpu1_sa_dqs_dn(0)';
NODE_NAME     U26 H60
 '@T6G_MB_LIB.T6G(SCH_1):PAGE40_I159@PURE_QUANTA.GENOA_SP5(CHIPS)':
 'MDA_DQS_L0': CDS_PINID='MDA_DQS_L0';
NODE_NAME     J30 12
 '@T6G_MB_LIB.T6G(SCH_1):PAGE100_I236@PURE_QUANTA.SCONN288_DDR506112002KQ(CHIPS)':
 'DQS0_A_C': CDS_PINID='DQS0_A_C';
NET_NAME
'M_D_CPU1_SA_DQS_DN<1>'
 '@T6G_MB_LIB.T6G(SCH_1):M_D_CPU1_SA_DQS_DN'<1>:
 C_SIGNAL='@t6g_mb_lib.t6g(sch_1):m_d_cpu1_sa_dqs_dn(1)';
NODE_NAME     U26 P60
 '@T6G_MB_LIB.T6G(SCH_1):PAGE40_I159@PURE_QUANTA.GENOA_SP5(CHIPS)':
 'MDA_DQS_L1': CDS_PINID='MDA_DQS_L1';
NODE_NAME     J30 23
 '@T6G_MB_LIB.T6G(SCH_1):PAGE100_I236@PURE_QUANTA.SCONN288_DDR506112002KQ(CHIPS)':
 'DQS1_A_C': CDS_PINID='DQS1_A_C';
NET_NAME
'M_D_CPU1_SA_DQS_DN<2>'
 '@T6G_MB_LIB.T6G(SCH_1):M_D_CPU1_SA_DQS_DN'<2>:
 C_SIGNAL='@t6g_mb_lib.t6g(sch_1):m_d_cpu1_sa_dqs_dn(2)';
NODE_NAME     U26 Y60
 '@T6G_MB_LIB.T6G(SCH_1):PAGE40_I159@PURE_QUANTA.GENOA_SP5(CHIPS)':
 'MDA_DQS_L2': CDS_PINID='MDA_DQS_L2';
NODE_NAME     J30 34
 '@T6G_MB_LIB.T6G(SCH_1):PAGE100_I236@PURE_QUANTA.SCONN288_DDR506112002KQ(CHIPS)':
 'DQS2_A_C': CDS_PINID='DQS2_A_C';
NET_NAME
'M_D_CPU1_SA_DQS_DN<3>'
 '@T6G_MB_LIB.T6G(SCH_1):M_D_CPU1_SA_DQS_DN'<3>:
 C_SIGNAL='@t6g_mb_lib.t6g(sch_1):m_d_cpu1_sa_dqs_dn(3)';
NODE_NAME     U26 AF60
 '@T6G_MB_LIB.T6G(SCH_1):PAGE40_I159@PURE_QUANTA.GENOA_SP5(CHIPS)':
 'MDA_DQS_L3': CDS_PINID='MDA_DQS_L3';
NODE_NAME     J30 45
 '@T6G_MB_LIB.T6G(SCH_1):PAGE100_I236@PURE_QUANTA.SCONN288_DDR506112002KQ(CHIPS)':
 'DQS3_A_C': CDS_PINID='DQS3_A_C';
NET_NAME
'M_D_CPU1_SA_DQS_DN<4>'
 '@T6G_MB_LIB.T6G(SCH_1):M_D_CPU1_SA_DQS_DN'<4>:
 C_SIGNAL='@t6g_mb_lib.t6g(sch_1):m_d_cpu1_sa_dqs_dn(4)';
NODE_NAME     U26 AM60
 '@T6G_MB_LIB.T6G(SCH_1):PAGE40_I159@PURE_QUANTA.GENOA_SP5(CHIPS)':
 'MDA_DQS_L4': CDS_PINID='MDA_DQS_L4';
NODE_NAME     J30 56
 '@T6G_MB_LIB.T6G(SCH_1):PAGE100_I236@PURE_QUANTA.SCONN288_DDR506112002KQ(CHIPS)':
 'DQS4_A_C': CDS_PINID='DQS4_A_C';
NET_NAME
'M_D_CPU1_SA_DQS_DN<5>'
 '@T6G_MB_LIB.T6G(SCH_1):M_D_CPU1_SA_DQS_DN'<5>:
 C_SIGNAL='@t6g_mb_lib.t6g(sch_1):m_d_cpu1_sa_dqs_dn(5)';
NODE_NAME     U26 H58
 '@T6G_MB_LIB.T6G(SCH_1):PAGE40_I159@PURE_QUANTA.GENOA_SP5(CHIPS)':
 'MDA_DQS_L5': CDS_PINID='MDA_DQS_L5';
NODE_NAME     J30 156
 '@T6G_MB_LIB.T6G(SCH_1):PAGE100_I236@PURE_QUANTA.SCONN288_DDR506112002KQ(CHIPS)':
 'DQS5_A_C||TDQS5_A_C||DQS5_A_T||TDQS5_A_T': CDS_PINID='\dqs5_a_c||tdqs5_a_c||dqs5_a_t||tdqs5_a_t\';
NET_NAME
'M_D_CPU1_SA_DQS_DN<6>'
 '@T6G_MB_LIB.T6G(SCH_1):M_D_CPU1_SA_DQS_DN'<6>:
 C_SIGNAL='@t6g_mb_lib.t6g(sch_1):m_d_cpu1_sa_dqs_dn(6)';
NODE_NAME     U26 P58
 '@T6G_MB_LIB.T6G(SCH_1):PAGE40_I159@PURE_QUANTA.GENOA_SP5(CHIPS)':
 'MDA_DQS_L6': CDS_PINID='MDA_DQS_L6';
NODE_NAME     J30 167
 '@T6G_MB_LIB.T6G(SCH_1):PAGE100_I236@PURE_QUANTA.SCONN288_DDR506112002KQ(CHIPS)':
 'DQS6_A_C||TDQS6_A_C||DQS6_A_T||TDQS6_A_T': CDS_PINID='\dqs6_a_c||tdqs6_a_c||dqs6_a_t||tdqs6_a_t\';
NET_NAME
'M_D_CPU1_SA_DQS_DN<7>'
 '@T6G_MB_LIB.T6G(SCH_1):M_D_CPU1_SA_DQS_DN'<7>:
 C_SIGNAL='@t6g_mb_lib.t6g(sch_1):m_d_cpu1_sa_dqs_dn(7)';
NODE_NAME     U26 Y58
 '@T6G_MB_LIB.T6G(SCH_1):PAGE40_I159@PURE_QUANTA.GENOA_SP5(CHIPS)':
 'MDA_DQS_L7': CDS_PINID='MDA_DQS_L7';
NODE_NAME     J30 178
 '@T6G_MB_LIB.T6G(SCH_1):PAGE100_I236@PURE_QUANTA.SCONN288_DDR506112002KQ(CHIPS)':
 'DQS7_A_C||TDQS7_A_C': CDS_PINID='\dqs7_a_c||tdqs7_a_c\';
NET_NAME
'M_D_CPU1_SA_DQS_DN<8>'
 '@T6G_MB_LIB.T6G(SCH_1):M_D_CPU1_SA_DQS_DN'<8>:
 C_SIGNAL='@t6g_mb_lib.t6g(sch_1):m_d_cpu1_sa_dqs_dn(8)';
NODE_NAME     U26 AF58
 '@T6G_MB_LIB.T6G(SCH_1):PAGE40_I159@PURE_QUANTA.GENOA_SP5(CHIPS)':
 'MDA_DQS_L8': CDS_PINID='MDA_DQS_L8';
NODE_NAME     J30 189
 '@T6G_MB_LIB.T6G(SCH_1):PAGE100_I236@PURE_QUANTA.SCONN288_DDR506112002KQ(CHIPS)':
 'DQS8_A_C||TDQS8_A_C': CDS_PINID='\dqs8_a_c||tdqs8_a_c\';
NET_NAME
'M_D_CPU1_SA_DQS_DN<9>'
 '@T6G_MB_LIB.T6G(SCH_1):M_D_CPU1_SA_DQS_DN'<9>:
 C_SIGNAL='@t6g_mb_lib.t6g(sch_1):m_d_cpu1_sa_dqs_dn(9)';
NODE_NAME     U26 AM58
 '@T6G_MB_LIB.T6G(SCH_1):PAGE40_I159@PURE_QUANTA.GENOA_SP5(CHIPS)':
 'MDA_DQS_L9': CDS_PINID='MDA_DQS_L9';
NODE_NAME     J30 200
 '@T6G_MB_LIB.T6G(SCH_1):PAGE100_I236@PURE_QUANTA.SCONN288_DDR506112002KQ(CHIPS)':
 'DQS9_A_C||TDQS9_A_C': CDS_PINID='\dqs9_a_c||tdqs9_a_c\';
NET_NAME
'M_D_CPU1_SA_DQS_DP<0>'
 '@T6G_MB_LIB.T6G(SCH_1):M_D_CPU1_SA_DQS_DP'<0>:
 C_SIGNAL='@t6g_mb_lib.t6g(sch_1):m_d_cpu1_sa_dqs_dp(0)';
NODE_NAME     U26 G60
 '@T6G_MB_LIB.T6G(SCH_1):PAGE40_I159@PURE_QUANTA.GENOA_SP5(CHIPS)':
 'MDA_DQS_H0': CDS_PINID='MDA_DQS_H0';
NODE_NAME     J30 11
 '@T6G_MB_LIB.T6G(SCH_1):PAGE100_I236@PURE_QUANTA.SCONN288_DDR506112002KQ(CHIPS)':
 'DQS0_A_T': CDS_PINID='DQS0_A_T';
NET_NAME
'M_D_CPU1_SA_DQS_DP<1>'
 '@T6G_MB_LIB.T6G(SCH_1):M_D_CPU1_SA_DQS_DP'<1>:
 C_SIGNAL='@t6g_mb_lib.t6g(sch_1):m_d_cpu1_sa_dqs_dp(1)';
NODE_NAME     U26 N60
 '@T6G_MB_LIB.T6G(SCH_1):PAGE40_I159@PURE_QUANTA.GENOA_SP5(CHIPS)':
 'MDA_DQS_H1': CDS_PINID='MDA_DQS_H1';
NODE_NAME     J30 22
 '@T6G_MB_LIB.T6G(SCH_1):PAGE100_I236@PURE_QUANTA.SCONN288_DDR506112002KQ(CHIPS)':
 'DQS1_A_T': CDS_PINID='DQS1_A_T';
NET_NAME
'M_D_CPU1_SA_DQS_DP<2>'
 '@T6G_MB_LIB.T6G(SCH_1):M_D_CPU1_SA_DQS_DP'<2>:
 C_SIGNAL='@t6g_mb_lib.t6g(sch_1):m_d_cpu1_sa_dqs_dp(2)';
NODE_NAME     U26 W60
 '@T6G_MB_LIB.T6G(SCH_1):PAGE40_I159@PURE_QUANTA.GENOA_SP5(CHIPS)':
 'MDA_DQS_H2': CDS_PINID='MDA_DQS_H2';
NODE_NAME     J30 33
 '@T6G_MB_LIB.T6G(SCH_1):PAGE100_I236@PURE_QUANTA.SCONN288_DDR506112002KQ(CHIPS)':
 'DQS2_A_T': CDS_PINID='DQS2_A_T';
NET_NAME
'M_D_CPU1_SA_DQS_DP<3>'
 '@T6G_MB_LIB.T6G(SCH_1):M_D_CPU1_SA_DQS_DP'<3>:
 C_SIGNAL='@t6g_mb_lib.t6g(sch_1):m_d_cpu1_sa_dqs_dp(3)';
NODE_NAME     U26 AE60
 '@T6G_MB_LIB.T6G(SCH_1):PAGE40_I159@PURE_QUANTA.GENOA_SP5(CHIPS)':
 'MDA_DQS_H3': CDS_PINID='MDA_DQS_H3';
NODE_NAME     J30 44
 '@T6G_MB_LIB.T6G(SCH_1):PAGE100_I236@PURE_QUANTA.SCONN288_DDR506112002KQ(CHIPS)':
 'DQS3_A_T': CDS_PINID='DQS3_A_T';
NET_NAME
'M_D_CPU1_SA_DQS_DP<4>'
 '@T6G_MB_LIB.T6G(SCH_1):M_D_CPU1_SA_DQS_DP'<4>:
 C_SIGNAL='@t6g_mb_lib.t6g(sch_1):m_d_cpu1_sa_dqs_dp(4)';
NODE_NAME     U26 AL60
 '@T6G_MB_LIB.T6G(SCH_1):PAGE40_I159@PURE_QUANTA.GENOA_SP5(CHIPS)':
 'MDA_DQS_H4': CDS_PINID='MDA_DQS_H4';
NODE_NAME     J30 55
 '@T6G_MB_LIB.T6G(SCH_1):PAGE100_I236@PURE_QUANTA.SCONN288_DDR506112002KQ(CHIPS)':
 'DQS4_A_T': CDS_PINID='DQS4_A_T';
NET_NAME
'M_D_CPU1_SA_DQS_DP<5>'
 '@T6G_MB_LIB.T6G(SCH_1):M_D_CPU1_SA_DQS_DP'<5>:
 C_SIGNAL='@t6g_mb_lib.t6g(sch_1):m_d_cpu1_sa_dqs_dp(5)';
NODE_NAME     U26 J59
 '@T6G_MB_LIB.T6G(SCH_1):PAGE40_I159@PURE_QUANTA.GENOA_SP5(CHIPS)':
 'MDA_DQS_H5': CDS_PINID='MDA_DQS_H5';
NODE_NAME     J30 157
 '@T6G_MB_LIB.T6G(SCH_1):PAGE100_I236@PURE_QUANTA.SCONN288_DDR506112002KQ(CHIPS)':
 'DQS5_A_T||TDQS5_A_T': CDS_PINID='\dqs5_a_t||tdqs5_a_t\';
NET_NAME
'M_D_CPU1_SA_DQS_DP<6>'
 '@T6G_MB_LIB.T6G(SCH_1):M_D_CPU1_SA_DQS_DP'<6>:
 C_SIGNAL='@t6g_mb_lib.t6g(sch_1):m_d_cpu1_sa_dqs_dp(6)';
NODE_NAME     U26 R59
 '@T6G_MB_LIB.T6G(SCH_1):PAGE40_I159@PURE_QUANTA.GENOA_SP5(CHIPS)':
 'MDA_DQS_H6': CDS_PINID='MDA_DQS_H6';
NODE_NAME     J30 168
 '@T6G_MB_LIB.T6G(SCH_1):PAGE100_I236@PURE_QUANTA.SCONN288_DDR506112002KQ(CHIPS)':
 'DQS6_A_T||TDQS6_A_T': CDS_PINID='\dqs6_a_t||tdqs6_a_t\';
NET_NAME
'M_D_CPU1_SA_DQS_DP<7>'
 '@T6G_MB_LIB.T6G(SCH_1):M_D_CPU1_SA_DQS_DP'<7>:
 C_SIGNAL='@t6g_mb_lib.t6g(sch_1):m_d_cpu1_sa_dqs_dp(7)';
NODE_NAME     U26 AA59
 '@T6G_MB_LIB.T6G(SCH_1):PAGE40_I159@PURE_QUANTA.GENOA_SP5(CHIPS)':
 'MDA_DQS_H7': CDS_PINID='MDA_DQS_H7';
NODE_NAME     J30 179
 '@T6G_MB_LIB.T6G(SCH_1):PAGE100_I236@PURE_QUANTA.SCONN288_DDR506112002KQ(CHIPS)':
 'DQS7_A_T||TDQS7_A_T': CDS_PINID='\dqs7_a_t||tdqs7_a_t\';
NET_NAME
'M_D_CPU1_SA_DQS_DP<8>'
 '@T6G_MB_LIB.T6G(SCH_1):M_D_CPU1_SA_DQS_DP'<8>:
 C_SIGNAL='@t6g_mb_lib.t6g(sch_1):m_d_cpu1_sa_dqs_dp(8)';
NODE_NAME     U26 AG59
 '@T6G_MB_LIB.T6G(SCH_1):PAGE40_I159@PURE_QUANTA.GENOA_SP5(CHIPS)':
 'MDA_DQS_H8': CDS_PINID='MDA_DQS_H8';
NODE_NAME     J30 190
 '@T6G_MB_LIB.T6G(SCH_1):PAGE100_I236@PURE_QUANTA.SCONN288_DDR506112002KQ(CHIPS)':
 'DQS8_A_T||TDQS8_A_T': CDS_PINID='\dqs8_a_t||tdqs8_a_t\';
NET_NAME
'M_D_CPU1_SA_DQS_DP<9>'
 '@T6G_MB_LIB.T6G(SCH_1):M_D_CPU1_SA_DQS_DP'<9>:
 C_SIGNAL='@t6g_mb_lib.t6g(sch_1):m_d_cpu1_sa_dqs_dp(9)';
NODE_NAME     U26 AN59
 '@T6G_MB_LIB.T6G(SCH_1):PAGE40_I159@PURE_QUANTA.GENOA_SP5(CHIPS)':
 'MDA_DQS_H9': CDS_PINID='MDA_DQS_H9';
NODE_NAME     J30 201
 '@T6G_MB_LIB.T6G(SCH_1):PAGE100_I236@PURE_QUANTA.SCONN288_DDR506112002KQ(CHIPS)':
 'DQS9_A_T||TDQS9_A_T': CDS_PINID='\dqs9_a_t||tdqs9_a_t\';
NET_NAME
'M_D_CPU1_SA_PAR'
 '@T6G_MB_LIB.T6G(SCH_1):M_D_CPU1_SA_PAR':
 C_SIGNAL='@t6g_mb_lib.t6g(sch_1):m_d_cpu1_sa_par';
NODE_NAME     U26 BC59
 '@T6G_MB_LIB.T6G(SCH_1):PAGE40_I159@PURE_QUANTA.GENOA_SP5(CHIPS)':
 'MDA_PAR': CDS_PINID='MDA_PAR';
NODE_NAME     J30 74
 '@T6G_MB_LIB.T6G(SCH_1):PAGE100_I52@PURE_QUANTA.SCONN288_DDR506112002KQ(CHIPS)':
 'PAR_A': CDS_PINID='PAR_A';
NET_NAME
'M_D_CPU1_SA_RSP<0>'
 '@T6G_MB_LIB.T6G(SCH_1):M_D_CPU1_SA_RSP'<0>:
 C_SIGNAL='@t6g_mb_lib.t6g(sch_1):m_d_cpu1_sa_rsp(0)';
NODE_NAME     U26 BN59
 '@T6G_MB_LIB.T6G(SCH_1):PAGE40_I159@PURE_QUANTA.GENOA_SP5(CHIPS)':
 'MDA0_RSP_L': CDS_PINID='MDA0_RSP_L';
NODE_NAME     J30 86
 '@T6G_MB_LIB.T6G(SCH_1):PAGE100_I52@PURE_QUANTA.SCONN288_DDR506112002KQ(CHIPS)':
 'LBD||RSP_A_N': CDS_PINID='\lbd||rsp_a_n\';
NET_NAME
'M_D_CPU1_SB_CA<0>'
 '@T6G_MB_LIB.T6G(SCH_1):M_D_CPU1_SB_CA'<0>:
 C_SIGNAL='@t6g_mb_lib.t6g(sch_1):m_d_cpu1_sb_ca(0)';
NODE_NAME     U26 BG59
 '@T6G_MB_LIB.T6G(SCH_1):PAGE40_I159@PURE_QUANTA.GENOA_SP5(CHIPS)':
 'MDB_CA0': CDS_PINID='MDB_CA0';
NODE_NAME     J30 76
 '@T6G_MB_LIB.T6G(SCH_1):PAGE100_I52@PURE_QUANTA.SCONN288_DDR506112002KQ(CHIPS)':
 'CA0_B': CDS_PINID='CA0_B';
NET_NAME
'M_D_CPU1_SB_CA<1>'
 '@T6G_MB_LIB.T6G(SCH_1):M_D_CPU1_SB_CA'<1>:
 C_SIGNAL='@t6g_mb_lib.t6g(sch_1):m_d_cpu1_sb_ca(1)';
NODE_NAME     U26 BH58
 '@T6G_MB_LIB.T6G(SCH_1):PAGE40_I159@PURE_QUANTA.GENOA_SP5(CHIPS)':
 'MDB_CA1': CDS_PINID='MDB_CA1';
NODE_NAME     J30 221
 '@T6G_MB_LIB.T6G(SCH_1):PAGE100_I52@PURE_QUANTA.SCONN288_DDR506112002KQ(CHIPS)':
 'CA1_B': CDS_PINID='CA1_B';
NET_NAME
'M_D_CPU1_SB_CA<2>'
 '@T6G_MB_LIB.T6G(SCH_1):M_D_CPU1_SB_CA'<2>:
 C_SIGNAL='@t6g_mb_lib.t6g(sch_1):m_d_cpu1_sb_ca(2)';
NODE_NAME     U26 BH60
 '@T6G_MB_LIB.T6G(SCH_1):PAGE40_I159@PURE_QUANTA.GENOA_SP5(CHIPS)':
 'MDB_CA2': CDS_PINID='MDB_CA2';
NODE_NAME     J30 78
 '@T6G_MB_LIB.T6G(SCH_1):PAGE100_I52@PURE_QUANTA.SCONN288_DDR506112002KQ(CHIPS)':
 'CA2_B': CDS_PINID='CA2_B';
NET_NAME
'M_D_CPU1_SB_CA<3>'
 '@T6G_MB_LIB.T6G(SCH_1):M_D_CPU1_SB_CA'<3>:
 C_SIGNAL='@t6g_mb_lib.t6g(sch_1):m_d_cpu1_sb_ca(3)';
NODE_NAME     U26 BJ60
 '@T6G_MB_LIB.T6G(SCH_1):PAGE40_I159@PURE_QUANTA.GENOA_SP5(CHIPS)':
 'MDB_CA3': CDS_PINID='MDB_CA3';
NODE_NAME     J30 223
 '@T6G_MB_LIB.T6G(SCH_1):PAGE100_I52@PURE_QUANTA.SCONN288_DDR506112002KQ(CHIPS)':
 'CA3_B': CDS_PINID='CA3_B';
NET_NAME
'M_D_CPU1_SB_CA<4>'
 '@T6G_MB_LIB.T6G(SCH_1):M_D_CPU1_SB_CA'<4>:
 C_SIGNAL='@t6g_mb_lib.t6g(sch_1):m_d_cpu1_sb_ca(4)';
NODE_NAME     U26 BJ59
 '@T6G_MB_LIB.T6G(SCH_1):PAGE40_I159@PURE_QUANTA.GENOA_SP5(CHIPS)':
 'MDB_CA4': CDS_PINID='MDB_CA4';
NODE_NAME     J30 80
 '@T6G_MB_LIB.T6G(SCH_1):PAGE100_I52@PURE_QUANTA.SCONN288_DDR506112002KQ(CHIPS)':
 'CA4_B': CDS_PINID='CA4_B';
NET_NAME
'M_D_CPU1_SB_CA<5>'
 '@T6G_MB_LIB.T6G(SCH_1):M_D_CPU1_SB_CA'<5>:
 C_SIGNAL='@t6g_mb_lib.t6g(sch_1):m_d_cpu1_sb_ca(5)';
NODE_NAME     U26 BK58
 '@T6G_MB_LIB.T6G(SCH_1):PAGE40_I159@PURE_QUANTA.GENOA_SP5(CHIPS)':
 'MDB_CA5': CDS_PINID='MDB_CA5';
NODE_NAME     J30 225
 '@T6G_MB_LIB.T6G(SCH_1):PAGE100_I52@PURE_QUANTA.SCONN288_DDR506112002KQ(CHIPS)':
 'CA5_B': CDS_PINID='CA5_B';
NET_NAME
'M_D_CPU1_SB_CA<6>'
 '@T6G_MB_LIB.T6G(SCH_1):M_D_CPU1_SB_CA'<6>:
 C_SIGNAL='@t6g_mb_lib.t6g(sch_1):m_d_cpu1_sb_ca(6)';
NODE_NAME     U26 BK60
 '@T6G_MB_LIB.T6G(SCH_1):PAGE40_I159@PURE_QUANTA.GENOA_SP5(CHIPS)':
 'MDB_CA6': CDS_PINID='MDB_CA6';
NODE_NAME     J30 82
 '@T6G_MB_LIB.T6G(SCH_1):PAGE100_I52@PURE_QUANTA.SCONN288_DDR506112002KQ(CHIPS)':
 'CA6_B': CDS_PINID='CA6_B';
NET_NAME
'M_D_CPU1_SB_CB<0>'
 '@T6G_MB_LIB.T6G(SCH_1):M_D_CPU1_SB_CB'<0>:
 C_SIGNAL='@t6g_mb_lib.t6g(sch_1):m_d_cpu1_sb_cb(0)';
NODE_NAME     U26 BY60
 '@T6G_MB_LIB.T6G(SCH_1):PAGE40_I159@PURE_QUANTA.GENOA_SP5(CHIPS)':
 'MDB_CHECK0': CDS_PINID='MDB_CHECK0';
NODE_NAME     J30 96
 '@T6G_MB_LIB.T6G(SCH_1):PAGE100_I52@PURE_QUANTA.SCONN288_DDR506112002KQ(CHIPS)':
 'CB0_B': CDS_PINID='CB0_B';
NET_NAME
'M_D_CPU1_SB_CB<1>'
 '@T6G_MB_LIB.T6G(SCH_1):M_D_CPU1_SB_CB'<1>:
 C_SIGNAL='@t6g_mb_lib.t6g(sch_1):m_d_cpu1_sb_cb(1)';
NODE_NAME     U26 CA59
 '@T6G_MB_LIB.T6G(SCH_1):PAGE40_I159@PURE_QUANTA.GENOA_SP5(CHIPS)':
 'MDB_CHECK1': CDS_PINID='MDB_CHECK1';
NODE_NAME     J30 98
 '@T6G_MB_LIB.T6G(SCH_1):PAGE100_I52@PURE_QUANTA.SCONN288_DDR506112002KQ(CHIPS)':
 'CB1_B': CDS_PINID='CB1_B';
NET_NAME
'M_D_CPU1_SB_CB<2>'
 '@T6G_MB_LIB.T6G(SCH_1):M_D_CPU1_SB_CB'<2>:
 C_SIGNAL='@t6g_mb_lib.t6g(sch_1):m_d_cpu1_sb_cb(2)';
NODE_NAME     U26 CA60
 '@T6G_MB_LIB.T6G(SCH_1):PAGE40_I159@PURE_QUANTA.GENOA_SP5(CHIPS)':
 'MDB_CHECK2': CDS_PINID='MDB_CHECK2';
NODE_NAME     J30 241
 '@T6G_MB_LIB.T6G(SCH_1):PAGE100_I52@PURE_QUANTA.SCONN288_DDR506112002KQ(CHIPS)':
 'CB2_B': CDS_PINID='CB2_B';
NET_NAME
'M_D_CPU1_SB_CB<3>'
 '@T6G_MB_LIB.T6G(SCH_1):M_D_CPU1_SB_CB'<3>:
 C_SIGNAL='@t6g_mb_lib.t6g(sch_1):m_d_cpu1_sb_cb(3)';
NODE_NAME     U26 CB58
 '@T6G_MB_LIB.T6G(SCH_1):PAGE40_I159@PURE_QUANTA.GENOA_SP5(CHIPS)':
 'MDB_CHECK3': CDS_PINID='MDB_CHECK3';
NODE_NAME     J30 243
 '@T6G_MB_LIB.T6G(SCH_1):PAGE100_I52@PURE_QUANTA.SCONN288_DDR506112002KQ(CHIPS)':
 'CB3_B': CDS_PINID='CB3_B';
NET_NAME
'M_D_CPU1_SB_CB<4>'
 '@T6G_MB_LIB.T6G(SCH_1):M_D_CPU1_SB_CB'<4>:
 C_SIGNAL='@t6g_mb_lib.t6g(sch_1):m_d_cpu1_sb_cb(4)';
NODE_NAME     U26 BT60
 '@T6G_MB_LIB.T6G(SCH_1):PAGE40_I159@PURE_QUANTA.GENOA_SP5(CHIPS)':
 'MDB_CHECK4': CDS_PINID='MDB_CHECK4';
NODE_NAME     J30 89
 '@T6G_MB_LIB.T6G(SCH_1):PAGE100_I52@PURE_QUANTA.SCONN288_DDR506112002KQ(CHIPS)':
 'CB4_B': CDS_PINID='CB4_B';
NET_NAME
'M_D_CPU1_SB_CB<5>'
 '@T6G_MB_LIB.T6G(SCH_1):M_D_CPU1_SB_CB'<5>:
 C_SIGNAL='@t6g_mb_lib.t6g(sch_1):m_d_cpu1_sb_cb(5)';
NODE_NAME     U26 BU59
 '@T6G_MB_LIB.T6G(SCH_1):PAGE40_I159@PURE_QUANTA.GENOA_SP5(CHIPS)':
 'MDB_CHECK5': CDS_PINID='MDB_CHECK5';
NODE_NAME     J30 91
 '@T6G_MB_LIB.T6G(SCH_1):PAGE100_I52@PURE_QUANTA.SCONN288_DDR506112002KQ(CHIPS)':
 'CB5_B': CDS_PINID='CB5_B';
NET_NAME
'M_D_CPU1_SB_CB<6>'
 '@T6G_MB_LIB.T6G(SCH_1):M_D_CPU1_SB_CB'<6>:
 C_SIGNAL='@t6g_mb_lib.t6g(sch_1):m_d_cpu1_sb_cb(6)';
NODE_NAME     U26 BU60
 '@T6G_MB_LIB.T6G(SCH_1):PAGE40_I159@PURE_QUANTA.GENOA_SP5(CHIPS)':
 'MDB_CHECK6': CDS_PINID='MDB_CHECK6';
NODE_NAME     J30 234
 '@T6G_MB_LIB.T6G(SCH_1):PAGE100_I52@PURE_QUANTA.SCONN288_DDR506112002KQ(CHIPS)':
 'CB6_B': CDS_PINID='CB6_B';
NET_NAME
'M_D_CPU1_SB_CB<7>'
 '@T6G_MB_LIB.T6G(SCH_1):M_D_CPU1_SB_CB'<7>:
 C_SIGNAL='@t6g_mb_lib.t6g(sch_1):m_d_cpu1_sb_cb(7)';
NODE_NAME     U26 BV58
 '@T6G_MB_LIB.T6G(SCH_1):PAGE40_I159@PURE_QUANTA.GENOA_SP5(CHIPS)':
 'MDB_CHECK7': CDS_PINID='MDB_CHECK7';
NODE_NAME     J30 236
 '@T6G_MB_LIB.T6G(SCH_1):PAGE100_I52@PURE_QUANTA.SCONN288_DDR506112002KQ(CHIPS)':
 'CB7_B': CDS_PINID='CB7_B';
NET_NAME
'M_D_CPU1_SB_CS_N<0>'
 '@T6G_MB_LIB.T6G(SCH_1):M_D_CPU1_SB_CS_N'<0>:
 C_SIGNAL='@t6g_mb_lib.t6g(sch_1):m_d_cpu1_sb_cs_n(0)';
NODE_NAME     U26 BM58
 '@T6G_MB_LIB.T6G(SCH_1):PAGE40_I159@PURE_QUANTA.GENOA_SP5(CHIPS)':
 'MDB0_CS_L0': CDS_PINID='MDB0_CS_L0';
NODE_NAME     J30 84
 '@T6G_MB_LIB.T6G(SCH_1):PAGE100_I52@PURE_QUANTA.SCONN288_DDR506112002KQ(CHIPS)':
 'CS0_B_N': CDS_PINID='CS0_B_N';
NET_NAME
'M_D_CPU1_SB_CS_N<1>'
 '@T6G_MB_LIB.T6G(SCH_1):M_D_CPU1_SB_CS_N'<1>:
 C_SIGNAL='@t6g_mb_lib.t6g(sch_1):m_d_cpu1_sb_cs_n(1)';
NODE_NAME     U26 BN60
 '@T6G_MB_LIB.T6G(SCH_1):PAGE40_I159@PURE_QUANTA.GENOA_SP5(CHIPS)':
 'MDB0_CS_L1': CDS_PINID='MDB0_CS_L1';
NODE_NAME     J30 229
 '@T6G_MB_LIB.T6G(SCH_1):PAGE100_I52@PURE_QUANTA.SCONN288_DDR506112002KQ(CHIPS)':
 'CS1_B_N': CDS_PINID='CS1_B_N';
NET_NAME
'M_D_CPU1_SB_DQ<0>'
 '@T6G_MB_LIB.T6G(SCH_1):M_D_CPU1_SB_DQ'<0>:
 C_SIGNAL='@t6g_mb_lib.t6g(sch_1):m_d_cpu1_sb_dq(0)';
NODE_NAME     U26 CB60
 '@T6G_MB_LIB.T6G(SCH_1):PAGE40_I159@PURE_QUANTA.GENOA_SP5(CHIPS)':
 'MDB_DATA0': CDS_PINID='MDB_DATA0';
NODE_NAME     J30 100
 '@T6G_MB_LIB.T6G(SCH_1):PAGE100_I52@PURE_QUANTA.SCONN288_DDR506112002KQ(CHIPS)':
 'DQ0_B': CDS_PINID='DQ0_B';
NET_NAME
'M_D_CPU1_SB_DQ<10>'
 '@T6G_MB_LIB.T6G(SCH_1):M_D_CPU1_SB_DQ'<10>:
 C_SIGNAL='@t6g_mb_lib.t6g(sch_1):m_d_cpu1_sb_dq(10)';
NODE_NAME     U26 CJ60
 '@T6G_MB_LIB.T6G(SCH_1):PAGE40_I159@PURE_QUANTA.GENOA_SP5(CHIPS)':
 'MDB_DATA10': CDS_PINID='MDB_DATA10';
NODE_NAME     J30 256
 '@T6G_MB_LIB.T6G(SCH_1):PAGE100_I52@PURE_QUANTA.SCONN288_DDR506112002KQ(CHIPS)':
 'DQ10_B': CDS_PINID='DQ10_B';
NET_NAME
'M_D_CPU1_SB_DQ<11>'
 '@T6G_MB_LIB.T6G(SCH_1):M_D_CPU1_SB_DQ'<11>:
 C_SIGNAL='@t6g_mb_lib.t6g(sch_1):m_d_cpu1_sb_dq(11)';
NODE_NAME     U26 CK58
 '@T6G_MB_LIB.T6G(SCH_1):PAGE40_I159@PURE_QUANTA.GENOA_SP5(CHIPS)':
 'MDB_DATA11': CDS_PINID='MDB_DATA11';
NODE_NAME     J30 258
 '@T6G_MB_LIB.T6G(SCH_1):PAGE100_I52@PURE_QUANTA.SCONN288_DDR506112002KQ(CHIPS)':
 'DQ11_B': CDS_PINID='DQ11_B';
NET_NAME
'M_D_CPU1_SB_DQ<12>'
 '@T6G_MB_LIB.T6G(SCH_1):M_D_CPU1_SB_DQ'<12>:
 C_SIGNAL='@t6g_mb_lib.t6g(sch_1):m_d_cpu1_sb_dq(12)';
NODE_NAME     U26 CM60
 '@T6G_MB_LIB.T6G(SCH_1):PAGE40_I159@PURE_QUANTA.GENOA_SP5(CHIPS)':
 'MDB_DATA12': CDS_PINID='MDB_DATA12';
NODE_NAME     J30 118
 '@T6G_MB_LIB.T6G(SCH_1):PAGE100_I52@PURE_QUANTA.SCONN288_DDR506112002KQ(CHIPS)':
 'DQ12_B': CDS_PINID='DQ12_B';
NET_NAME
'M_D_CPU1_SB_DQ<13>'
 '@T6G_MB_LIB.T6G(SCH_1):M_D_CPU1_SB_DQ'<13>:
 C_SIGNAL='@t6g_mb_lib.t6g(sch_1):m_d_cpu1_sb_dq(13)';
NODE_NAME     U26 CN59
 '@T6G_MB_LIB.T6G(SCH_1):PAGE40_I159@PURE_QUANTA.GENOA_SP5(CHIPS)':
 'MDB_DATA13': CDS_PINID='MDB_DATA13';
NODE_NAME     J30 120
 '@T6G_MB_LIB.T6G(SCH_1):PAGE100_I52@PURE_QUANTA.SCONN288_DDR506112002KQ(CHIPS)':
 'DQ13_B': CDS_PINID='DQ13_B';
NET_NAME
'M_D_CPU1_SB_DQ<14>'
 '@T6G_MB_LIB.T6G(SCH_1):M_D_CPU1_SB_DQ'<14>:
 C_SIGNAL='@t6g_mb_lib.t6g(sch_1):m_d_cpu1_sb_dq(14)';
NODE_NAME     U26 CN60
 '@T6G_MB_LIB.T6G(SCH_1):PAGE40_I159@PURE_QUANTA.GENOA_SP5(CHIPS)':
 'MDB_DATA14': CDS_PINID='MDB_DATA14';
NODE_NAME     J30 263
 '@T6G_MB_LIB.T6G(SCH_1):PAGE100_I52@PURE_QUANTA.SCONN288_DDR506112002KQ(CHIPS)':
 'DQ14_B': CDS_PINID='DQ14_B';
NET_NAME
'M_D_CPU1_SB_DQ<15>'
 '@T6G_MB_LIB.T6G(SCH_1):M_D_CPU1_SB_DQ'<15>:
 C_SIGNAL='@t6g_mb_lib.t6g(sch_1):m_d_cpu1_sb_dq(15)';
NODE_NAME     U26 CP58
 '@T6G_MB_LIB.T6G(SCH_1):PAGE40_I159@PURE_QUANTA.GENOA_SP5(CHIPS)':
 'MDB_DATA15': CDS_PINID='MDB_DATA15';
NODE_NAME     J30 265
 '@T6G_MB_LIB.T6G(SCH_1):PAGE100_I52@PURE_QUANTA.SCONN288_DDR506112002KQ(CHIPS)':
 'DQ15_B': CDS_PINID='DQ15_B';
NET_NAME
'M_D_CPU1_SB_DQ<16>'
 '@T6G_MB_LIB.T6G(SCH_1):M_D_CPU1_SB_DQ'<16>:
 C_SIGNAL='@t6g_mb_lib.t6g(sch_1):m_d_cpu1_sb_dq(16)';
NODE_NAME     U26 CP60
 '@T6G_MB_LIB.T6G(SCH_1):PAGE40_I159@PURE_QUANTA.GENOA_SP5(CHIPS)':
 'MDB_DATA16': CDS_PINID='MDB_DATA16';
NODE_NAME     J30 122
 '@T6G_MB_LIB.T6G(SCH_1):PAGE100_I52@PURE_QUANTA.SCONN288_DDR506112002KQ(CHIPS)':
 'DQ16_B': CDS_PINID='DQ16_B';
NET_NAME
'M_D_CPU1_SB_DQ<17>'
 '@T6G_MB_LIB.T6G(SCH_1):M_D_CPU1_SB_DQ'<17>:
 C_SIGNAL='@t6g_mb_lib.t6g(sch_1):m_d_cpu1_sb_dq(17)';
NODE_NAME     U26 CR59
 '@T6G_MB_LIB.T6G(SCH_1):PAGE40_I159@PURE_QUANTA.GENOA_SP5(CHIPS)':
 'MDB_DATA17': CDS_PINID='MDB_DATA17';
NODE_NAME     J30 124
 '@T6G_MB_LIB.T6G(SCH_1):PAGE100_I52@PURE_QUANTA.SCONN288_DDR506112002KQ(CHIPS)':
 'DQ17_B': CDS_PINID='DQ17_B';
NET_NAME
'M_D_CPU1_SB_DQ<18>'
 '@T6G_MB_LIB.T6G(SCH_1):M_D_CPU1_SB_DQ'<18>:
 C_SIGNAL='@t6g_mb_lib.t6g(sch_1):m_d_cpu1_sb_dq(18)';
NODE_NAME     U26 CR60
 '@T6G_MB_LIB.T6G(SCH_1):PAGE40_I159@PURE_QUANTA.GENOA_SP5(CHIPS)':
 'MDB_DATA18': CDS_PINID='MDB_DATA18';
NODE_NAME     J30 267
 '@T6G_MB_LIB.T6G(SCH_1):PAGE100_I52@PURE_QUANTA.SCONN288_DDR506112002KQ(CHIPS)':
 'DQ18_B': CDS_PINID='DQ18_B';
NET_NAME
'M_D_CPU1_SB_DQ<19>'
 '@T6G_MB_LIB.T6G(SCH_1):M_D_CPU1_SB_DQ'<19>:
 C_SIGNAL='@t6g_mb_lib.t6g(sch_1):m_d_cpu1_sb_dq(19)';
NODE_NAME     U26 CT58
 '@T6G_MB_LIB.T6G(SCH_1):PAGE40_I159@PURE_QUANTA.GENOA_SP5(CHIPS)':
 'MDB_DATA19': CDS_PINID='MDB_DATA19';
NODE_NAME     J30 269
 '@T6G_MB_LIB.T6G(SCH_1):PAGE100_I52@PURE_QUANTA.SCONN288_DDR506112002KQ(CHIPS)':
 'DQ19_B': CDS_PINID='DQ19_B';
NET_NAME
'M_D_CPU1_SB_DQ<1>'
 '@T6G_MB_LIB.T6G(SCH_1):M_D_CPU1_SB_DQ'<1>:
 C_SIGNAL='@t6g_mb_lib.t6g(sch_1):m_d_cpu1_sb_dq(1)';
NODE_NAME     U26 CC59
 '@T6G_MB_LIB.T6G(SCH_1):PAGE40_I159@PURE_QUANTA.GENOA_SP5(CHIPS)':
 'MDB_DATA1': CDS_PINID='MDB_DATA1';
NODE_NAME     J30 102
 '@T6G_MB_LIB.T6G(SCH_1):PAGE100_I52@PURE_QUANTA.SCONN288_DDR506112002KQ(CHIPS)':
 'DQ1_B': CDS_PINID='DQ1_B';
NET_NAME
'M_D_CPU1_SB_DQ<20>'
 '@T6G_MB_LIB.T6G(SCH_1):M_D_CPU1_SB_DQ'<20>:
 C_SIGNAL='@t6g_mb_lib.t6g(sch_1):m_d_cpu1_sb_dq(20)';
NODE_NAME     U26 CV60
 '@T6G_MB_LIB.T6G(SCH_1):PAGE40_I159@PURE_QUANTA.GENOA_SP5(CHIPS)':
 'MDB_DATA20': CDS_PINID='MDB_DATA20';
NODE_NAME     J30 129
 '@T6G_MB_LIB.T6G(SCH_1):PAGE100_I52@PURE_QUANTA.SCONN288_DDR506112002KQ(CHIPS)':
 'DQ20_B': CDS_PINID='DQ20_B';
NET_NAME
'M_D_CPU1_SB_DQ<21>'
 '@T6G_MB_LIB.T6G(SCH_1):M_D_CPU1_SB_DQ'<21>:
 C_SIGNAL='@t6g_mb_lib.t6g(sch_1):m_d_cpu1_sb_dq(21)';
NODE_NAME     U26 CW59
 '@T6G_MB_LIB.T6G(SCH_1):PAGE40_I159@PURE_QUANTA.GENOA_SP5(CHIPS)':
 'MDB_DATA21': CDS_PINID='MDB_DATA21';
NODE_NAME     J30 131
 '@T6G_MB_LIB.T6G(SCH_1):PAGE100_I52@PURE_QUANTA.SCONN288_DDR506112002KQ(CHIPS)':
 'DQ21_B': CDS_PINID='DQ21_B';
NET_NAME
'M_D_CPU1_SB_DQ<22>'
 '@T6G_MB_LIB.T6G(SCH_1):M_D_CPU1_SB_DQ'<22>:
 C_SIGNAL='@t6g_mb_lib.t6g(sch_1):m_d_cpu1_sb_dq(22)';
NODE_NAME     U26 CW60
 '@T6G_MB_LIB.T6G(SCH_1):PAGE40_I159@PURE_QUANTA.GENOA_SP5(CHIPS)':
 'MDB_DATA22': CDS_PINID='MDB_DATA22';
NODE_NAME     J30 274
 '@T6G_MB_LIB.T6G(SCH_1):PAGE100_I52@PURE_QUANTA.SCONN288_DDR506112002KQ(CHIPS)':
 'DQ22_B': CDS_PINID='DQ22_B';
NET_NAME
'M_D_CPU1_SB_DQ<23>'
 '@T6G_MB_LIB.T6G(SCH_1):M_D_CPU1_SB_DQ'<23>:
 C_SIGNAL='@t6g_mb_lib.t6g(sch_1):m_d_cpu1_sb_dq(23)';
NODE_NAME     U26 CY58
 '@T6G_MB_LIB.T6G(SCH_1):PAGE40_I159@PURE_QUANTA.GENOA_SP5(CHIPS)':
 'MDB_DATA23': CDS_PINID='MDB_DATA23';
NODE_NAME     J30 276
 '@T6G_MB_LIB.T6G(SCH_1):PAGE100_I52@PURE_QUANTA.SCONN288_DDR506112002KQ(CHIPS)':
 'DQ23_B': CDS_PINID='DQ23_B';
NET_NAME
'M_D_CPU1_SB_DQ<24>'
 '@T6G_MB_LIB.T6G(SCH_1):M_D_CPU1_SB_DQ'<24>:
 C_SIGNAL='@t6g_mb_lib.t6g(sch_1):m_d_cpu1_sb_dq(24)';
NODE_NAME     U26 CY60
 '@T6G_MB_LIB.T6G(SCH_1):PAGE40_I159@PURE_QUANTA.GENOA_SP5(CHIPS)':
 'MDB_DATA24': CDS_PINID='MDB_DATA24';
NODE_NAME     J30 133
 '@T6G_MB_LIB.T6G(SCH_1):PAGE100_I52@PURE_QUANTA.SCONN288_DDR506112002KQ(CHIPS)':
 'DQ24_B': CDS_PINID='DQ24_B';
NET_NAME
'M_D_CPU1_SB_DQ<25>'
 '@T6G_MB_LIB.T6G(SCH_1):M_D_CPU1_SB_DQ'<25>:
 C_SIGNAL='@t6g_mb_lib.t6g(sch_1):m_d_cpu1_sb_dq(25)';
NODE_NAME     U26 DA59
 '@T6G_MB_LIB.T6G(SCH_1):PAGE40_I159@PURE_QUANTA.GENOA_SP5(CHIPS)':
 'MDB_DATA25': CDS_PINID='MDB_DATA25';
NODE_NAME     J30 135
 '@T6G_MB_LIB.T6G(SCH_1):PAGE100_I52@PURE_QUANTA.SCONN288_DDR506112002KQ(CHIPS)':
 'DQ25_B': CDS_PINID='DQ25_B';
NET_NAME
'M_D_CPU1_SB_DQ<26>'
 '@T6G_MB_LIB.T6G(SCH_1):M_D_CPU1_SB_DQ'<26>:
 C_SIGNAL='@t6g_mb_lib.t6g(sch_1):m_d_cpu1_sb_dq(26)';
NODE_NAME     U26 DA60
 '@T6G_MB_LIB.T6G(SCH_1):PAGE40_I159@PURE_QUANTA.GENOA_SP5(CHIPS)':
 'MDB_DATA26': CDS_PINID='MDB_DATA26';
NODE_NAME     J30 278
 '@T6G_MB_LIB.T6G(SCH_1):PAGE100_I52@PURE_QUANTA.SCONN288_DDR506112002KQ(CHIPS)':
 'DQ26_B': CDS_PINID='DQ26_B';
NET_NAME
'M_D_CPU1_SB_DQ<27>'
 '@T6G_MB_LIB.T6G(SCH_1):M_D_CPU1_SB_DQ'<27>:
 C_SIGNAL='@t6g_mb_lib.t6g(sch_1):m_d_cpu1_sb_dq(27)';
NODE_NAME     U26 DB58
 '@T6G_MB_LIB.T6G(SCH_1):PAGE40_I159@PURE_QUANTA.GENOA_SP5(CHIPS)':
 'MDB_DATA27': CDS_PINID='MDB_DATA27';
NODE_NAME     J30 280
 '@T6G_MB_LIB.T6G(SCH_1):PAGE100_I52@PURE_QUANTA.SCONN288_DDR506112002KQ(CHIPS)':
 'DQ27_B': CDS_PINID='DQ27_B';
NET_NAME
'M_D_CPU1_SB_DQ<28>'
 '@T6G_MB_LIB.T6G(SCH_1):M_D_CPU1_SB_DQ'<28>:
 C_SIGNAL='@t6g_mb_lib.t6g(sch_1):m_d_cpu1_sb_dq(28)';
NODE_NAME     U26 DD60
 '@T6G_MB_LIB.T6G(SCH_1):PAGE40_I159@PURE_QUANTA.GENOA_SP5(CHIPS)':
 'MDB_DATA28': CDS_PINID='MDB_DATA28';
NODE_NAME     J30 140
 '@T6G_MB_LIB.T6G(SCH_1):PAGE100_I52@PURE_QUANTA.SCONN288_DDR506112002KQ(CHIPS)':
 'DQ28_B': CDS_PINID='DQ28_B';
NET_NAME
'M_D_CPU1_SB_DQ<29>'
 '@T6G_MB_LIB.T6G(SCH_1):M_D_CPU1_SB_DQ'<29>:
 C_SIGNAL='@t6g_mb_lib.t6g(sch_1):m_d_cpu1_sb_dq(29)';
NODE_NAME     U26 DE59
 '@T6G_MB_LIB.T6G(SCH_1):PAGE40_I159@PURE_QUANTA.GENOA_SP5(CHIPS)':
 'MDB_DATA29': CDS_PINID='MDB_DATA29';
NODE_NAME     J30 142
 '@T6G_MB_LIB.T6G(SCH_1):PAGE100_I52@PURE_QUANTA.SCONN288_DDR506112002KQ(CHIPS)':
 'DQ29_B': CDS_PINID='DQ29_B';
NET_NAME
'M_D_CPU1_SB_DQ<2>'
 '@T6G_MB_LIB.T6G(SCH_1):M_D_CPU1_SB_DQ'<2>:
 C_SIGNAL='@t6g_mb_lib.t6g(sch_1):m_d_cpu1_sb_dq(2)';
NODE_NAME     U26 CC60
 '@T6G_MB_LIB.T6G(SCH_1):PAGE40_I159@PURE_QUANTA.GENOA_SP5(CHIPS)':
 'MDB_DATA2': CDS_PINID='MDB_DATA2';
NODE_NAME     J30 245
 '@T6G_MB_LIB.T6G(SCH_1):PAGE100_I52@PURE_QUANTA.SCONN288_DDR506112002KQ(CHIPS)':
 'DQ2_B': CDS_PINID='DQ2_B';
NET_NAME
'M_D_CPU1_SB_DQ<30>'
 '@T6G_MB_LIB.T6G(SCH_1):M_D_CPU1_SB_DQ'<30>:
 C_SIGNAL='@t6g_mb_lib.t6g(sch_1):m_d_cpu1_sb_dq(30)';
NODE_NAME     U26 DE60
 '@T6G_MB_LIB.T6G(SCH_1):PAGE40_I159@PURE_QUANTA.GENOA_SP5(CHIPS)':
 'MDB_DATA30': CDS_PINID='MDB_DATA30';
NODE_NAME     J30 285
 '@T6G_MB_LIB.T6G(SCH_1):PAGE100_I52@PURE_QUANTA.SCONN288_DDR506112002KQ(CHIPS)':
 'DQ30_B': CDS_PINID='DQ30_B';
NET_NAME
'M_D_CPU1_SB_DQ<31>'
 '@T6G_MB_LIB.T6G(SCH_1):M_D_CPU1_SB_DQ'<31>:
 C_SIGNAL='@t6g_mb_lib.t6g(sch_1):m_d_cpu1_sb_dq(31)';
NODE_NAME     U26 DF60
 '@T6G_MB_LIB.T6G(SCH_1):PAGE40_I159@PURE_QUANTA.GENOA_SP5(CHIPS)':
 'MDB_DATA31': CDS_PINID='MDB_DATA31';
NODE_NAME     J30 287
 '@T6G_MB_LIB.T6G(SCH_1):PAGE100_I52@PURE_QUANTA.SCONN288_DDR506112002KQ(CHIPS)':
 'DQ31_B': CDS_PINID='DQ31_B';
NET_NAME
'M_D_CPU1_SB_DQ<3>'
 '@T6G_MB_LIB.T6G(SCH_1):M_D_CPU1_SB_DQ'<3>:
 C_SIGNAL='@t6g_mb_lib.t6g(sch_1):m_d_cpu1_sb_dq(3)';
NODE_NAME     U26 CD58
 '@T6G_MB_LIB.T6G(SCH_1):PAGE40_I159@PURE_QUANTA.GENOA_SP5(CHIPS)':
 'MDB_DATA3': CDS_PINID='MDB_DATA3';
NODE_NAME     J30 247
 '@T6G_MB_LIB.T6G(SCH_1):PAGE100_I52@PURE_QUANTA.SCONN288_DDR506112002KQ(CHIPS)':
 'DQ3_B': CDS_PINID='DQ3_B';
NET_NAME
'M_D_CPU1_SB_DQ<4>'
 '@T6G_MB_LIB.T6G(SCH_1):M_D_CPU1_SB_DQ'<4>:
 C_SIGNAL='@t6g_mb_lib.t6g(sch_1):m_d_cpu1_sb_dq(4)';
NODE_NAME     U26 CF60
 '@T6G_MB_LIB.T6G(SCH_1):PAGE40_I159@PURE_QUANTA.GENOA_SP5(CHIPS)':
 'MDB_DATA4': CDS_PINID='MDB_DATA4';
NODE_NAME     J30 107
 '@T6G_MB_LIB.T6G(SCH_1):PAGE100_I52@PURE_QUANTA.SCONN288_DDR506112002KQ(CHIPS)':
 'DQ4_B': CDS_PINID='DQ4_B';
NET_NAME
'M_D_CPU1_SB_DQ<5>'
 '@T6G_MB_LIB.T6G(SCH_1):M_D_CPU1_SB_DQ'<5>:
 C_SIGNAL='@t6g_mb_lib.t6g(sch_1):m_d_cpu1_sb_dq(5)';
NODE_NAME     U26 CG59
 '@T6G_MB_LIB.T6G(SCH_1):PAGE40_I159@PURE_QUANTA.GENOA_SP5(CHIPS)':
 'MDB_DATA5': CDS_PINID='MDB_DATA5';
NODE_NAME     J30 109
 '@T6G_MB_LIB.T6G(SCH_1):PAGE100_I52@PURE_QUANTA.SCONN288_DDR506112002KQ(CHIPS)':
 'DQ5_B': CDS_PINID='DQ5_B';
NET_NAME
'M_D_CPU1_SB_DQ<6>'
 '@T6G_MB_LIB.T6G(SCH_1):M_D_CPU1_SB_DQ'<6>:
 C_SIGNAL='@t6g_mb_lib.t6g(sch_1):m_d_cpu1_sb_dq(6)';
NODE_NAME     U26 CG60
 '@T6G_MB_LIB.T6G(SCH_1):PAGE40_I159@PURE_QUANTA.GENOA_SP5(CHIPS)':
 'MDB_DATA6': CDS_PINID='MDB_DATA6';
NODE_NAME     J30 252
 '@T6G_MB_LIB.T6G(SCH_1):PAGE100_I52@PURE_QUANTA.SCONN288_DDR506112002KQ(CHIPS)':
 'DQ6_B': CDS_PINID='DQ6_B';
NET_NAME
'M_D_CPU1_SB_DQ<7>'
 '@T6G_MB_LIB.T6G(SCH_1):M_D_CPU1_SB_DQ'<7>:
 C_SIGNAL='@t6g_mb_lib.t6g(sch_1):m_d_cpu1_sb_dq(7)';
NODE_NAME     U26 CH58
 '@T6G_MB_LIB.T6G(SCH_1):PAGE40_I159@PURE_QUANTA.GENOA_SP5(CHIPS)':
 'MDB_DATA7': CDS_PINID='MDB_DATA7';
NODE_NAME     J30 254
 '@T6G_MB_LIB.T6G(SCH_1):PAGE100_I52@PURE_QUANTA.SCONN288_DDR506112002KQ(CHIPS)':
 'DQ7_B': CDS_PINID='DQ7_B';
NET_NAME
'M_D_CPU1_SB_DQ<8>'
 '@T6G_MB_LIB.T6G(SCH_1):M_D_CPU1_SB_DQ'<8>:
 C_SIGNAL='@t6g_mb_lib.t6g(sch_1):m_d_cpu1_sb_dq(8)';
NODE_NAME     U26 CH60
 '@T6G_MB_LIB.T6G(SCH_1):PAGE40_I159@PURE_QUANTA.GENOA_SP5(CHIPS)':
 'MDB_DATA8': CDS_PINID='MDB_DATA8';
NODE_NAME     J30 111
 '@T6G_MB_LIB.T6G(SCH_1):PAGE100_I52@PURE_QUANTA.SCONN288_DDR506112002KQ(CHIPS)':
 'DQ8_B': CDS_PINID='DQ8_B';
NET_NAME
'M_D_CPU1_SB_DQ<9>'
 '@T6G_MB_LIB.T6G(SCH_1):M_D_CPU1_SB_DQ'<9>:
 C_SIGNAL='@t6g_mb_lib.t6g(sch_1):m_d_cpu1_sb_dq(9)';
NODE_NAME     U26 CJ59
 '@T6G_MB_LIB.T6G(SCH_1):PAGE40_I159@PURE_QUANTA.GENOA_SP5(CHIPS)':
 'MDB_DATA9': CDS_PINID='MDB_DATA9';
NODE_NAME     J30 113
 '@T6G_MB_LIB.T6G(SCH_1):PAGE100_I52@PURE_QUANTA.SCONN288_DDR506112002KQ(CHIPS)':
 'DQ9_B': CDS_PINID='DQ9_B';
NET_NAME
'M_D_CPU1_SB_DQS_DN<0>'
 '@T6G_MB_LIB.T6G(SCH_1):M_D_CPU1_SB_DQS_DN'<0>:
 C_SIGNAL='@t6g_mb_lib.t6g(sch_1):m_d_cpu1_sb_dqs_dn(0)';
NODE_NAME     U26 CE60
 '@T6G_MB_LIB.T6G(SCH_1):PAGE40_I159@PURE_QUANTA.GENOA_SP5(CHIPS)':
 'MDB_DQS_L0': CDS_PINID='MDB_DQS_L0';
NODE_NAME     J30 105
 '@T6G_MB_LIB.T6G(SCH_1):PAGE100_I236@PURE_QUANTA.SCONN288_DDR506112002KQ(CHIPS)':
 'DQS0_B_C': CDS_PINID='DQS0_B_C';
NET_NAME
'M_D_CPU1_SB_DQS_DN<1>'
 '@T6G_MB_LIB.T6G(SCH_1):M_D_CPU1_SB_DQS_DN'<1>:
 C_SIGNAL='@t6g_mb_lib.t6g(sch_1):m_d_cpu1_sb_dqs_dn(1)';
NODE_NAME     U26 CL60
 '@T6G_MB_LIB.T6G(SCH_1):PAGE40_I159@PURE_QUANTA.GENOA_SP5(CHIPS)':
 'MDB_DQS_L1': CDS_PINID='MDB_DQS_L1';
NODE_NAME     J30 116
 '@T6G_MB_LIB.T6G(SCH_1):PAGE100_I236@PURE_QUANTA.SCONN288_DDR506112002KQ(CHIPS)':
 'DQS1_B_C': CDS_PINID='DQS1_B_C';
NET_NAME
'M_D_CPU1_SB_DQS_DN<2>'
 '@T6G_MB_LIB.T6G(SCH_1):M_D_CPU1_SB_DQS_DN'<2>:
 C_SIGNAL='@t6g_mb_lib.t6g(sch_1):m_d_cpu1_sb_dqs_dn(2)';
NODE_NAME     U26 CU60
 '@T6G_MB_LIB.T6G(SCH_1):PAGE40_I159@PURE_QUANTA.GENOA_SP5(CHIPS)':
 'MDB_DQS_L2': CDS_PINID='MDB_DQS_L2';
NODE_NAME     J30 127
 '@T6G_MB_LIB.T6G(SCH_1):PAGE100_I236@PURE_QUANTA.SCONN288_DDR506112002KQ(CHIPS)':
 'DQS2_B_C': CDS_PINID='DQS2_B_C';
NET_NAME
'M_D_CPU1_SB_DQS_DN<3>'
 '@T6G_MB_LIB.T6G(SCH_1):M_D_CPU1_SB_DQS_DN'<3>:
 C_SIGNAL='@t6g_mb_lib.t6g(sch_1):m_d_cpu1_sb_dqs_dn(3)';
NODE_NAME     U26 DC60
 '@T6G_MB_LIB.T6G(SCH_1):PAGE40_I159@PURE_QUANTA.GENOA_SP5(CHIPS)':
 'MDB_DQS_L3': CDS_PINID='MDB_DQS_L3';
NODE_NAME     J30 138
 '@T6G_MB_LIB.T6G(SCH_1):PAGE100_I236@PURE_QUANTA.SCONN288_DDR506112002KQ(CHIPS)':
 'DQS3_B_C': CDS_PINID='DQS3_B_C';
NET_NAME
'M_D_CPU1_SB_DQS_DN<4>'
 '@T6G_MB_LIB.T6G(SCH_1):M_D_CPU1_SB_DQS_DN'<4>:
 C_SIGNAL='@t6g_mb_lib.t6g(sch_1):m_d_cpu1_sb_dqs_dn(4)';
NODE_NAME     U26 BW59
 '@T6G_MB_LIB.T6G(SCH_1):PAGE40_I159@PURE_QUANTA.GENOA_SP5(CHIPS)':
 'MDB_DQS_L4': CDS_PINID='MDB_DQS_L4';
NODE_NAME     J30 238
 '@T6G_MB_LIB.T6G(SCH_1):PAGE100_I236@PURE_QUANTA.SCONN288_DDR506112002KQ(CHIPS)':
 'DQS4_B_C': CDS_PINID='DQS4_B_C';
NET_NAME
'M_D_CPU1_SB_DQS_DN<5>'
 '@T6G_MB_LIB.T6G(SCH_1):M_D_CPU1_SB_DQS_DN'<5>:
 C_SIGNAL='@t6g_mb_lib.t6g(sch_1):m_d_cpu1_sb_dqs_dn(5)';
NODE_NAME     U26 CE59
 '@T6G_MB_LIB.T6G(SCH_1):PAGE40_I159@PURE_QUANTA.GENOA_SP5(CHIPS)':
 'MDB_DQS_L5': CDS_PINID='MDB_DQS_L5';
NODE_NAME     J30 249
 '@T6G_MB_LIB.T6G(SCH_1):PAGE100_I236@PURE_QUANTA.SCONN288_DDR506112002KQ(CHIPS)':
 'DQS5_B_C||TDQS5_B_C': CDS_PINID='\dqs5_b_c||tdqs5_b_c\';
NET_NAME
'M_D_CPU1_SB_DQS_DN<6>'
 '@T6G_MB_LIB.T6G(SCH_1):M_D_CPU1_SB_DQS_DN'<6>:
 C_SIGNAL='@t6g_mb_lib.t6g(sch_1):m_d_cpu1_sb_dqs_dn(6)';
NODE_NAME     U26 CL59
 '@T6G_MB_LIB.T6G(SCH_1):PAGE40_I159@PURE_QUANTA.GENOA_SP5(CHIPS)':
 'MDB_DQS_L6': CDS_PINID='MDB_DQS_L6';
NODE_NAME     J30 260
 '@T6G_MB_LIB.T6G(SCH_1):PAGE100_I236@PURE_QUANTA.SCONN288_DDR506112002KQ(CHIPS)':
 'DQS6_B_C||TDQS6_B_C': CDS_PINID='\dqs6_b_c||tdqs6_b_c\';
NET_NAME
'M_D_CPU1_SB_DQS_DN<7>'
 '@T6G_MB_LIB.T6G(SCH_1):M_D_CPU1_SB_DQS_DN'<7>:
 C_SIGNAL='@t6g_mb_lib.t6g(sch_1):m_d_cpu1_sb_dqs_dn(7)';
NODE_NAME     U26 CU59
 '@T6G_MB_LIB.T6G(SCH_1):PAGE40_I159@PURE_QUANTA.GENOA_SP5(CHIPS)':
 'MDB_DQS_L7': CDS_PINID='MDB_DQS_L7';
NODE_NAME     J30 271
 '@T6G_MB_LIB.T6G(SCH_1):PAGE100_I236@PURE_QUANTA.SCONN288_DDR506112002KQ(CHIPS)':
 'DQS7_B_C||TDQS7_B_C': CDS_PINID='\dqs7_b_c||tdqs7_b_c\';
NET_NAME
'M_D_CPU1_SB_DQS_DN<8>'
 '@T6G_MB_LIB.T6G(SCH_1):M_D_CPU1_SB_DQS_DN'<8>:
 C_SIGNAL='@t6g_mb_lib.t6g(sch_1):m_d_cpu1_sb_dqs_dn(8)';
NODE_NAME     U26 DC59
 '@T6G_MB_LIB.T6G(SCH_1):PAGE40_I159@PURE_QUANTA.GENOA_SP5(CHIPS)':
 'MDB_DQS_L8': CDS_PINID='MDB_DQS_L8';
NODE_NAME     J30 282
 '@T6G_MB_LIB.T6G(SCH_1):PAGE100_I236@PURE_QUANTA.SCONN288_DDR506112002KQ(CHIPS)':
 'DQS8_B_C||TDQS8_B_C': CDS_PINID='\dqs8_b_c||tdqs8_b_c\';
NET_NAME
'M_D_CPU1_SB_DQS_DN<9>'
 '@T6G_MB_LIB.T6G(SCH_1):M_D_CPU1_SB_DQS_DN'<9>:
 C_SIGNAL='@t6g_mb_lib.t6g(sch_1):m_d_cpu1_sb_dqs_dn(9)';
NODE_NAME     U26 BW60
 '@T6G_MB_LIB.T6G(SCH_1):PAGE40_I159@PURE_QUANTA.GENOA_SP5(CHIPS)':
 'MDB_DQS_L9': CDS_PINID='MDB_DQS_L9';
NODE_NAME     J30 94
 '@T6G_MB_LIB.T6G(SCH_1):PAGE100_I236@PURE_QUANTA.SCONN288_DDR506112002KQ(CHIPS)':
 'DQS9_B_C||TDQS9_B_C': CDS_PINID='\dqs9_b_c||tdqs9_b_c\';
NET_NAME
'M_D_CPU1_SB_DQS_DP<0>'
 '@T6G_MB_LIB.T6G(SCH_1):M_D_CPU1_SB_DQS_DP'<0>:
 C_SIGNAL='@t6g_mb_lib.t6g(sch_1):m_d_cpu1_sb_dqs_dp(0)';
NODE_NAME     U26 CD60
 '@T6G_MB_LIB.T6G(SCH_1):PAGE40_I159@PURE_QUANTA.GENOA_SP5(CHIPS)':
 'MDB_DQS_H0': CDS_PINID='MDB_DQS_H0';
NODE_NAME     J30 104
 '@T6G_MB_LIB.T6G(SCH_1):PAGE100_I236@PURE_QUANTA.SCONN288_DDR506112002KQ(CHIPS)':
 'DQS0_B_T': CDS_PINID='DQS0_B_T';
NET_NAME
'M_D_CPU1_SB_DQS_DP<1>'
 '@T6G_MB_LIB.T6G(SCH_1):M_D_CPU1_SB_DQS_DP'<1>:
 C_SIGNAL='@t6g_mb_lib.t6g(sch_1):m_d_cpu1_sb_dqs_dp(1)';
NODE_NAME     U26 CK60
 '@T6G_MB_LIB.T6G(SCH_1):PAGE40_I159@PURE_QUANTA.GENOA_SP5(CHIPS)':
 'MDB_DQS_H1': CDS_PINID='MDB_DQS_H1';
NODE_NAME     J30 115
 '@T6G_MB_LIB.T6G(SCH_1):PAGE100_I236@PURE_QUANTA.SCONN288_DDR506112002KQ(CHIPS)':
 'DQS1_B_T': CDS_PINID='DQS1_B_T';
NET_NAME
'M_D_CPU1_SB_DQS_DP<2>'
 '@T6G_MB_LIB.T6G(SCH_1):M_D_CPU1_SB_DQS_DP'<2>:
 C_SIGNAL='@t6g_mb_lib.t6g(sch_1):m_d_cpu1_sb_dqs_dp(2)';
NODE_NAME     U26 CT60
 '@T6G_MB_LIB.T6G(SCH_1):PAGE40_I159@PURE_QUANTA.GENOA_SP5(CHIPS)':
 'MDB_DQS_H2': CDS_PINID='MDB_DQS_H2';
NODE_NAME     J30 126
 '@T6G_MB_LIB.T6G(SCH_1):PAGE100_I236@PURE_QUANTA.SCONN288_DDR506112002KQ(CHIPS)':
 'DQS2_B_T': CDS_PINID='DQS2_B_T';
NET_NAME
'M_D_CPU1_SB_DQS_DP<3>'
 '@T6G_MB_LIB.T6G(SCH_1):M_D_CPU1_SB_DQS_DP'<3>:
 C_SIGNAL='@t6g_mb_lib.t6g(sch_1):m_d_cpu1_sb_dqs_dp(3)';
NODE_NAME     U26 DB60
 '@T6G_MB_LIB.T6G(SCH_1):PAGE40_I159@PURE_QUANTA.GENOA_SP5(CHIPS)':
 'MDB_DQS_H3': CDS_PINID='MDB_DQS_H3';
NODE_NAME     J30 137
 '@T6G_MB_LIB.T6G(SCH_1):PAGE100_I236@PURE_QUANTA.SCONN288_DDR506112002KQ(CHIPS)':
 'DQS3_B_T': CDS_PINID='DQS3_B_T';
NET_NAME
'M_D_CPU1_SB_DQS_DP<4>'
 '@T6G_MB_LIB.T6G(SCH_1):M_D_CPU1_SB_DQS_DP'<4>:
 C_SIGNAL='@t6g_mb_lib.t6g(sch_1):m_d_cpu1_sb_dqs_dp(4)';
NODE_NAME     U26 BY58
 '@T6G_MB_LIB.T6G(SCH_1):PAGE40_I159@PURE_QUANTA.GENOA_SP5(CHIPS)':
 'MDB_DQS_H4': CDS_PINID='MDB_DQS_H4';
NODE_NAME     J30 239
 '@T6G_MB_LIB.T6G(SCH_1):PAGE100_I236@PURE_QUANTA.SCONN288_DDR506112002KQ(CHIPS)':
 'DQS4_B_T': CDS_PINID='DQS4_B_T';
NET_NAME
'M_D_CPU1_SB_DQS_DP<5>'
 '@T6G_MB_LIB.T6G(SCH_1):M_D_CPU1_SB_DQS_DP'<5>:
 C_SIGNAL='@t6g_mb_lib.t6g(sch_1):m_d_cpu1_sb_dqs_dp(5)';
NODE_NAME     U26 CF58
 '@T6G_MB_LIB.T6G(SCH_1):PAGE40_I159@PURE_QUANTA.GENOA_SP5(CHIPS)':
 'MDB_DQS_H5': CDS_PINID='MDB_DQS_H5';
NODE_NAME     J30 250
 '@T6G_MB_LIB.T6G(SCH_1):PAGE100_I236@PURE_QUANTA.SCONN288_DDR506112002KQ(CHIPS)':
 'DQS5_B_T||TDQS5_B_T': CDS_PINID='\dqs5_b_t||tdqs5_b_t\';
NET_NAME
'M_D_CPU1_SB_DQS_DP<6>'
 '@T6G_MB_LIB.T6G(SCH_1):M_D_CPU1_SB_DQS_DP'<6>:
 C_SIGNAL='@t6g_mb_lib.t6g(sch_1):m_d_cpu1_sb_dqs_dp(6)';
NODE_NAME     U26 CM58
 '@T6G_MB_LIB.T6G(SCH_1):PAGE40_I159@PURE_QUANTA.GENOA_SP5(CHIPS)':
 'MDB_DQS_H6': CDS_PINID='MDB_DQS_H6';
NODE_NAME     J30 261
 '@T6G_MB_LIB.T6G(SCH_1):PAGE100_I236@PURE_QUANTA.SCONN288_DDR506112002KQ(CHIPS)':
 'DQS6_B_T||TDQS6_B_T': CDS_PINID='\dqs6_b_t||tdqs6_b_t\';
NET_NAME
'M_D_CPU1_SB_DQS_DP<7>'
 '@T6G_MB_LIB.T6G(SCH_1):M_D_CPU1_SB_DQS_DP'<7>:
 C_SIGNAL='@t6g_mb_lib.t6g(sch_1):m_d_cpu1_sb_dqs_dp(7)';
NODE_NAME     U26 CV58
 '@T6G_MB_LIB.T6G(SCH_1):PAGE40_I159@PURE_QUANTA.GENOA_SP5(CHIPS)':
 'MDB_DQS_H7': CDS_PINID='MDB_DQS_H7';
NODE_NAME     J30 272
 '@T6G_MB_LIB.T6G(SCH_1):PAGE100_I236@PURE_QUANTA.SCONN288_DDR506112002KQ(CHIPS)':
 'DQS7_B_T||TDQS7_B_T': CDS_PINID='\dqs7_b_t||tdqs7_b_t\';
NET_NAME
'M_D_CPU1_SB_DQS_DP<8>'
 '@T6G_MB_LIB.T6G(SCH_1):M_D_CPU1_SB_DQS_DP'<8>:
 C_SIGNAL='@t6g_mb_lib.t6g(sch_1):m_d_cpu1_sb_dqs_dp(8)';
NODE_NAME     U26 DD58
 '@T6G_MB_LIB.T6G(SCH_1):PAGE40_I159@PURE_QUANTA.GENOA_SP5(CHIPS)':
 'MDB_DQS_H8': CDS_PINID='MDB_DQS_H8';
NODE_NAME     J30 283
 '@T6G_MB_LIB.T6G(SCH_1):PAGE100_I236@PURE_QUANTA.SCONN288_DDR506112002KQ(CHIPS)':
 'DQS8_B_T||TDQS8_B_T': CDS_PINID='\dqs8_b_t||tdqs8_b_t\';
NET_NAME
'M_D_CPU1_SB_DQS_DP<9>'
 '@T6G_MB_LIB.T6G(SCH_1):M_D_CPU1_SB_DQS_DP'<9>:
 C_SIGNAL='@t6g_mb_lib.t6g(sch_1):m_d_cpu1_sb_dqs_dp(9)';
NODE_NAME     U26 BV60
 '@T6G_MB_LIB.T6G(SCH_1):PAGE40_I159@PURE_QUANTA.GENOA_SP5(CHIPS)':
 'MDB_DQS_H9': CDS_PINID='MDB_DQS_H9';
NODE_NAME     J30 93
 '@T6G_MB_LIB.T6G(SCH_1):PAGE100_I236@PURE_QUANTA.SCONN288_DDR506112002KQ(CHIPS)':
 'DQS9_B_T||TDQS9_B_T||DBI4_B_N': CDS_PINID='\dqs9_b_t||tdqs9_b_t||dbi4_b_n\';
NET_NAME
'M_D_CPU1_SB_PAR'
 '@T6G_MB_LIB.T6G(SCH_1):M_D_CPU1_SB_PAR':
 C_SIGNAL='@t6g_mb_lib.t6g(sch_1):m_d_cpu1_sb_par';
NODE_NAME     U26 BL60
 '@T6G_MB_LIB.T6G(SCH_1):PAGE40_I159@PURE_QUANTA.GENOA_SP5(CHIPS)':
 'MDB_PAR': CDS_PINID='MDB_PAR';
NODE_NAME     J30 227
 '@T6G_MB_LIB.T6G(SCH_1):PAGE100_I52@PURE_QUANTA.SCONN288_DDR506112002KQ(CHIPS)':
 'PAR_B': CDS_PINID='PAR_B';
NET_NAME
'M_D_CPU1_SB_RSP<0>'
 '@T6G_MB_LIB.T6G(SCH_1):M_D_CPU1_SB_RSP'<0>:
 C_SIGNAL='@t6g_mb_lib.t6g(sch_1):m_d_cpu1_sb_rsp(0)';
NODE_NAME     U26 BP60
 '@T6G_MB_LIB.T6G(SCH_1):PAGE40_I159@PURE_QUANTA.GENOA_SP5(CHIPS)':
 'MDB0_RSP_L': CDS_PINID='MDB0_RSP_L';
NODE_NAME     J30 87
 '@T6G_MB_LIB.T6G(SCH_1):PAGE100_I52@PURE_QUANTA.SCONN288_DDR506112002KQ(CHIPS)':
 'LBS||RSP_B_N': CDS_PINID='\lbs||rsp_b_n\';
NET_NAME
'M_E_CPU0_ALERT_N'
 '@T6G_MB_LIB.T6G(SCH_1):M_E_CPU0_ALERT_N':
 C_SIGNAL='@t6g_mb_lib.t6g(sch_1):m_e_cpu0_alert_n';
NODE_NAME     R379 1
 '@T6G_MB_LIB.T6G(SCH_1):PAGE14_I315@PURE_QUANTA.Q_RES(CHIPS)':
 'A': CDS_PINID='A';
NODE_NAME     J21 62
 '@T6G_MB_LIB.T6G(SCH_1):PAGE89_I348@PURE_QUANTA.SCONN288_DDR506112002KQ(CHIPS)':
 'ALERT_N': CDS_PINID='ALERT_N';
NET_NAME
'M_E_CPU0_ALERT_R_N'
 '@T6G_MB_LIB.T6G(SCH_1):M_E_CPU0_ALERT_R_N':
 C_SIGNAL='@t6g_mb_lib.t6g(sch_1):m_e_cpu0_alert_r_n';
NODE_NAME     U25 AT69
 '@T6G_MB_LIB.T6G(SCH_1):PAGE14_I159@PURE_QUANTA.GENOA_SP5(CHIPS)':
 'ME_ALERT_L': CDS_PINID='ME_ALERT_L';
NODE_NAME     R379 2
 '@T6G_MB_LIB.T6G(SCH_1):PAGE14_I315@PURE_QUANTA.Q_RES(CHIPS)':
 'B': CDS_PINID='B';
NET_NAME
'M_E_CPU0_CLK_DN<0>'
 '@T6G_MB_LIB.T6G(SCH_1):M_E_CPU0_CLK_DN'<0>:
 C_SIGNAL='@t6g_mb_lib.t6g(sch_1):m_e_cpu0_clk_dn(0)';
NODE_NAME     U25 BD70
 '@T6G_MB_LIB.T6G(SCH_1):PAGE14_I159@PURE_QUANTA.GENOA_SP5(CHIPS)':
 'ME0_CLK_L': CDS_PINID='ME0_CLK_L';
NODE_NAME     J21 218
 '@T6G_MB_LIB.T6G(SCH_1):PAGE89_I348@PURE_QUANTA.SCONN288_DDR506112002KQ(CHIPS)':
 'CK_C': CDS_PINID='CK_C';
NET_NAME
'M_E_CPU0_CLK_DP<0>'
 '@T6G_MB_LIB.T6G(SCH_1):M_E_CPU0_CLK_DP'<0>:
 C_SIGNAL='@t6g_mb_lib.t6g(sch_1):m_e_cpu0_clk_dp(0)';
NODE_NAME     U25 BC71
 '@T6G_MB_LIB.T6G(SCH_1):PAGE14_I159@PURE_QUANTA.GENOA_SP5(CHIPS)':
 'ME0_CLK_H': CDS_PINID='ME0_CLK_H';
NODE_NAME     J21 217
 '@T6G_MB_LIB.T6G(SCH_1):PAGE89_I348@PURE_QUANTA.SCONN288_DDR506112002KQ(CHIPS)':
 'CK_T': CDS_PINID='CK_T';
NET_NAME
'M_E_CPU0_RESET_N'
 '@T6G_MB_LIB.T6G(SCH_1):M_E_CPU0_RESET_N':
 C_SIGNAL='@t6g_mb_lib.t6g(sch_1):m_e_cpu0_reset_n';
NODE_NAME     U25 AU69
 '@T6G_MB_LIB.T6G(SCH_1):PAGE14_I159@PURE_QUANTA.GENOA_SP5(CHIPS)':
 'ME_RESET_L': CDS_PINID='ME_RESET_L';
NODE_NAME     J21 207
 '@T6G_MB_LIB.T6G(SCH_1):PAGE89_I348@PURE_QUANTA.SCONN288_DDR506112002KQ(CHIPS)':
 'RESET_N': CDS_PINID='RESET_N';
NET_NAME
'M_E_CPU0_SA_CA<0>'
 '@T6G_MB_LIB.T6G(SCH_1):M_E_CPU0_SA_CA'<0>:
 C_SIGNAL='@t6g_mb_lib.t6g(sch_1):m_e_cpu0_sa_ca(0)';
NODE_NAME     U25 AW71
 '@T6G_MB_LIB.T6G(SCH_1):PAGE14_I159@PURE_QUANTA.GENOA_SP5(CHIPS)':
 'MEA_CA0': CDS_PINID='MEA_CA0';
NODE_NAME     J21 66
 '@T6G_MB_LIB.T6G(SCH_1):PAGE89_I348@PURE_QUANTA.SCONN288_DDR506112002KQ(CHIPS)':
 'CA0_A': CDS_PINID='CA0_A';
NET_NAME
'M_E_CPU0_SA_CA<1>'
 '@T6G_MB_LIB.T6G(SCH_1):M_E_CPU0_SA_CA'<1>:
 C_SIGNAL='@t6g_mb_lib.t6g(sch_1):m_e_cpu0_sa_ca(1)';
NODE_NAME     U25 AY70
 '@T6G_MB_LIB.T6G(SCH_1):PAGE14_I159@PURE_QUANTA.GENOA_SP5(CHIPS)':
 'MEA_CA1': CDS_PINID='MEA_CA1';
NODE_NAME     J21 211
 '@T6G_MB_LIB.T6G(SCH_1):PAGE89_I348@PURE_QUANTA.SCONN288_DDR506112002KQ(CHIPS)':
 'CA1_A': CDS_PINID='CA1_A';
NET_NAME
'M_E_CPU0_SA_CA<2>'
 '@T6G_MB_LIB.T6G(SCH_1):M_E_CPU0_SA_CA'<2>:
 C_SIGNAL='@t6g_mb_lib.t6g(sch_1):m_e_cpu0_sa_ca(2)';
NODE_NAME     U25 AY69
 '@T6G_MB_LIB.T6G(SCH_1):PAGE14_I159@PURE_QUANTA.GENOA_SP5(CHIPS)':
 'MEA_CA2': CDS_PINID='MEA_CA2';
NODE_NAME     J21 68
 '@T6G_MB_LIB.T6G(SCH_1):PAGE89_I348@PURE_QUANTA.SCONN288_DDR506112002KQ(CHIPS)':
 'CA2_A': CDS_PINID='CA2_A';
NET_NAME
'M_E_CPU0_SA_CA<3>'
 '@T6G_MB_LIB.T6G(SCH_1):M_E_CPU0_SA_CA'<3>:
 C_SIGNAL='@t6g_mb_lib.t6g(sch_1):m_e_cpu0_sa_ca(3)';
NODE_NAME     U25 BA69
 '@T6G_MB_LIB.T6G(SCH_1):PAGE14_I159@PURE_QUANTA.GENOA_SP5(CHIPS)':
 'MEA_CA3': CDS_PINID='MEA_CA3';
NODE_NAME     J21 213
 '@T6G_MB_LIB.T6G(SCH_1):PAGE89_I348@PURE_QUANTA.SCONN288_DDR506112002KQ(CHIPS)':
 'CA3_A': CDS_PINID='CA3_A';
NET_NAME
'M_E_CPU0_SA_CA<4>'
 '@T6G_MB_LIB.T6G(SCH_1):M_E_CPU0_SA_CA'<4>:
 C_SIGNAL='@t6g_mb_lib.t6g(sch_1):m_e_cpu0_sa_ca(4)';
NODE_NAME     U25 BA71
 '@T6G_MB_LIB.T6G(SCH_1):PAGE14_I159@PURE_QUANTA.GENOA_SP5(CHIPS)':
 'MEA_CA4': CDS_PINID='MEA_CA4';
NODE_NAME     J21 70
 '@T6G_MB_LIB.T6G(SCH_1):PAGE89_I348@PURE_QUANTA.SCONN288_DDR506112002KQ(CHIPS)':
 'CA4_A': CDS_PINID='CA4_A';
NET_NAME
'M_E_CPU0_SA_CA<5>'
 '@T6G_MB_LIB.T6G(SCH_1):M_E_CPU0_SA_CA'<5>:
 C_SIGNAL='@t6g_mb_lib.t6g(sch_1):m_e_cpu0_sa_ca(5)';
NODE_NAME     U25 BB70
 '@T6G_MB_LIB.T6G(SCH_1):PAGE14_I159@PURE_QUANTA.GENOA_SP5(CHIPS)':
 'MEA_CA5': CDS_PINID='MEA_CA5';
NODE_NAME     J21 215
 '@T6G_MB_LIB.T6G(SCH_1):PAGE89_I348@PURE_QUANTA.SCONN288_DDR506112002KQ(CHIPS)':
 'CA5_A': CDS_PINID='CA5_A';
NET_NAME
'M_E_CPU0_SA_CA<6>'
 '@T6G_MB_LIB.T6G(SCH_1):M_E_CPU0_SA_CA'<6>:
 C_SIGNAL='@t6g_mb_lib.t6g(sch_1):m_e_cpu0_sa_ca(6)';
NODE_NAME     U25 BB69
 '@T6G_MB_LIB.T6G(SCH_1):PAGE14_I159@PURE_QUANTA.GENOA_SP5(CHIPS)':
 'MEA_CA6': CDS_PINID='MEA_CA6';
NODE_NAME     J21 72
 '@T6G_MB_LIB.T6G(SCH_1):PAGE89_I348@PURE_QUANTA.SCONN288_DDR506112002KQ(CHIPS)':
 'CA6_A': CDS_PINID='CA6_A';
NET_NAME
'M_E_CPU0_SA_CB<0>'
 '@T6G_MB_LIB.T6G(SCH_1):M_E_CPU0_SA_CB'<0>:
 C_SIGNAL='@t6g_mb_lib.t6g(sch_1):m_e_cpu0_sa_cb(0)';
NODE_NAME     U25 AJ71
 '@T6G_MB_LIB.T6G(SCH_1):PAGE14_I159@PURE_QUANTA.GENOA_SP5(CHIPS)':
 'MEA_CHECK0': CDS_PINID='MEA_CHECK0';
NODE_NAME     J21 51
 '@T6G_MB_LIB.T6G(SCH_1):PAGE89_I348@PURE_QUANTA.SCONN288_DDR506112002KQ(CHIPS)':
 'CB0_A': CDS_PINID='CB0_A';
NET_NAME
'M_E_CPU0_SA_CB<1>'
 '@T6G_MB_LIB.T6G(SCH_1):M_E_CPU0_SA_CB'<1>:
 C_SIGNAL='@t6g_mb_lib.t6g(sch_1):m_e_cpu0_sa_cb(1)';
NODE_NAME     U25 AK69
 '@T6G_MB_LIB.T6G(SCH_1):PAGE14_I159@PURE_QUANTA.GENOA_SP5(CHIPS)':
 'MEA_CHECK1': CDS_PINID='MEA_CHECK1';
NODE_NAME     J21 53
 '@T6G_MB_LIB.T6G(SCH_1):PAGE89_I348@PURE_QUANTA.SCONN288_DDR506112002KQ(CHIPS)':
 'CB1_A': CDS_PINID='CB1_A';
NET_NAME
'M_E_CPU0_SA_CB<2>'
 '@T6G_MB_LIB.T6G(SCH_1):M_E_CPU0_SA_CB'<2>:
 C_SIGNAL='@t6g_mb_lib.t6g(sch_1):m_e_cpu0_sa_cb(2)';
NODE_NAME     U25 AK70
 '@T6G_MB_LIB.T6G(SCH_1):PAGE14_I159@PURE_QUANTA.GENOA_SP5(CHIPS)':
 'MEA_CHECK2': CDS_PINID='MEA_CHECK2';
NODE_NAME     J21 196
 '@T6G_MB_LIB.T6G(SCH_1):PAGE89_I348@PURE_QUANTA.SCONN288_DDR506112002KQ(CHIPS)':
 'CB2_A': CDS_PINID='CB2_A';
NET_NAME
'M_E_CPU0_SA_CB<3>'
 '@T6G_MB_LIB.T6G(SCH_1):M_E_CPU0_SA_CB'<3>:
 C_SIGNAL='@t6g_mb_lib.t6g(sch_1):m_e_cpu0_sa_cb(3)';
NODE_NAME     U25 AL69
 '@T6G_MB_LIB.T6G(SCH_1):PAGE14_I159@PURE_QUANTA.GENOA_SP5(CHIPS)':
 'MEA_CHECK3': CDS_PINID='MEA_CHECK3';
NODE_NAME     J21 198
 '@T6G_MB_LIB.T6G(SCH_1):PAGE89_I348@PURE_QUANTA.SCONN288_DDR506112002KQ(CHIPS)':
 'CB3_A': CDS_PINID='CB3_A';
NET_NAME
'M_E_CPU0_SA_CB<4>'
 '@T6G_MB_LIB.T6G(SCH_1):M_E_CPU0_SA_CB'<4>:
 C_SIGNAL='@t6g_mb_lib.t6g(sch_1):m_e_cpu0_sa_cb(4)';
NODE_NAME     U25 AN71
 '@T6G_MB_LIB.T6G(SCH_1):PAGE14_I159@PURE_QUANTA.GENOA_SP5(CHIPS)':
 'MEA_CHECK4': CDS_PINID='MEA_CHECK4';
NODE_NAME     J21 58
 '@T6G_MB_LIB.T6G(SCH_1):PAGE89_I348@PURE_QUANTA.SCONN288_DDR506112002KQ(CHIPS)':
 'CB4_A': CDS_PINID='CB4_A';
NET_NAME
'M_E_CPU0_SA_CB<5>'
 '@T6G_MB_LIB.T6G(SCH_1):M_E_CPU0_SA_CB'<5>:
 C_SIGNAL='@t6g_mb_lib.t6g(sch_1):m_e_cpu0_sa_cb(5)';
NODE_NAME     U25 AP69
 '@T6G_MB_LIB.T6G(SCH_1):PAGE14_I159@PURE_QUANTA.GENOA_SP5(CHIPS)':
 'MEA_CHECK5': CDS_PINID='MEA_CHECK5';
NODE_NAME     J21 60
 '@T6G_MB_LIB.T6G(SCH_1):PAGE89_I348@PURE_QUANTA.SCONN288_DDR506112002KQ(CHIPS)':
 'CB5_A': CDS_PINID='CB5_A';
NET_NAME
'M_E_CPU0_SA_CB<6>'
 '@T6G_MB_LIB.T6G(SCH_1):M_E_CPU0_SA_CB'<6>:
 C_SIGNAL='@t6g_mb_lib.t6g(sch_1):m_e_cpu0_sa_cb(6)';
NODE_NAME     U25 AP70
 '@T6G_MB_LIB.T6G(SCH_1):PAGE14_I159@PURE_QUANTA.GENOA_SP5(CHIPS)':
 'MEA_CHECK6': CDS_PINID='MEA_CHECK6';
NODE_NAME     J21 203
 '@T6G_MB_LIB.T6G(SCH_1):PAGE89_I348@PURE_QUANTA.SCONN288_DDR506112002KQ(CHIPS)':
 'CB6_A': CDS_PINID='CB6_A';
NET_NAME
'M_E_CPU0_SA_CB<7>'
 '@T6G_MB_LIB.T6G(SCH_1):M_E_CPU0_SA_CB'<7>:
 C_SIGNAL='@t6g_mb_lib.t6g(sch_1):m_e_cpu0_sa_cb(7)';
NODE_NAME     U25 AR69
 '@T6G_MB_LIB.T6G(SCH_1):PAGE14_I159@PURE_QUANTA.GENOA_SP5(CHIPS)':
 'MEA_CHECK7': CDS_PINID='MEA_CHECK7';
NODE_NAME     J21 205
 '@T6G_MB_LIB.T6G(SCH_1):PAGE89_I348@PURE_QUANTA.SCONN288_DDR506112002KQ(CHIPS)':
 'CB7_A': CDS_PINID='CB7_A';
NET_NAME
'M_E_CPU0_SA_CS_N<0>'
 '@T6G_MB_LIB.T6G(SCH_1):M_E_CPU0_SA_CS_N'<0>:
 C_SIGNAL='@t6g_mb_lib.t6g(sch_1):m_e_cpu0_sa_cs_n(0)';
NODE_NAME     U25 AV70
 '@T6G_MB_LIB.T6G(SCH_1):PAGE14_I159@PURE_QUANTA.GENOA_SP5(CHIPS)':
 'MEA0_CS_L0': CDS_PINID='MEA0_CS_L0';
NODE_NAME     J21 64
 '@T6G_MB_LIB.T6G(SCH_1):PAGE89_I348@PURE_QUANTA.SCONN288_DDR506112002KQ(CHIPS)':
 'CS0_A_N': CDS_PINID='CS0_A_N';
NET_NAME
'M_E_CPU0_SA_CS_N<1>'
 '@T6G_MB_LIB.T6G(SCH_1):M_E_CPU0_SA_CS_N'<1>:
 C_SIGNAL='@t6g_mb_lib.t6g(sch_1):m_e_cpu0_sa_cs_n(1)';
NODE_NAME     U25 AW69
 '@T6G_MB_LIB.T6G(SCH_1):PAGE14_I159@PURE_QUANTA.GENOA_SP5(CHIPS)':
 'MEA0_CS_L1': CDS_PINID='MEA0_CS_L1';
NODE_NAME     J21 209
 '@T6G_MB_LIB.T6G(SCH_1):PAGE89_I348@PURE_QUANTA.SCONN288_DDR506112002KQ(CHIPS)':
 'CS1_A_N': CDS_PINID='CS1_A_N';
NET_NAME
'M_E_CPU0_SA_DQ<0>'
 '@T6G_MB_LIB.T6G(SCH_1):M_E_CPU0_SA_DQ'<0>:
 C_SIGNAL='@t6g_mb_lib.t6g(sch_1):m_e_cpu0_sa_dq(0)';
NODE_NAME     U25 E71
 '@T6G_MB_LIB.T6G(SCH_1):PAGE14_I159@PURE_QUANTA.GENOA_SP5(CHIPS)':
 'MEA_DATA0': CDS_PINID='MEA_DATA0';
NODE_NAME     J21 7
 '@T6G_MB_LIB.T6G(SCH_1):PAGE89_I348@PURE_QUANTA.SCONN288_DDR506112002KQ(CHIPS)':
 'DQ0_A': CDS_PINID='DQ0_A';
NET_NAME
'M_E_CPU0_SA_DQ<10>'
 '@T6G_MB_LIB.T6G(SCH_1):M_E_CPU0_SA_DQ'<10>:
 C_SIGNAL='@t6g_mb_lib.t6g(sch_1):m_e_cpu0_sa_dq(10)';
NODE_NAME     U25 M70
 '@T6G_MB_LIB.T6G(SCH_1):PAGE14_I159@PURE_QUANTA.GENOA_SP5(CHIPS)':
 'MEA_DATA10': CDS_PINID='MEA_DATA10';
NODE_NAME     J21 163
 '@T6G_MB_LIB.T6G(SCH_1):PAGE89_I348@PURE_QUANTA.SCONN288_DDR506112002KQ(CHIPS)':
 'DQ10_A': CDS_PINID='DQ10_A';
NET_NAME
'M_E_CPU0_SA_DQ<11>'
 '@T6G_MB_LIB.T6G(SCH_1):M_E_CPU0_SA_DQ'<11>:
 C_SIGNAL='@t6g_mb_lib.t6g(sch_1):m_e_cpu0_sa_dq(11)';
NODE_NAME     U25 N69
 '@T6G_MB_LIB.T6G(SCH_1):PAGE14_I159@PURE_QUANTA.GENOA_SP5(CHIPS)':
 'MEA_DATA11': CDS_PINID='MEA_DATA11';
NODE_NAME     J21 165
 '@T6G_MB_LIB.T6G(SCH_1):PAGE89_I348@PURE_QUANTA.SCONN288_DDR506112002KQ(CHIPS)':
 'DQ11_A': CDS_PINID='DQ11_A';
NET_NAME
'M_E_CPU0_SA_DQ<12>'
 '@T6G_MB_LIB.T6G(SCH_1):M_E_CPU0_SA_DQ'<12>:
 C_SIGNAL='@t6g_mb_lib.t6g(sch_1):m_e_cpu0_sa_dq(12)';
NODE_NAME     U25 R71
 '@T6G_MB_LIB.T6G(SCH_1):PAGE14_I159@PURE_QUANTA.GENOA_SP5(CHIPS)':
 'MEA_DATA12': CDS_PINID='MEA_DATA12';
NODE_NAME     J21 25
 '@T6G_MB_LIB.T6G(SCH_1):PAGE89_I348@PURE_QUANTA.SCONN288_DDR506112002KQ(CHIPS)':
 'DQ12_A': CDS_PINID='DQ12_A';
NET_NAME
'M_E_CPU0_SA_DQ<13>'
 '@T6G_MB_LIB.T6G(SCH_1):M_E_CPU0_SA_DQ'<13>:
 C_SIGNAL='@t6g_mb_lib.t6g(sch_1):m_e_cpu0_sa_dq(13)';
NODE_NAME     U25 T69
 '@T6G_MB_LIB.T6G(SCH_1):PAGE14_I159@PURE_QUANTA.GENOA_SP5(CHIPS)':
 'MEA_DATA13': CDS_PINID='MEA_DATA13';
NODE_NAME     J21 27
 '@T6G_MB_LIB.T6G(SCH_1):PAGE89_I348@PURE_QUANTA.SCONN288_DDR506112002KQ(CHIPS)':
 'DQ13_A': CDS_PINID='DQ13_A';
NET_NAME
'M_E_CPU0_SA_DQ<14>'
 '@T6G_MB_LIB.T6G(SCH_1):M_E_CPU0_SA_DQ'<14>:
 C_SIGNAL='@t6g_mb_lib.t6g(sch_1):m_e_cpu0_sa_dq(14)';
NODE_NAME     U25 T70
 '@T6G_MB_LIB.T6G(SCH_1):PAGE14_I159@PURE_QUANTA.GENOA_SP5(CHIPS)':
 'MEA_DATA14': CDS_PINID='MEA_DATA14';
NODE_NAME     J21 170
 '@T6G_MB_LIB.T6G(SCH_1):PAGE89_I348@PURE_QUANTA.SCONN288_DDR506112002KQ(CHIPS)':
 'DQ14_A': CDS_PINID='DQ14_A';
NET_NAME
'M_E_CPU0_SA_DQ<15>'
 '@T6G_MB_LIB.T6G(SCH_1):M_E_CPU0_SA_DQ'<15>:
 C_SIGNAL='@t6g_mb_lib.t6g(sch_1):m_e_cpu0_sa_dq(15)';
NODE_NAME     U25 U69
 '@T6G_MB_LIB.T6G(SCH_1):PAGE14_I159@PURE_QUANTA.GENOA_SP5(CHIPS)':
 'MEA_DATA15': CDS_PINID='MEA_DATA15';
NODE_NAME     J21 172
 '@T6G_MB_LIB.T6G(SCH_1):PAGE89_I348@PURE_QUANTA.SCONN288_DDR506112002KQ(CHIPS)':
 'DQ15_A': CDS_PINID='DQ15_A';
NET_NAME
'M_E_CPU0_SA_DQ<16>'
 '@T6G_MB_LIB.T6G(SCH_1):M_E_CPU0_SA_DQ'<16>:
 C_SIGNAL='@t6g_mb_lib.t6g(sch_1):m_e_cpu0_sa_dq(16)';
NODE_NAME     U25 U71
 '@T6G_MB_LIB.T6G(SCH_1):PAGE14_I159@PURE_QUANTA.GENOA_SP5(CHIPS)':
 'MEA_DATA16': CDS_PINID='MEA_DATA16';
NODE_NAME     J21 29
 '@T6G_MB_LIB.T6G(SCH_1):PAGE89_I348@PURE_QUANTA.SCONN288_DDR506112002KQ(CHIPS)':
 'DQ16_A': CDS_PINID='DQ16_A';
NET_NAME
'M_E_CPU0_SA_DQ<17>'
 '@T6G_MB_LIB.T6G(SCH_1):M_E_CPU0_SA_DQ'<17>:
 C_SIGNAL='@t6g_mb_lib.t6g(sch_1):m_e_cpu0_sa_dq(17)';
NODE_NAME     U25 V69
 '@T6G_MB_LIB.T6G(SCH_1):PAGE14_I159@PURE_QUANTA.GENOA_SP5(CHIPS)':
 'MEA_DATA17': CDS_PINID='MEA_DATA17';
NODE_NAME     J21 31
 '@T6G_MB_LIB.T6G(SCH_1):PAGE89_I348@PURE_QUANTA.SCONN288_DDR506112002KQ(CHIPS)':
 'DQ17_A': CDS_PINID='DQ17_A';
NET_NAME
'M_E_CPU0_SA_DQ<18>'
 '@T6G_MB_LIB.T6G(SCH_1):M_E_CPU0_SA_DQ'<18>:
 C_SIGNAL='@t6g_mb_lib.t6g(sch_1):m_e_cpu0_sa_dq(18)';
NODE_NAME     U25 V70
 '@T6G_MB_LIB.T6G(SCH_1):PAGE14_I159@PURE_QUANTA.GENOA_SP5(CHIPS)':
 'MEA_DATA18': CDS_PINID='MEA_DATA18';
NODE_NAME     J21 174
 '@T6G_MB_LIB.T6G(SCH_1):PAGE89_I348@PURE_QUANTA.SCONN288_DDR506112002KQ(CHIPS)':
 'DQ18_A': CDS_PINID='DQ18_A';
NET_NAME
'M_E_CPU0_SA_DQ<19>'
 '@T6G_MB_LIB.T6G(SCH_1):M_E_CPU0_SA_DQ'<19>:
 C_SIGNAL='@t6g_mb_lib.t6g(sch_1):m_e_cpu0_sa_dq(19)';
NODE_NAME     U25 W69
 '@T6G_MB_LIB.T6G(SCH_1):PAGE14_I159@PURE_QUANTA.GENOA_SP5(CHIPS)':
 'MEA_DATA19': CDS_PINID='MEA_DATA19';
NODE_NAME     J21 176
 '@T6G_MB_LIB.T6G(SCH_1):PAGE89_I348@PURE_QUANTA.SCONN288_DDR506112002KQ(CHIPS)':
 'DQ19_A': CDS_PINID='DQ19_A';
NET_NAME
'M_E_CPU0_SA_DQ<1>'
 '@T6G_MB_LIB.T6G(SCH_1):M_E_CPU0_SA_DQ'<1>:
 C_SIGNAL='@t6g_mb_lib.t6g(sch_1):m_e_cpu0_sa_dq(1)';
NODE_NAME     U25 F69
 '@T6G_MB_LIB.T6G(SCH_1):PAGE14_I159@PURE_QUANTA.GENOA_SP5(CHIPS)':
 'MEA_DATA1': CDS_PINID='MEA_DATA1';
NODE_NAME     J21 9
 '@T6G_MB_LIB.T6G(SCH_1):PAGE89_I348@PURE_QUANTA.SCONN288_DDR506112002KQ(CHIPS)':
 'DQ1_A': CDS_PINID='DQ1_A';
NET_NAME
'M_E_CPU0_SA_DQ<20>'
 '@T6G_MB_LIB.T6G(SCH_1):M_E_CPU0_SA_DQ'<20>:
 C_SIGNAL='@t6g_mb_lib.t6g(sch_1):m_e_cpu0_sa_dq(20)';
NODE_NAME     U25 AA71
 '@T6G_MB_LIB.T6G(SCH_1):PAGE14_I159@PURE_QUANTA.GENOA_SP5(CHIPS)':
 'MEA_DATA20': CDS_PINID='MEA_DATA20';
NODE_NAME     J21 36
 '@T6G_MB_LIB.T6G(SCH_1):PAGE89_I348@PURE_QUANTA.SCONN288_DDR506112002KQ(CHIPS)':
 'DQ20_A': CDS_PINID='DQ20_A';
NET_NAME
'M_E_CPU0_SA_DQ<21>'
 '@T6G_MB_LIB.T6G(SCH_1):M_E_CPU0_SA_DQ'<21>:
 C_SIGNAL='@t6g_mb_lib.t6g(sch_1):m_e_cpu0_sa_dq(21)';
NODE_NAME     U25 AB69
 '@T6G_MB_LIB.T6G(SCH_1):PAGE14_I159@PURE_QUANTA.GENOA_SP5(CHIPS)':
 'MEA_DATA21': CDS_PINID='MEA_DATA21';
NODE_NAME     J21 38
 '@T6G_MB_LIB.T6G(SCH_1):PAGE89_I348@PURE_QUANTA.SCONN288_DDR506112002KQ(CHIPS)':
 'DQ21_A': CDS_PINID='DQ21_A';
NET_NAME
'M_E_CPU0_SA_DQ<22>'
 '@T6G_MB_LIB.T6G(SCH_1):M_E_CPU0_SA_DQ'<22>:
 C_SIGNAL='@t6g_mb_lib.t6g(sch_1):m_e_cpu0_sa_dq(22)';
NODE_NAME     U25 AB70
 '@T6G_MB_LIB.T6G(SCH_1):PAGE14_I159@PURE_QUANTA.GENOA_SP5(CHIPS)':
 'MEA_DATA22': CDS_PINID='MEA_DATA22';
NODE_NAME     J21 181
 '@T6G_MB_LIB.T6G(SCH_1):PAGE89_I348@PURE_QUANTA.SCONN288_DDR506112002KQ(CHIPS)':
 'DQ22_A': CDS_PINID='DQ22_A';
NET_NAME
'M_E_CPU0_SA_DQ<23>'
 '@T6G_MB_LIB.T6G(SCH_1):M_E_CPU0_SA_DQ'<23>:
 C_SIGNAL='@t6g_mb_lib.t6g(sch_1):m_e_cpu0_sa_dq(23)';
NODE_NAME     U25 AC69
 '@T6G_MB_LIB.T6G(SCH_1):PAGE14_I159@PURE_QUANTA.GENOA_SP5(CHIPS)':
 'MEA_DATA23': CDS_PINID='MEA_DATA23';
NODE_NAME     J21 183
 '@T6G_MB_LIB.T6G(SCH_1):PAGE89_I348@PURE_QUANTA.SCONN288_DDR506112002KQ(CHIPS)':
 'DQ23_A': CDS_PINID='DQ23_A';
NET_NAME
'M_E_CPU0_SA_DQ<24>'
 '@T6G_MB_LIB.T6G(SCH_1):M_E_CPU0_SA_DQ'<24>:
 C_SIGNAL='@t6g_mb_lib.t6g(sch_1):m_e_cpu0_sa_dq(24)';
NODE_NAME     U25 AC71
 '@T6G_MB_LIB.T6G(SCH_1):PAGE14_I159@PURE_QUANTA.GENOA_SP5(CHIPS)':
 'MEA_DATA24': CDS_PINID='MEA_DATA24';
NODE_NAME     J21 40
 '@T6G_MB_LIB.T6G(SCH_1):PAGE89_I348@PURE_QUANTA.SCONN288_DDR506112002KQ(CHIPS)':
 'DQ24_A': CDS_PINID='DQ24_A';
NET_NAME
'M_E_CPU0_SA_DQ<25>'
 '@T6G_MB_LIB.T6G(SCH_1):M_E_CPU0_SA_DQ'<25>:
 C_SIGNAL='@t6g_mb_lib.t6g(sch_1):m_e_cpu0_sa_dq(25)';
NODE_NAME     U25 AD69
 '@T6G_MB_LIB.T6G(SCH_1):PAGE14_I159@PURE_QUANTA.GENOA_SP5(CHIPS)':
 'MEA_DATA25': CDS_PINID='MEA_DATA25';
NODE_NAME     J21 42
 '@T6G_MB_LIB.T6G(SCH_1):PAGE89_I348@PURE_QUANTA.SCONN288_DDR506112002KQ(CHIPS)':
 'DQ25_A': CDS_PINID='DQ25_A';
NET_NAME
'M_E_CPU0_SA_DQ<26>'
 '@T6G_MB_LIB.T6G(SCH_1):M_E_CPU0_SA_DQ'<26>:
 C_SIGNAL='@t6g_mb_lib.t6g(sch_1):m_e_cpu0_sa_dq(26)';
NODE_NAME     U25 AD70
 '@T6G_MB_LIB.T6G(SCH_1):PAGE14_I159@PURE_QUANTA.GENOA_SP5(CHIPS)':
 'MEA_DATA26': CDS_PINID='MEA_DATA26';
NODE_NAME     J21 185
 '@T6G_MB_LIB.T6G(SCH_1):PAGE89_I348@PURE_QUANTA.SCONN288_DDR506112002KQ(CHIPS)':
 'DQ26_A': CDS_PINID='DQ26_A';
NET_NAME
'M_E_CPU0_SA_DQ<27>'
 '@T6G_MB_LIB.T6G(SCH_1):M_E_CPU0_SA_DQ'<27>:
 C_SIGNAL='@t6g_mb_lib.t6g(sch_1):m_e_cpu0_sa_dq(27)';
NODE_NAME     U25 AE69
 '@T6G_MB_LIB.T6G(SCH_1):PAGE14_I159@PURE_QUANTA.GENOA_SP5(CHIPS)':
 'MEA_DATA27': CDS_PINID='MEA_DATA27';
NODE_NAME     J21 187
 '@T6G_MB_LIB.T6G(SCH_1):PAGE89_I348@PURE_QUANTA.SCONN288_DDR506112002KQ(CHIPS)':
 'DQ27_A': CDS_PINID='DQ27_A';
NET_NAME
'M_E_CPU0_SA_DQ<28>'
 '@T6G_MB_LIB.T6G(SCH_1):M_E_CPU0_SA_DQ'<28>:
 C_SIGNAL='@t6g_mb_lib.t6g(sch_1):m_e_cpu0_sa_dq(28)';
NODE_NAME     U25 AG71
 '@T6G_MB_LIB.T6G(SCH_1):PAGE14_I159@PURE_QUANTA.GENOA_SP5(CHIPS)':
 'MEA_DATA28': CDS_PINID='MEA_DATA28';
NODE_NAME     J21 47
 '@T6G_MB_LIB.T6G(SCH_1):PAGE89_I348@PURE_QUANTA.SCONN288_DDR506112002KQ(CHIPS)':
 'DQ28_A': CDS_PINID='DQ28_A';
NET_NAME
'M_E_CPU0_SA_DQ<29>'
 '@T6G_MB_LIB.T6G(SCH_1):M_E_CPU0_SA_DQ'<29>:
 C_SIGNAL='@t6g_mb_lib.t6g(sch_1):m_e_cpu0_sa_dq(29)';
NODE_NAME     U25 AH69
 '@T6G_MB_LIB.T6G(SCH_1):PAGE14_I159@PURE_QUANTA.GENOA_SP5(CHIPS)':
 'MEA_DATA29': CDS_PINID='MEA_DATA29';
NODE_NAME     J21 49
 '@T6G_MB_LIB.T6G(SCH_1):PAGE89_I348@PURE_QUANTA.SCONN288_DDR506112002KQ(CHIPS)':
 'DQ29_A': CDS_PINID='DQ29_A';
NET_NAME
'M_E_CPU0_SA_DQ<2>'
 '@T6G_MB_LIB.T6G(SCH_1):M_E_CPU0_SA_DQ'<2>:
 C_SIGNAL='@t6g_mb_lib.t6g(sch_1):m_e_cpu0_sa_dq(2)';
NODE_NAME     U25 F70
 '@T6G_MB_LIB.T6G(SCH_1):PAGE14_I159@PURE_QUANTA.GENOA_SP5(CHIPS)':
 'MEA_DATA2': CDS_PINID='MEA_DATA2';
NODE_NAME     J21 152
 '@T6G_MB_LIB.T6G(SCH_1):PAGE89_I348@PURE_QUANTA.SCONN288_DDR506112002KQ(CHIPS)':
 'DQ2_A': CDS_PINID='DQ2_A';
NET_NAME
'M_E_CPU0_SA_DQ<30>'
 '@T6G_MB_LIB.T6G(SCH_1):M_E_CPU0_SA_DQ'<30>:
 C_SIGNAL='@t6g_mb_lib.t6g(sch_1):m_e_cpu0_sa_dq(30)';
NODE_NAME     U25 AH70
 '@T6G_MB_LIB.T6G(SCH_1):PAGE14_I159@PURE_QUANTA.GENOA_SP5(CHIPS)':
 'MEA_DATA30': CDS_PINID='MEA_DATA30';
NODE_NAME     J21 192
 '@T6G_MB_LIB.T6G(SCH_1):PAGE89_I348@PURE_QUANTA.SCONN288_DDR506112002KQ(CHIPS)':
 'DQ30_A': CDS_PINID='DQ30_A';
NET_NAME
'M_E_CPU0_SA_DQ<31>'
 '@T6G_MB_LIB.T6G(SCH_1):M_E_CPU0_SA_DQ'<31>:
 C_SIGNAL='@t6g_mb_lib.t6g(sch_1):m_e_cpu0_sa_dq(31)';
NODE_NAME     U25 AJ69
 '@T6G_MB_LIB.T6G(SCH_1):PAGE14_I159@PURE_QUANTA.GENOA_SP5(CHIPS)':
 'MEA_DATA31': CDS_PINID='MEA_DATA31';
NODE_NAME     J21 194
 '@T6G_MB_LIB.T6G(SCH_1):PAGE89_I348@PURE_QUANTA.SCONN288_DDR506112002KQ(CHIPS)':
 'DQ31_A': CDS_PINID='DQ31_A';
NET_NAME
'M_E_CPU0_SA_DQ<3>'
 '@T6G_MB_LIB.T6G(SCH_1):M_E_CPU0_SA_DQ'<3>:
 C_SIGNAL='@t6g_mb_lib.t6g(sch_1):m_e_cpu0_sa_dq(3)';
NODE_NAME     U25 G69
 '@T6G_MB_LIB.T6G(SCH_1):PAGE14_I159@PURE_QUANTA.GENOA_SP5(CHIPS)':
 'MEA_DATA3': CDS_PINID='MEA_DATA3';
NODE_NAME     J21 154
 '@T6G_MB_LIB.T6G(SCH_1):PAGE89_I348@PURE_QUANTA.SCONN288_DDR506112002KQ(CHIPS)':
 'DQ3_A': CDS_PINID='DQ3_A';
NET_NAME
'M_E_CPU0_SA_DQ<4>'
 '@T6G_MB_LIB.T6G(SCH_1):M_E_CPU0_SA_DQ'<4>:
 C_SIGNAL='@t6g_mb_lib.t6g(sch_1):m_e_cpu0_sa_dq(4)';
NODE_NAME     U25 J71
 '@T6G_MB_LIB.T6G(SCH_1):PAGE14_I159@PURE_QUANTA.GENOA_SP5(CHIPS)':
 'MEA_DATA4': CDS_PINID='MEA_DATA4';
NODE_NAME     J21 14
 '@T6G_MB_LIB.T6G(SCH_1):PAGE89_I348@PURE_QUANTA.SCONN288_DDR506112002KQ(CHIPS)':
 'DQ4_A': CDS_PINID='DQ4_A';
NET_NAME
'M_E_CPU0_SA_DQ<5>'
 '@T6G_MB_LIB.T6G(SCH_1):M_E_CPU0_SA_DQ'<5>:
 C_SIGNAL='@t6g_mb_lib.t6g(sch_1):m_e_cpu0_sa_dq(5)';
NODE_NAME     U25 K69
 '@T6G_MB_LIB.T6G(SCH_1):PAGE14_I159@PURE_QUANTA.GENOA_SP5(CHIPS)':
 'MEA_DATA5': CDS_PINID='MEA_DATA5';
NODE_NAME     J21 16
 '@T6G_MB_LIB.T6G(SCH_1):PAGE89_I348@PURE_QUANTA.SCONN288_DDR506112002KQ(CHIPS)':
 'DQ5_A': CDS_PINID='DQ5_A';
NET_NAME
'M_E_CPU0_SA_DQ<6>'
 '@T6G_MB_LIB.T6G(SCH_1):M_E_CPU0_SA_DQ'<6>:
 C_SIGNAL='@t6g_mb_lib.t6g(sch_1):m_e_cpu0_sa_dq(6)';
NODE_NAME     U25 K70
 '@T6G_MB_LIB.T6G(SCH_1):PAGE14_I159@PURE_QUANTA.GENOA_SP5(CHIPS)':
 'MEA_DATA6': CDS_PINID='MEA_DATA6';
NODE_NAME     J21 159
 '@T6G_MB_LIB.T6G(SCH_1):PAGE89_I348@PURE_QUANTA.SCONN288_DDR506112002KQ(CHIPS)':
 'DQ6_A': CDS_PINID='DQ6_A';
NET_NAME
'M_E_CPU0_SA_DQ<7>'
 '@T6G_MB_LIB.T6G(SCH_1):M_E_CPU0_SA_DQ'<7>:
 C_SIGNAL='@t6g_mb_lib.t6g(sch_1):m_e_cpu0_sa_dq(7)';
NODE_NAME     U25 L69
 '@T6G_MB_LIB.T6G(SCH_1):PAGE14_I159@PURE_QUANTA.GENOA_SP5(CHIPS)':
 'MEA_DATA7': CDS_PINID='MEA_DATA7';
NODE_NAME     J21 161
 '@T6G_MB_LIB.T6G(SCH_1):PAGE89_I348@PURE_QUANTA.SCONN288_DDR506112002KQ(CHIPS)':
 'DQ7_A': CDS_PINID='DQ7_A';
NET_NAME
'M_E_CPU0_SA_DQ<8>'
 '@T6G_MB_LIB.T6G(SCH_1):M_E_CPU0_SA_DQ'<8>:
 C_SIGNAL='@t6g_mb_lib.t6g(sch_1):m_e_cpu0_sa_dq(8)';
NODE_NAME     U25 L71
 '@T6G_MB_LIB.T6G(SCH_1):PAGE14_I159@PURE_QUANTA.GENOA_SP5(CHIPS)':
 'MEA_DATA8': CDS_PINID='MEA_DATA8';
NODE_NAME     J21 18
 '@T6G_MB_LIB.T6G(SCH_1):PAGE89_I348@PURE_QUANTA.SCONN288_DDR506112002KQ(CHIPS)':
 'DQ8_A': CDS_PINID='DQ8_A';
NET_NAME
'M_E_CPU0_SA_DQ<9>'
 '@T6G_MB_LIB.T6G(SCH_1):M_E_CPU0_SA_DQ'<9>:
 C_SIGNAL='@t6g_mb_lib.t6g(sch_1):m_e_cpu0_sa_dq(9)';
NODE_NAME     U25 M69
 '@T6G_MB_LIB.T6G(SCH_1):PAGE14_I159@PURE_QUANTA.GENOA_SP5(CHIPS)':
 'MEA_DATA9': CDS_PINID='MEA_DATA9';
NODE_NAME     J21 20
 '@T6G_MB_LIB.T6G(SCH_1):PAGE89_I348@PURE_QUANTA.SCONN288_DDR506112002KQ(CHIPS)':
 'DQ9_A': CDS_PINID='DQ9_A';
NET_NAME
'M_E_CPU0_SA_DQS_DN<0>'
 '@T6G_MB_LIB.T6G(SCH_1):M_E_CPU0_SA_DQS_DN'<0>:
 C_SIGNAL='@t6g_mb_lib.t6g(sch_1):m_e_cpu0_sa_dqs_dn(0)';
NODE_NAME     U25 H70
 '@T6G_MB_LIB.T6G(SCH_1):PAGE14_I159@PURE_QUANTA.GENOA_SP5(CHIPS)':
 'MEA_DQS_L0': CDS_PINID='MEA_DQS_L0';
NODE_NAME     J21 12
 '@T6G_MB_LIB.T6G(SCH_1):PAGE89_I410@PURE_QUANTA.SCONN288_DDR506112002KQ(CHIPS)':
 'DQS0_A_C': CDS_PINID='DQS0_A_C';
NET_NAME
'M_E_CPU0_SA_DQS_DN<1>'
 '@T6G_MB_LIB.T6G(SCH_1):M_E_CPU0_SA_DQS_DN'<1>:
 C_SIGNAL='@t6g_mb_lib.t6g(sch_1):m_e_cpu0_sa_dqs_dn(1)';
NODE_NAME     U25 P70
 '@T6G_MB_LIB.T6G(SCH_1):PAGE14_I159@PURE_QUANTA.GENOA_SP5(CHIPS)':
 'MEA_DQS_L1': CDS_PINID='MEA_DQS_L1';
NODE_NAME     J21 23
 '@T6G_MB_LIB.T6G(SCH_1):PAGE89_I410@PURE_QUANTA.SCONN288_DDR506112002KQ(CHIPS)':
 'DQS1_A_C': CDS_PINID='DQS1_A_C';
NET_NAME
'M_E_CPU0_SA_DQS_DN<2>'
 '@T6G_MB_LIB.T6G(SCH_1):M_E_CPU0_SA_DQS_DN'<2>:
 C_SIGNAL='@t6g_mb_lib.t6g(sch_1):m_e_cpu0_sa_dqs_dn(2)';
NODE_NAME     U25 Y70
 '@T6G_MB_LIB.T6G(SCH_1):PAGE14_I159@PURE_QUANTA.GENOA_SP5(CHIPS)':
 'MEA_DQS_L2': CDS_PINID='MEA_DQS_L2';
NODE_NAME     J21 34
 '@T6G_MB_LIB.T6G(SCH_1):PAGE89_I410@PURE_QUANTA.SCONN288_DDR506112002KQ(CHIPS)':
 'DQS2_A_C': CDS_PINID='DQS2_A_C';
NET_NAME
'M_E_CPU0_SA_DQS_DN<3>'
 '@T6G_MB_LIB.T6G(SCH_1):M_E_CPU0_SA_DQS_DN'<3>:
 C_SIGNAL='@t6g_mb_lib.t6g(sch_1):m_e_cpu0_sa_dqs_dn(3)';
NODE_NAME     U25 AF70
 '@T6G_MB_LIB.T6G(SCH_1):PAGE14_I159@PURE_QUANTA.GENOA_SP5(CHIPS)':
 'MEA_DQS_L3': CDS_PINID='MEA_DQS_L3';
NODE_NAME     J21 45
 '@T6G_MB_LIB.T6G(SCH_1):PAGE89_I410@PURE_QUANTA.SCONN288_DDR506112002KQ(CHIPS)':
 'DQS3_A_C': CDS_PINID='DQS3_A_C';
NET_NAME
'M_E_CPU0_SA_DQS_DN<4>'
 '@T6G_MB_LIB.T6G(SCH_1):M_E_CPU0_SA_DQS_DN'<4>:
 C_SIGNAL='@t6g_mb_lib.t6g(sch_1):m_e_cpu0_sa_dqs_dn(4)';
NODE_NAME     U25 AM70
 '@T6G_MB_LIB.T6G(SCH_1):PAGE14_I159@PURE_QUANTA.GENOA_SP5(CHIPS)':
 'MEA_DQS_L4': CDS_PINID='MEA_DQS_L4';
NODE_NAME     J21 56
 '@T6G_MB_LIB.T6G(SCH_1):PAGE89_I410@PURE_QUANTA.SCONN288_DDR506112002KQ(CHIPS)':
 'DQS4_A_C': CDS_PINID='DQS4_A_C';
NET_NAME
'M_E_CPU0_SA_DQS_DN<5>'
 '@T6G_MB_LIB.T6G(SCH_1):M_E_CPU0_SA_DQS_DN'<5>:
 C_SIGNAL='@t6g_mb_lib.t6g(sch_1):m_e_cpu0_sa_dqs_dn(5)';
NODE_NAME     U25 H69
 '@T6G_MB_LIB.T6G(SCH_1):PAGE14_I159@PURE_QUANTA.GENOA_SP5(CHIPS)':
 'MEA_DQS_L5': CDS_PINID='MEA_DQS_L5';
NODE_NAME     J21 156
 '@T6G_MB_LIB.T6G(SCH_1):PAGE89_I410@PURE_QUANTA.SCONN288_DDR506112002KQ(CHIPS)':
 'DQS5_A_C||TDQS5_A_C||DQS5_A_T||TDQS5_A_T': CDS_PINID='\dqs5_a_c||tdqs5_a_c||dqs5_a_t||tdqs5_a_t\';
NET_NAME
'M_E_CPU0_SA_DQS_DN<6>'
 '@T6G_MB_LIB.T6G(SCH_1):M_E_CPU0_SA_DQS_DN'<6>:
 C_SIGNAL='@t6g_mb_lib.t6g(sch_1):m_e_cpu0_sa_dqs_dn(6)';
NODE_NAME     U25 P69
 '@T6G_MB_LIB.T6G(SCH_1):PAGE14_I159@PURE_QUANTA.GENOA_SP5(CHIPS)':
 'MEA_DQS_L6': CDS_PINID='MEA_DQS_L6';
NODE_NAME     J21 167
 '@T6G_MB_LIB.T6G(SCH_1):PAGE89_I410@PURE_QUANTA.SCONN288_DDR506112002KQ(CHIPS)':
 'DQS6_A_C||TDQS6_A_C||DQS6_A_T||TDQS6_A_T': CDS_PINID='\dqs6_a_c||tdqs6_a_c||dqs6_a_t||tdqs6_a_t\';
NET_NAME
'M_E_CPU0_SA_DQS_DN<7>'
 '@T6G_MB_LIB.T6G(SCH_1):M_E_CPU0_SA_DQS_DN'<7>:
 C_SIGNAL='@t6g_mb_lib.t6g(sch_1):m_e_cpu0_sa_dqs_dn(7)';
NODE_NAME     U25 Y69
 '@T6G_MB_LIB.T6G(SCH_1):PAGE14_I159@PURE_QUANTA.GENOA_SP5(CHIPS)':
 'MEA_DQS_L7': CDS_PINID='MEA_DQS_L7';
NODE_NAME     J21 178
 '@T6G_MB_LIB.T6G(SCH_1):PAGE89_I410@PURE_QUANTA.SCONN288_DDR506112002KQ(CHIPS)':
 'DQS7_A_C||TDQS7_A_C': CDS_PINID='\dqs7_a_c||tdqs7_a_c\';
NET_NAME
'M_E_CPU0_SA_DQS_DN<8>'
 '@T6G_MB_LIB.T6G(SCH_1):M_E_CPU0_SA_DQS_DN'<8>:
 C_SIGNAL='@t6g_mb_lib.t6g(sch_1):m_e_cpu0_sa_dqs_dn(8)';
NODE_NAME     U25 AF69
 '@T6G_MB_LIB.T6G(SCH_1):PAGE14_I159@PURE_QUANTA.GENOA_SP5(CHIPS)':
 'MEA_DQS_L8': CDS_PINID='MEA_DQS_L8';
NODE_NAME     J21 189
 '@T6G_MB_LIB.T6G(SCH_1):PAGE89_I410@PURE_QUANTA.SCONN288_DDR506112002KQ(CHIPS)':
 'DQS8_A_C||TDQS8_A_C': CDS_PINID='\dqs8_a_c||tdqs8_a_c\';
NET_NAME
'M_E_CPU0_SA_DQS_DN<9>'
 '@T6G_MB_LIB.T6G(SCH_1):M_E_CPU0_SA_DQS_DN'<9>:
 C_SIGNAL='@t6g_mb_lib.t6g(sch_1):m_e_cpu0_sa_dqs_dn(9)';
NODE_NAME     U25 AM69
 '@T6G_MB_LIB.T6G(SCH_1):PAGE14_I159@PURE_QUANTA.GENOA_SP5(CHIPS)':
 'MEA_DQS_L9': CDS_PINID='MEA_DQS_L9';
NODE_NAME     J21 200
 '@T6G_MB_LIB.T6G(SCH_1):PAGE89_I410@PURE_QUANTA.SCONN288_DDR506112002KQ(CHIPS)':
 'DQS9_A_C||TDQS9_A_C': CDS_PINID='\dqs9_a_c||tdqs9_a_c\';
NET_NAME
'M_E_CPU0_SA_DQS_DP<0>'
 '@T6G_MB_LIB.T6G(SCH_1):M_E_CPU0_SA_DQS_DP'<0>:
 C_SIGNAL='@t6g_mb_lib.t6g(sch_1):m_e_cpu0_sa_dqs_dp(0)';
NODE_NAME     U25 G71
 '@T6G_MB_LIB.T6G(SCH_1):PAGE14_I159@PURE_QUANTA.GENOA_SP5(CHIPS)':
 'MEA_DQS_H0': CDS_PINID='MEA_DQS_H0';
NODE_NAME     J21 11
 '@T6G_MB_LIB.T6G(SCH_1):PAGE89_I410@PURE_QUANTA.SCONN288_DDR506112002KQ(CHIPS)':
 'DQS0_A_T': CDS_PINID='DQS0_A_T';
NET_NAME
'M_E_CPU0_SA_DQS_DP<1>'
 '@T6G_MB_LIB.T6G(SCH_1):M_E_CPU0_SA_DQS_DP'<1>:
 C_SIGNAL='@t6g_mb_lib.t6g(sch_1):m_e_cpu0_sa_dqs_dp(1)';
NODE_NAME     U25 N71
 '@T6G_MB_LIB.T6G(SCH_1):PAGE14_I159@PURE_QUANTA.GENOA_SP5(CHIPS)':
 'MEA_DQS_H1': CDS_PINID='MEA_DQS_H1';
NODE_NAME     J21 22
 '@T6G_MB_LIB.T6G(SCH_1):PAGE89_I410@PURE_QUANTA.SCONN288_DDR506112002KQ(CHIPS)':
 'DQS1_A_T': CDS_PINID='DQS1_A_T';
NET_NAME
'M_E_CPU0_SA_DQS_DP<2>'
 '@T6G_MB_LIB.T6G(SCH_1):M_E_CPU0_SA_DQS_DP'<2>:
 C_SIGNAL='@t6g_mb_lib.t6g(sch_1):m_e_cpu0_sa_dqs_dp(2)';
NODE_NAME     U25 W71
 '@T6G_MB_LIB.T6G(SCH_1):PAGE14_I159@PURE_QUANTA.GENOA_SP5(CHIPS)':
 'MEA_DQS_H2': CDS_PINID='MEA_DQS_H2';
NODE_NAME     J21 33
 '@T6G_MB_LIB.T6G(SCH_1):PAGE89_I410@PURE_QUANTA.SCONN288_DDR506112002KQ(CHIPS)':
 'DQS2_A_T': CDS_PINID='DQS2_A_T';
NET_NAME
'M_E_CPU0_SA_DQS_DP<3>'
 '@T6G_MB_LIB.T6G(SCH_1):M_E_CPU0_SA_DQS_DP'<3>:
 C_SIGNAL='@t6g_mb_lib.t6g(sch_1):m_e_cpu0_sa_dqs_dp(3)';
NODE_NAME     U25 AE71
 '@T6G_MB_LIB.T6G(SCH_1):PAGE14_I159@PURE_QUANTA.GENOA_SP5(CHIPS)':
 'MEA_DQS_H3': CDS_PINID='MEA_DQS_H3';
NODE_NAME     J21 44
 '@T6G_MB_LIB.T6G(SCH_1):PAGE89_I410@PURE_QUANTA.SCONN288_DDR506112002KQ(CHIPS)':
 'DQS3_A_T': CDS_PINID='DQS3_A_T';
NET_NAME
'M_E_CPU0_SA_DQS_DP<4>'
 '@T6G_MB_LIB.T6G(SCH_1):M_E_CPU0_SA_DQS_DP'<4>:
 C_SIGNAL='@t6g_mb_lib.t6g(sch_1):m_e_cpu0_sa_dqs_dp(4)';
NODE_NAME     U25 AL71
 '@T6G_MB_LIB.T6G(SCH_1):PAGE14_I159@PURE_QUANTA.GENOA_SP5(CHIPS)':
 'MEA_DQS_H4': CDS_PINID='MEA_DQS_H4';
NODE_NAME     J21 55
 '@T6G_MB_LIB.T6G(SCH_1):PAGE89_I410@PURE_QUANTA.SCONN288_DDR506112002KQ(CHIPS)':
 'DQS4_A_T': CDS_PINID='DQS4_A_T';
NET_NAME
'M_E_CPU0_SA_DQS_DP<5>'
 '@T6G_MB_LIB.T6G(SCH_1):M_E_CPU0_SA_DQS_DP'<5>:
 C_SIGNAL='@t6g_mb_lib.t6g(sch_1):m_e_cpu0_sa_dqs_dp(5)';
NODE_NAME     U25 J69
 '@T6G_MB_LIB.T6G(SCH_1):PAGE14_I159@PURE_QUANTA.GENOA_SP5(CHIPS)':
 'MEA_DQS_H5': CDS_PINID='MEA_DQS_H5';
NODE_NAME     J21 157
 '@T6G_MB_LIB.T6G(SCH_1):PAGE89_I410@PURE_QUANTA.SCONN288_DDR506112002KQ(CHIPS)':
 'DQS5_A_T||TDQS5_A_T': CDS_PINID='\dqs5_a_t||tdqs5_a_t\';
NET_NAME
'M_E_CPU0_SA_DQS_DP<6>'
 '@T6G_MB_LIB.T6G(SCH_1):M_E_CPU0_SA_DQS_DP'<6>:
 C_SIGNAL='@t6g_mb_lib.t6g(sch_1):m_e_cpu0_sa_dqs_dp(6)';
NODE_NAME     U25 R69
 '@T6G_MB_LIB.T6G(SCH_1):PAGE14_I159@PURE_QUANTA.GENOA_SP5(CHIPS)':
 'MEA_DQS_H6': CDS_PINID='MEA_DQS_H6';
NODE_NAME     J21 168
 '@T6G_MB_LIB.T6G(SCH_1):PAGE89_I410@PURE_QUANTA.SCONN288_DDR506112002KQ(CHIPS)':
 'DQS6_A_T||TDQS6_A_T': CDS_PINID='\dqs6_a_t||tdqs6_a_t\';
NET_NAME
'M_E_CPU0_SA_DQS_DP<7>'
 '@T6G_MB_LIB.T6G(SCH_1):M_E_CPU0_SA_DQS_DP'<7>:
 C_SIGNAL='@t6g_mb_lib.t6g(sch_1):m_e_cpu0_sa_dqs_dp(7)';
NODE_NAME     U25 AA69
 '@T6G_MB_LIB.T6G(SCH_1):PAGE14_I159@PURE_QUANTA.GENOA_SP5(CHIPS)':
 'MEA_DQS_H7': CDS_PINID='MEA_DQS_H7';
NODE_NAME     J21 179
 '@T6G_MB_LIB.T6G(SCH_1):PAGE89_I410@PURE_QUANTA.SCONN288_DDR506112002KQ(CHIPS)':
 'DQS7_A_T||TDQS7_A_T': CDS_PINID='\dqs7_a_t||tdqs7_a_t\';
NET_NAME
'M_E_CPU0_SA_DQS_DP<8>'
 '@T6G_MB_LIB.T6G(SCH_1):M_E_CPU0_SA_DQS_DP'<8>:
 C_SIGNAL='@t6g_mb_lib.t6g(sch_1):m_e_cpu0_sa_dqs_dp(8)';
NODE_NAME     U25 AG69
 '@T6G_MB_LIB.T6G(SCH_1):PAGE14_I159@PURE_QUANTA.GENOA_SP5(CHIPS)':
 'MEA_DQS_H8': CDS_PINID='MEA_DQS_H8';
NODE_NAME     J21 190
 '@T6G_MB_LIB.T6G(SCH_1):PAGE89_I410@PURE_QUANTA.SCONN288_DDR506112002KQ(CHIPS)':
 'DQS8_A_T||TDQS8_A_T': CDS_PINID='\dqs8_a_t||tdqs8_a_t\';
NET_NAME
'M_E_CPU0_SA_DQS_DP<9>'
 '@T6G_MB_LIB.T6G(SCH_1):M_E_CPU0_SA_DQS_DP'<9>:
 C_SIGNAL='@t6g_mb_lib.t6g(sch_1):m_e_cpu0_sa_dqs_dp(9)';
NODE_NAME     U25 AN69
 '@T6G_MB_LIB.T6G(SCH_1):PAGE14_I159@PURE_QUANTA.GENOA_SP5(CHIPS)':
 'MEA_DQS_H9': CDS_PINID='MEA_DQS_H9';
NODE_NAME     J21 201
 '@T6G_MB_LIB.T6G(SCH_1):PAGE89_I410@PURE_QUANTA.SCONN288_DDR506112002KQ(CHIPS)':
 'DQS9_A_T||TDQS9_A_T': CDS_PINID='\dqs9_a_t||tdqs9_a_t\';
NET_NAME
'M_E_CPU0_SA_PAR'
 '@T6G_MB_LIB.T6G(SCH_1):M_E_CPU0_SA_PAR':
 C_SIGNAL='@t6g_mb_lib.t6g(sch_1):m_e_cpu0_sa_par';
NODE_NAME     U25 BC69
 '@T6G_MB_LIB.T6G(SCH_1):PAGE14_I159@PURE_QUANTA.GENOA_SP5(CHIPS)':
 'MEA_PAR': CDS_PINID='MEA_PAR';
NODE_NAME     J21 74
 '@T6G_MB_LIB.T6G(SCH_1):PAGE89_I348@PURE_QUANTA.SCONN288_DDR506112002KQ(CHIPS)':
 'PAR_A': CDS_PINID='PAR_A';
NET_NAME
'M_E_CPU0_SA_RSP<0>'
 '@T6G_MB_LIB.T6G(SCH_1):M_E_CPU0_SA_RSP'<0>:
 C_SIGNAL='@t6g_mb_lib.t6g(sch_1):m_e_cpu0_sa_rsp(0)';
NODE_NAME     U25 BN69
 '@T6G_MB_LIB.T6G(SCH_1):PAGE14_I159@PURE_QUANTA.GENOA_SP5(CHIPS)':
 'MEA0_RSP_L': CDS_PINID='MEA0_RSP_L';
NODE_NAME     J21 86
 '@T6G_MB_LIB.T6G(SCH_1):PAGE89_I348@PURE_QUANTA.SCONN288_DDR506112002KQ(CHIPS)':
 'LBD||RSP_A_N': CDS_PINID='\lbd||rsp_a_n\';
NET_NAME
'M_E_CPU0_SB_CA<0>'
 '@T6G_MB_LIB.T6G(SCH_1):M_E_CPU0_SB_CA'<0>:
 C_SIGNAL='@t6g_mb_lib.t6g(sch_1):m_e_cpu0_sb_ca(0)';
NODE_NAME     U25 BG69
 '@T6G_MB_LIB.T6G(SCH_1):PAGE14_I159@PURE_QUANTA.GENOA_SP5(CHIPS)':
 'MEB_CA0': CDS_PINID='MEB_CA0';
NODE_NAME     J21 76
 '@T6G_MB_LIB.T6G(SCH_1):PAGE89_I348@PURE_QUANTA.SCONN288_DDR506112002KQ(CHIPS)':
 'CA0_B': CDS_PINID='CA0_B';
NET_NAME
'M_E_CPU0_SB_CA<1>'
 '@T6G_MB_LIB.T6G(SCH_1):M_E_CPU0_SB_CA'<1>:
 C_SIGNAL='@t6g_mb_lib.t6g(sch_1):m_e_cpu0_sb_ca(1)';
NODE_NAME     U25 BH69
 '@T6G_MB_LIB.T6G(SCH_1):PAGE14_I159@PURE_QUANTA.GENOA_SP5(CHIPS)':
 'MEB_CA1': CDS_PINID='MEB_CA1';
NODE_NAME     J21 221
 '@T6G_MB_LIB.T6G(SCH_1):PAGE89_I348@PURE_QUANTA.SCONN288_DDR506112002KQ(CHIPS)':
 'CA1_B': CDS_PINID='CA1_B';
NET_NAME
'M_E_CPU0_SB_CA<2>'
 '@T6G_MB_LIB.T6G(SCH_1):M_E_CPU0_SB_CA'<2>:
 C_SIGNAL='@t6g_mb_lib.t6g(sch_1):m_e_cpu0_sb_ca(2)';
NODE_NAME     U25 BH70
 '@T6G_MB_LIB.T6G(SCH_1):PAGE14_I159@PURE_QUANTA.GENOA_SP5(CHIPS)':
 'MEB_CA2': CDS_PINID='MEB_CA2';
NODE_NAME     J21 78
 '@T6G_MB_LIB.T6G(SCH_1):PAGE89_I348@PURE_QUANTA.SCONN288_DDR506112002KQ(CHIPS)':
 'CA2_B': CDS_PINID='CA2_B';
NET_NAME
'M_E_CPU0_SB_CA<3>'
 '@T6G_MB_LIB.T6G(SCH_1):M_E_CPU0_SB_CA'<3>:
 C_SIGNAL='@t6g_mb_lib.t6g(sch_1):m_e_cpu0_sb_ca(3)';
NODE_NAME     U25 BJ71
 '@T6G_MB_LIB.T6G(SCH_1):PAGE14_I159@PURE_QUANTA.GENOA_SP5(CHIPS)':
 'MEB_CA3': CDS_PINID='MEB_CA3';
NODE_NAME     J21 223
 '@T6G_MB_LIB.T6G(SCH_1):PAGE89_I348@PURE_QUANTA.SCONN288_DDR506112002KQ(CHIPS)':
 'CA3_B': CDS_PINID='CA3_B';
NET_NAME
'M_E_CPU0_SB_CA<4>'
 '@T6G_MB_LIB.T6G(SCH_1):M_E_CPU0_SB_CA'<4>:
 C_SIGNAL='@t6g_mb_lib.t6g(sch_1):m_e_cpu0_sb_ca(4)';
NODE_NAME     U25 BJ69
 '@T6G_MB_LIB.T6G(SCH_1):PAGE14_I159@PURE_QUANTA.GENOA_SP5(CHIPS)':
 'MEB_CA4': CDS_PINID='MEB_CA4';
NODE_NAME     J21 80
 '@T6G_MB_LIB.T6G(SCH_1):PAGE89_I348@PURE_QUANTA.SCONN288_DDR506112002KQ(CHIPS)':
 'CA4_B': CDS_PINID='CA4_B';
NET_NAME
'M_E_CPU0_SB_CA<5>'
 '@T6G_MB_LIB.T6G(SCH_1):M_E_CPU0_SB_CA'<5>:
 C_SIGNAL='@t6g_mb_lib.t6g(sch_1):m_e_cpu0_sb_ca(5)';
NODE_NAME     U25 BK69
 '@T6G_MB_LIB.T6G(SCH_1):PAGE14_I159@PURE_QUANTA.GENOA_SP5(CHIPS)':
 'MEB_CA5': CDS_PINID='MEB_CA5';
NODE_NAME     J21 225
 '@T6G_MB_LIB.T6G(SCH_1):PAGE89_I348@PURE_QUANTA.SCONN288_DDR506112002KQ(CHIPS)':
 'CA5_B': CDS_PINID='CA5_B';
NET_NAME
'M_E_CPU0_SB_CA<6>'
 '@T6G_MB_LIB.T6G(SCH_1):M_E_CPU0_SB_CA'<6>:
 C_SIGNAL='@t6g_mb_lib.t6g(sch_1):m_e_cpu0_sb_ca(6)';
NODE_NAME     U25 BK70
 '@T6G_MB_LIB.T6G(SCH_1):PAGE14_I159@PURE_QUANTA.GENOA_SP5(CHIPS)':
 'MEB_CA6': CDS_PINID='MEB_CA6';
NODE_NAME     J21 82
 '@T6G_MB_LIB.T6G(SCH_1):PAGE89_I348@PURE_QUANTA.SCONN288_DDR506112002KQ(CHIPS)':
 'CA6_B': CDS_PINID='CA6_B';
NET_NAME
'M_E_CPU0_SB_CB<0>'
 '@T6G_MB_LIB.T6G(SCH_1):M_E_CPU0_SB_CB'<0>:
 C_SIGNAL='@t6g_mb_lib.t6g(sch_1):m_e_cpu0_sb_cb(0)';
NODE_NAME     U25 BY70
 '@T6G_MB_LIB.T6G(SCH_1):PAGE14_I159@PURE_QUANTA.GENOA_SP5(CHIPS)':
 'MEB_CHECK0': CDS_PINID='MEB_CHECK0';
NODE_NAME     J21 96
 '@T6G_MB_LIB.T6G(SCH_1):PAGE89_I348@PURE_QUANTA.SCONN288_DDR506112002KQ(CHIPS)':
 'CB0_B': CDS_PINID='CB0_B';
NET_NAME
'M_E_CPU0_SB_CB<1>'
 '@T6G_MB_LIB.T6G(SCH_1):M_E_CPU0_SB_CB'<1>:
 C_SIGNAL='@t6g_mb_lib.t6g(sch_1):m_e_cpu0_sb_cb(1)';
NODE_NAME     U25 CA69
 '@T6G_MB_LIB.T6G(SCH_1):PAGE14_I159@PURE_QUANTA.GENOA_SP5(CHIPS)':
 'MEB_CHECK1': CDS_PINID='MEB_CHECK1';
NODE_NAME     J21 98
 '@T6G_MB_LIB.T6G(SCH_1):PAGE89_I348@PURE_QUANTA.SCONN288_DDR506112002KQ(CHIPS)':
 'CB1_B': CDS_PINID='CB1_B';
NET_NAME
'M_E_CPU0_SB_CB<2>'
 '@T6G_MB_LIB.T6G(SCH_1):M_E_CPU0_SB_CB'<2>:
 C_SIGNAL='@t6g_mb_lib.t6g(sch_1):m_e_cpu0_sb_cb(2)';
NODE_NAME     U25 CA71
 '@T6G_MB_LIB.T6G(SCH_1):PAGE14_I159@PURE_QUANTA.GENOA_SP5(CHIPS)':
 'MEB_CHECK2': CDS_PINID='MEB_CHECK2';
NODE_NAME     J21 241
 '@T6G_MB_LIB.T6G(SCH_1):PAGE89_I348@PURE_QUANTA.SCONN288_DDR506112002KQ(CHIPS)':
 'CB2_B': CDS_PINID='CB2_B';
NET_NAME
'M_E_CPU0_SB_CB<3>'
 '@T6G_MB_LIB.T6G(SCH_1):M_E_CPU0_SB_CB'<3>:
 C_SIGNAL='@t6g_mb_lib.t6g(sch_1):m_e_cpu0_sb_cb(3)';
NODE_NAME     U25 CB69
 '@T6G_MB_LIB.T6G(SCH_1):PAGE14_I159@PURE_QUANTA.GENOA_SP5(CHIPS)':
 'MEB_CHECK3': CDS_PINID='MEB_CHECK3';
NODE_NAME     J21 243
 '@T6G_MB_LIB.T6G(SCH_1):PAGE89_I348@PURE_QUANTA.SCONN288_DDR506112002KQ(CHIPS)':
 'CB3_B': CDS_PINID='CB3_B';
NET_NAME
'M_E_CPU0_SB_CB<4>'
 '@T6G_MB_LIB.T6G(SCH_1):M_E_CPU0_SB_CB'<4>:
 C_SIGNAL='@t6g_mb_lib.t6g(sch_1):m_e_cpu0_sb_cb(4)';
NODE_NAME     U25 BT70
 '@T6G_MB_LIB.T6G(SCH_1):PAGE14_I159@PURE_QUANTA.GENOA_SP5(CHIPS)':
 'MEB_CHECK4': CDS_PINID='MEB_CHECK4';
NODE_NAME     J21 89
 '@T6G_MB_LIB.T6G(SCH_1):PAGE89_I348@PURE_QUANTA.SCONN288_DDR506112002KQ(CHIPS)':
 'CB4_B': CDS_PINID='CB4_B';
NET_NAME
'M_E_CPU0_SB_CB<5>'
 '@T6G_MB_LIB.T6G(SCH_1):M_E_CPU0_SB_CB'<5>:
 C_SIGNAL='@t6g_mb_lib.t6g(sch_1):m_e_cpu0_sb_cb(5)';
NODE_NAME     U25 BU69
 '@T6G_MB_LIB.T6G(SCH_1):PAGE14_I159@PURE_QUANTA.GENOA_SP5(CHIPS)':
 'MEB_CHECK5': CDS_PINID='MEB_CHECK5';
NODE_NAME     J21 91
 '@T6G_MB_LIB.T6G(SCH_1):PAGE89_I348@PURE_QUANTA.SCONN288_DDR506112002KQ(CHIPS)':
 'CB5_B': CDS_PINID='CB5_B';
NET_NAME
'M_E_CPU0_SB_CB<6>'
 '@T6G_MB_LIB.T6G(SCH_1):M_E_CPU0_SB_CB'<6>:
 C_SIGNAL='@t6g_mb_lib.t6g(sch_1):m_e_cpu0_sb_cb(6)';
NODE_NAME     U25 BU71
 '@T6G_MB_LIB.T6G(SCH_1):PAGE14_I159@PURE_QUANTA.GENOA_SP5(CHIPS)':
 'MEB_CHECK6': CDS_PINID='MEB_CHECK6';
NODE_NAME     J21 234
 '@T6G_MB_LIB.T6G(SCH_1):PAGE89_I348@PURE_QUANTA.SCONN288_DDR506112002KQ(CHIPS)':
 'CB6_B': CDS_PINID='CB6_B';
NET_NAME
'M_E_CPU0_SB_CB<7>'
 '@T6G_MB_LIB.T6G(SCH_1):M_E_CPU0_SB_CB'<7>:
 C_SIGNAL='@t6g_mb_lib.t6g(sch_1):m_e_cpu0_sb_cb(7)';
NODE_NAME     U25 BV69
 '@T6G_MB_LIB.T6G(SCH_1):PAGE14_I159@PURE_QUANTA.GENOA_SP5(CHIPS)':
 'MEB_CHECK7': CDS_PINID='MEB_CHECK7';
NODE_NAME     J21 236
 '@T6G_MB_LIB.T6G(SCH_1):PAGE89_I348@PURE_QUANTA.SCONN288_DDR506112002KQ(CHIPS)':
 'CB7_B': CDS_PINID='CB7_B';
NET_NAME
'M_E_CPU0_SB_CS_N<0>'
 '@T6G_MB_LIB.T6G(SCH_1):M_E_CPU0_SB_CS_N'<0>:
 C_SIGNAL='@t6g_mb_lib.t6g(sch_1):m_e_cpu0_sb_cs_n(0)';
NODE_NAME     U25 BM69
 '@T6G_MB_LIB.T6G(SCH_1):PAGE14_I159@PURE_QUANTA.GENOA_SP5(CHIPS)':
 'MEB0_CS_L0': CDS_PINID='MEB0_CS_L0';
NODE_NAME     J21 84
 '@T6G_MB_LIB.T6G(SCH_1):PAGE89_I348@PURE_QUANTA.SCONN288_DDR506112002KQ(CHIPS)':
 'CS0_B_N': CDS_PINID='CS0_B_N';
NET_NAME
'M_E_CPU0_SB_CS_N<1>'
 '@T6G_MB_LIB.T6G(SCH_1):M_E_CPU0_SB_CS_N'<1>:
 C_SIGNAL='@t6g_mb_lib.t6g(sch_1):m_e_cpu0_sb_cs_n(1)';
NODE_NAME     U25 BN71
 '@T6G_MB_LIB.T6G(SCH_1):PAGE14_I159@PURE_QUANTA.GENOA_SP5(CHIPS)':
 'MEB0_CS_L1': CDS_PINID='MEB0_CS_L1';
NODE_NAME     J21 229
 '@T6G_MB_LIB.T6G(SCH_1):PAGE89_I348@PURE_QUANTA.SCONN288_DDR506112002KQ(CHIPS)':
 'CS1_B_N': CDS_PINID='CS1_B_N';
NET_NAME
'M_E_CPU0_SB_DQ<0>'
 '@T6G_MB_LIB.T6G(SCH_1):M_E_CPU0_SB_DQ'<0>:
 C_SIGNAL='@t6g_mb_lib.t6g(sch_1):m_e_cpu0_sb_dq(0)';
NODE_NAME     U25 CB70
 '@T6G_MB_LIB.T6G(SCH_1):PAGE14_I159@PURE_QUANTA.GENOA_SP5(CHIPS)':
 'MEB_DATA0': CDS_PINID='MEB_DATA0';
NODE_NAME     J21 100
 '@T6G_MB_LIB.T6G(SCH_1):PAGE89_I348@PURE_QUANTA.SCONN288_DDR506112002KQ(CHIPS)':
 'DQ0_B': CDS_PINID='DQ0_B';
NET_NAME
'M_E_CPU0_SB_DQ<10>'
 '@T6G_MB_LIB.T6G(SCH_1):M_E_CPU0_SB_DQ'<10>:
 C_SIGNAL='@t6g_mb_lib.t6g(sch_1):m_e_cpu0_sb_dq(10)';
NODE_NAME     U25 CJ71
 '@T6G_MB_LIB.T6G(SCH_1):PAGE14_I159@PURE_QUANTA.GENOA_SP5(CHIPS)':
 'MEB_DATA10': CDS_PINID='MEB_DATA10';
NODE_NAME     J21 256
 '@T6G_MB_LIB.T6G(SCH_1):PAGE89_I348@PURE_QUANTA.SCONN288_DDR506112002KQ(CHIPS)':
 'DQ10_B': CDS_PINID='DQ10_B';
NET_NAME
'M_E_CPU0_SB_DQ<11>'
 '@T6G_MB_LIB.T6G(SCH_1):M_E_CPU0_SB_DQ'<11>:
 C_SIGNAL='@t6g_mb_lib.t6g(sch_1):m_e_cpu0_sb_dq(11)';
NODE_NAME     U25 CK69
 '@T6G_MB_LIB.T6G(SCH_1):PAGE14_I159@PURE_QUANTA.GENOA_SP5(CHIPS)':
 'MEB_DATA11': CDS_PINID='MEB_DATA11';
NODE_NAME     J21 258
 '@T6G_MB_LIB.T6G(SCH_1):PAGE89_I348@PURE_QUANTA.SCONN288_DDR506112002KQ(CHIPS)':
 'DQ11_B': CDS_PINID='DQ11_B';
NET_NAME
'M_E_CPU0_SB_DQ<12>'
 '@T6G_MB_LIB.T6G(SCH_1):M_E_CPU0_SB_DQ'<12>:
 C_SIGNAL='@t6g_mb_lib.t6g(sch_1):m_e_cpu0_sb_dq(12)';
NODE_NAME     U25 CM70
 '@T6G_MB_LIB.T6G(SCH_1):PAGE14_I159@PURE_QUANTA.GENOA_SP5(CHIPS)':
 'MEB_DATA12': CDS_PINID='MEB_DATA12';
NODE_NAME     J21 118
 '@T6G_MB_LIB.T6G(SCH_1):PAGE89_I348@PURE_QUANTA.SCONN288_DDR506112002KQ(CHIPS)':
 'DQ12_B': CDS_PINID='DQ12_B';
NET_NAME
'M_E_CPU0_SB_DQ<13>'
 '@T6G_MB_LIB.T6G(SCH_1):M_E_CPU0_SB_DQ'<13>:
 C_SIGNAL='@t6g_mb_lib.t6g(sch_1):m_e_cpu0_sb_dq(13)';
NODE_NAME     U25 CN69
 '@T6G_MB_LIB.T6G(SCH_1):PAGE14_I159@PURE_QUANTA.GENOA_SP5(CHIPS)':
 'MEB_DATA13': CDS_PINID='MEB_DATA13';
NODE_NAME     J21 120
 '@T6G_MB_LIB.T6G(SCH_1):PAGE89_I348@PURE_QUANTA.SCONN288_DDR506112002KQ(CHIPS)':
 'DQ13_B': CDS_PINID='DQ13_B';
NET_NAME
'M_E_CPU0_SB_DQ<14>'
 '@T6G_MB_LIB.T6G(SCH_1):M_E_CPU0_SB_DQ'<14>:
 C_SIGNAL='@t6g_mb_lib.t6g(sch_1):m_e_cpu0_sb_dq(14)';
NODE_NAME     U25 CN71
 '@T6G_MB_LIB.T6G(SCH_1):PAGE14_I159@PURE_QUANTA.GENOA_SP5(CHIPS)':
 'MEB_DATA14': CDS_PINID='MEB_DATA14';
NODE_NAME     J21 263
 '@T6G_MB_LIB.T6G(SCH_1):PAGE89_I348@PURE_QUANTA.SCONN288_DDR506112002KQ(CHIPS)':
 'DQ14_B': CDS_PINID='DQ14_B';
NET_NAME
'M_E_CPU0_SB_DQ<15>'
 '@T6G_MB_LIB.T6G(SCH_1):M_E_CPU0_SB_DQ'<15>:
 C_SIGNAL='@t6g_mb_lib.t6g(sch_1):m_e_cpu0_sb_dq(15)';
NODE_NAME     U25 CP69
 '@T6G_MB_LIB.T6G(SCH_1):PAGE14_I159@PURE_QUANTA.GENOA_SP5(CHIPS)':
 'MEB_DATA15': CDS_PINID='MEB_DATA15';
NODE_NAME     J21 265
 '@T6G_MB_LIB.T6G(SCH_1):PAGE89_I348@PURE_QUANTA.SCONN288_DDR506112002KQ(CHIPS)':
 'DQ15_B': CDS_PINID='DQ15_B';
NET_NAME
'M_E_CPU0_SB_DQ<16>'
 '@T6G_MB_LIB.T6G(SCH_1):M_E_CPU0_SB_DQ'<16>:
 C_SIGNAL='@t6g_mb_lib.t6g(sch_1):m_e_cpu0_sb_dq(16)';
NODE_NAME     U25 CP70
 '@T6G_MB_LIB.T6G(SCH_1):PAGE14_I159@PURE_QUANTA.GENOA_SP5(CHIPS)':
 'MEB_DATA16': CDS_PINID='MEB_DATA16';
NODE_NAME     J21 122
 '@T6G_MB_LIB.T6G(SCH_1):PAGE89_I348@PURE_QUANTA.SCONN288_DDR506112002KQ(CHIPS)':
 'DQ16_B': CDS_PINID='DQ16_B';
NET_NAME
'M_E_CPU0_SB_DQ<17>'
 '@T6G_MB_LIB.T6G(SCH_1):M_E_CPU0_SB_DQ'<17>:
 C_SIGNAL='@t6g_mb_lib.t6g(sch_1):m_e_cpu0_sb_dq(17)';
NODE_NAME     U25 CR69
 '@T6G_MB_LIB.T6G(SCH_1):PAGE14_I159@PURE_QUANTA.GENOA_SP5(CHIPS)':
 'MEB_DATA17': CDS_PINID='MEB_DATA17';
NODE_NAME     J21 124
 '@T6G_MB_LIB.T6G(SCH_1):PAGE89_I348@PURE_QUANTA.SCONN288_DDR506112002KQ(CHIPS)':
 'DQ17_B': CDS_PINID='DQ17_B';
NET_NAME
'M_E_CPU0_SB_DQ<18>'
 '@T6G_MB_LIB.T6G(SCH_1):M_E_CPU0_SB_DQ'<18>:
 C_SIGNAL='@t6g_mb_lib.t6g(sch_1):m_e_cpu0_sb_dq(18)';
NODE_NAME     U25 CR71
 '@T6G_MB_LIB.T6G(SCH_1):PAGE14_I159@PURE_QUANTA.GENOA_SP5(CHIPS)':
 'MEB_DATA18': CDS_PINID='MEB_DATA18';
NODE_NAME     J21 267
 '@T6G_MB_LIB.T6G(SCH_1):PAGE89_I348@PURE_QUANTA.SCONN288_DDR506112002KQ(CHIPS)':
 'DQ18_B': CDS_PINID='DQ18_B';
NET_NAME
'M_E_CPU0_SB_DQ<19>'
 '@T6G_MB_LIB.T6G(SCH_1):M_E_CPU0_SB_DQ'<19>:
 C_SIGNAL='@t6g_mb_lib.t6g(sch_1):m_e_cpu0_sb_dq(19)';
NODE_NAME     U25 CT69
 '@T6G_MB_LIB.T6G(SCH_1):PAGE14_I159@PURE_QUANTA.GENOA_SP5(CHIPS)':
 'MEB_DATA19': CDS_PINID='MEB_DATA19';
NODE_NAME     J21 269
 '@T6G_MB_LIB.T6G(SCH_1):PAGE89_I348@PURE_QUANTA.SCONN288_DDR506112002KQ(CHIPS)':
 'DQ19_B': CDS_PINID='DQ19_B';
NET_NAME
'M_E_CPU0_SB_DQ<1>'
 '@T6G_MB_LIB.T6G(SCH_1):M_E_CPU0_SB_DQ'<1>:
 C_SIGNAL='@t6g_mb_lib.t6g(sch_1):m_e_cpu0_sb_dq(1)';
NODE_NAME     U25 CC69
 '@T6G_MB_LIB.T6G(SCH_1):PAGE14_I159@PURE_QUANTA.GENOA_SP5(CHIPS)':
 'MEB_DATA1': CDS_PINID='MEB_DATA1';
NODE_NAME     J21 102
 '@T6G_MB_LIB.T6G(SCH_1):PAGE89_I348@PURE_QUANTA.SCONN288_DDR506112002KQ(CHIPS)':
 'DQ1_B': CDS_PINID='DQ1_B';
NET_NAME
'M_E_CPU0_SB_DQ<20>'
 '@T6G_MB_LIB.T6G(SCH_1):M_E_CPU0_SB_DQ'<20>:
 C_SIGNAL='@t6g_mb_lib.t6g(sch_1):m_e_cpu0_sb_dq(20)';
NODE_NAME     U25 CV70
 '@T6G_MB_LIB.T6G(SCH_1):PAGE14_I159@PURE_QUANTA.GENOA_SP5(CHIPS)':
 'MEB_DATA20': CDS_PINID='MEB_DATA20';
NODE_NAME     J21 129
 '@T6G_MB_LIB.T6G(SCH_1):PAGE89_I348@PURE_QUANTA.SCONN288_DDR506112002KQ(CHIPS)':
 'DQ20_B': CDS_PINID='DQ20_B';
NET_NAME
'M_E_CPU0_SB_DQ<21>'
 '@T6G_MB_LIB.T6G(SCH_1):M_E_CPU0_SB_DQ'<21>:
 C_SIGNAL='@t6g_mb_lib.t6g(sch_1):m_e_cpu0_sb_dq(21)';
NODE_NAME     U25 CW69
 '@T6G_MB_LIB.T6G(SCH_1):PAGE14_I159@PURE_QUANTA.GENOA_SP5(CHIPS)':
 'MEB_DATA21': CDS_PINID='MEB_DATA21';
NODE_NAME     J21 131
 '@T6G_MB_LIB.T6G(SCH_1):PAGE89_I348@PURE_QUANTA.SCONN288_DDR506112002KQ(CHIPS)':
 'DQ21_B': CDS_PINID='DQ21_B';
NET_NAME
'M_E_CPU0_SB_DQ<22>'
 '@T6G_MB_LIB.T6G(SCH_1):M_E_CPU0_SB_DQ'<22>:
 C_SIGNAL='@t6g_mb_lib.t6g(sch_1):m_e_cpu0_sb_dq(22)';
NODE_NAME     U25 CW71
 '@T6G_MB_LIB.T6G(SCH_1):PAGE14_I159@PURE_QUANTA.GENOA_SP5(CHIPS)':
 'MEB_DATA22': CDS_PINID='MEB_DATA22';
NODE_NAME     J21 274
 '@T6G_MB_LIB.T6G(SCH_1):PAGE89_I348@PURE_QUANTA.SCONN288_DDR506112002KQ(CHIPS)':
 'DQ22_B': CDS_PINID='DQ22_B';
NET_NAME
'M_E_CPU0_SB_DQ<23>'
 '@T6G_MB_LIB.T6G(SCH_1):M_E_CPU0_SB_DQ'<23>:
 C_SIGNAL='@t6g_mb_lib.t6g(sch_1):m_e_cpu0_sb_dq(23)';
NODE_NAME     U25 CY69
 '@T6G_MB_LIB.T6G(SCH_1):PAGE14_I159@PURE_QUANTA.GENOA_SP5(CHIPS)':
 'MEB_DATA23': CDS_PINID='MEB_DATA23';
NODE_NAME     J21 276
 '@T6G_MB_LIB.T6G(SCH_1):PAGE89_I348@PURE_QUANTA.SCONN288_DDR506112002KQ(CHIPS)':
 'DQ23_B': CDS_PINID='DQ23_B';
NET_NAME
'M_E_CPU0_SB_DQ<24>'
 '@T6G_MB_LIB.T6G(SCH_1):M_E_CPU0_SB_DQ'<24>:
 C_SIGNAL='@t6g_mb_lib.t6g(sch_1):m_e_cpu0_sb_dq(24)';
NODE_NAME     U25 CY70
 '@T6G_MB_LIB.T6G(SCH_1):PAGE14_I159@PURE_QUANTA.GENOA_SP5(CHIPS)':
 'MEB_DATA24': CDS_PINID='MEB_DATA24';
NODE_NAME     J21 133
 '@T6G_MB_LIB.T6G(SCH_1):PAGE89_I348@PURE_QUANTA.SCONN288_DDR506112002KQ(CHIPS)':
 'DQ24_B': CDS_PINID='DQ24_B';
NET_NAME
'M_E_CPU0_SB_DQ<25>'
 '@T6G_MB_LIB.T6G(SCH_1):M_E_CPU0_SB_DQ'<25>:
 C_SIGNAL='@t6g_mb_lib.t6g(sch_1):m_e_cpu0_sb_dq(25)';
NODE_NAME     U25 DA69
 '@T6G_MB_LIB.T6G(SCH_1):PAGE14_I159@PURE_QUANTA.GENOA_SP5(CHIPS)':
 'MEB_DATA25': CDS_PINID='MEB_DATA25';
NODE_NAME     J21 135
 '@T6G_MB_LIB.T6G(SCH_1):PAGE89_I348@PURE_QUANTA.SCONN288_DDR506112002KQ(CHIPS)':
 'DQ25_B': CDS_PINID='DQ25_B';
NET_NAME
'M_E_CPU0_SB_DQ<26>'
 '@T6G_MB_LIB.T6G(SCH_1):M_E_CPU0_SB_DQ'<26>:
 C_SIGNAL='@t6g_mb_lib.t6g(sch_1):m_e_cpu0_sb_dq(26)';
NODE_NAME     U25 DA71
 '@T6G_MB_LIB.T6G(SCH_1):PAGE14_I159@PURE_QUANTA.GENOA_SP5(CHIPS)':
 'MEB_DATA26': CDS_PINID='MEB_DATA26';
NODE_NAME     J21 278
 '@T6G_MB_LIB.T6G(SCH_1):PAGE89_I348@PURE_QUANTA.SCONN288_DDR506112002KQ(CHIPS)':
 'DQ26_B': CDS_PINID='DQ26_B';
NET_NAME
'M_E_CPU0_SB_DQ<27>'
 '@T6G_MB_LIB.T6G(SCH_1):M_E_CPU0_SB_DQ'<27>:
 C_SIGNAL='@t6g_mb_lib.t6g(sch_1):m_e_cpu0_sb_dq(27)';
NODE_NAME     U25 DB69
 '@T6G_MB_LIB.T6G(SCH_1):PAGE14_I159@PURE_QUANTA.GENOA_SP5(CHIPS)':
 'MEB_DATA27': CDS_PINID='MEB_DATA27';
NODE_NAME     J21 280
 '@T6G_MB_LIB.T6G(SCH_1):PAGE89_I348@PURE_QUANTA.SCONN288_DDR506112002KQ(CHIPS)':
 'DQ27_B': CDS_PINID='DQ27_B';
NET_NAME
'M_E_CPU0_SB_DQ<28>'
 '@T6G_MB_LIB.T6G(SCH_1):M_E_CPU0_SB_DQ'<28>:
 C_SIGNAL='@t6g_mb_lib.t6g(sch_1):m_e_cpu0_sb_dq(28)';
NODE_NAME     U25 DD70
 '@T6G_MB_LIB.T6G(SCH_1):PAGE14_I159@PURE_QUANTA.GENOA_SP5(CHIPS)':
 'MEB_DATA28': CDS_PINID='MEB_DATA28';
NODE_NAME     J21 140
 '@T6G_MB_LIB.T6G(SCH_1):PAGE89_I348@PURE_QUANTA.SCONN288_DDR506112002KQ(CHIPS)':
 'DQ28_B': CDS_PINID='DQ28_B';
NET_NAME
'M_E_CPU0_SB_DQ<29>'
 '@T6G_MB_LIB.T6G(SCH_1):M_E_CPU0_SB_DQ'<29>:
 C_SIGNAL='@t6g_mb_lib.t6g(sch_1):m_e_cpu0_sb_dq(29)';
NODE_NAME     U25 DE69
 '@T6G_MB_LIB.T6G(SCH_1):PAGE14_I159@PURE_QUANTA.GENOA_SP5(CHIPS)':
 'MEB_DATA29': CDS_PINID='MEB_DATA29';
NODE_NAME     J21 142
 '@T6G_MB_LIB.T6G(SCH_1):PAGE89_I348@PURE_QUANTA.SCONN288_DDR506112002KQ(CHIPS)':
 'DQ29_B': CDS_PINID='DQ29_B';
NET_NAME
'M_E_CPU0_SB_DQ<2>'
 '@T6G_MB_LIB.T6G(SCH_1):M_E_CPU0_SB_DQ'<2>:
 C_SIGNAL='@t6g_mb_lib.t6g(sch_1):m_e_cpu0_sb_dq(2)';
NODE_NAME     U25 CC71
 '@T6G_MB_LIB.T6G(SCH_1):PAGE14_I159@PURE_QUANTA.GENOA_SP5(CHIPS)':
 'MEB_DATA2': CDS_PINID='MEB_DATA2';
NODE_NAME     J21 245
 '@T6G_MB_LIB.T6G(SCH_1):PAGE89_I348@PURE_QUANTA.SCONN288_DDR506112002KQ(CHIPS)':
 'DQ2_B': CDS_PINID='DQ2_B';
NET_NAME
'M_E_CPU0_SB_DQ<30>'
 '@T6G_MB_LIB.T6G(SCH_1):M_E_CPU0_SB_DQ'<30>:
 C_SIGNAL='@t6g_mb_lib.t6g(sch_1):m_e_cpu0_sb_dq(30)';
NODE_NAME     U25 DE71
 '@T6G_MB_LIB.T6G(SCH_1):PAGE14_I159@PURE_QUANTA.GENOA_SP5(CHIPS)':
 'MEB_DATA30': CDS_PINID='MEB_DATA30';
NODE_NAME     J21 285
 '@T6G_MB_LIB.T6G(SCH_1):PAGE89_I348@PURE_QUANTA.SCONN288_DDR506112002KQ(CHIPS)':
 'DQ30_B': CDS_PINID='DQ30_B';
NET_NAME
'M_E_CPU0_SB_DQ<31>'
 '@T6G_MB_LIB.T6G(SCH_1):M_E_CPU0_SB_DQ'<31>:
 C_SIGNAL='@t6g_mb_lib.t6g(sch_1):m_e_cpu0_sb_dq(31)';
NODE_NAME     U25 DF69
 '@T6G_MB_LIB.T6G(SCH_1):PAGE14_I159@PURE_QUANTA.GENOA_SP5(CHIPS)':
 'MEB_DATA31': CDS_PINID='MEB_DATA31';
NODE_NAME     J21 287
 '@T6G_MB_LIB.T6G(SCH_1):PAGE89_I348@PURE_QUANTA.SCONN288_DDR506112002KQ(CHIPS)':
 'DQ31_B': CDS_PINID='DQ31_B';
NET_NAME
'M_E_CPU0_SB_DQ<3>'
 '@T6G_MB_LIB.T6G(SCH_1):M_E_CPU0_SB_DQ'<3>:
 C_SIGNAL='@t6g_mb_lib.t6g(sch_1):m_e_cpu0_sb_dq(3)';
NODE_NAME     U25 CD69
 '@T6G_MB_LIB.T6G(SCH_1):PAGE14_I159@PURE_QUANTA.GENOA_SP5(CHIPS)':
 'MEB_DATA3': CDS_PINID='MEB_DATA3';
NODE_NAME     J21 247
 '@T6G_MB_LIB.T6G(SCH_1):PAGE89_I348@PURE_QUANTA.SCONN288_DDR506112002KQ(CHIPS)':
 'DQ3_B': CDS_PINID='DQ3_B';
NET_NAME
'M_E_CPU0_SB_DQ<4>'
 '@T6G_MB_LIB.T6G(SCH_1):M_E_CPU0_SB_DQ'<4>:
 C_SIGNAL='@t6g_mb_lib.t6g(sch_1):m_e_cpu0_sb_dq(4)';
NODE_NAME     U25 CF70
 '@T6G_MB_LIB.T6G(SCH_1):PAGE14_I159@PURE_QUANTA.GENOA_SP5(CHIPS)':
 'MEB_DATA4': CDS_PINID='MEB_DATA4';
NODE_NAME     J21 107
 '@T6G_MB_LIB.T6G(SCH_1):PAGE89_I348@PURE_QUANTA.SCONN288_DDR506112002KQ(CHIPS)':
 'DQ4_B': CDS_PINID='DQ4_B';
NET_NAME
'M_E_CPU0_SB_DQ<5>'
 '@T6G_MB_LIB.T6G(SCH_1):M_E_CPU0_SB_DQ'<5>:
 C_SIGNAL='@t6g_mb_lib.t6g(sch_1):m_e_cpu0_sb_dq(5)';
NODE_NAME     U25 CG69
 '@T6G_MB_LIB.T6G(SCH_1):PAGE14_I159@PURE_QUANTA.GENOA_SP5(CHIPS)':
 'MEB_DATA5': CDS_PINID='MEB_DATA5';
NODE_NAME     J21 109
 '@T6G_MB_LIB.T6G(SCH_1):PAGE89_I348@PURE_QUANTA.SCONN288_DDR506112002KQ(CHIPS)':
 'DQ5_B': CDS_PINID='DQ5_B';
NET_NAME
'M_E_CPU0_SB_DQ<6>'
 '@T6G_MB_LIB.T6G(SCH_1):M_E_CPU0_SB_DQ'<6>:
 C_SIGNAL='@t6g_mb_lib.t6g(sch_1):m_e_cpu0_sb_dq(6)';
NODE_NAME     U25 CG71
 '@T6G_MB_LIB.T6G(SCH_1):PAGE14_I159@PURE_QUANTA.GENOA_SP5(CHIPS)':
 'MEB_DATA6': CDS_PINID='MEB_DATA6';
NODE_NAME     J21 252
 '@T6G_MB_LIB.T6G(SCH_1):PAGE89_I348@PURE_QUANTA.SCONN288_DDR506112002KQ(CHIPS)':
 'DQ6_B': CDS_PINID='DQ6_B';
NET_NAME
'M_E_CPU0_SB_DQ<7>'
 '@T6G_MB_LIB.T6G(SCH_1):M_E_CPU0_SB_DQ'<7>:
 C_SIGNAL='@t6g_mb_lib.t6g(sch_1):m_e_cpu0_sb_dq(7)';
NODE_NAME     U25 CH69
 '@T6G_MB_LIB.T6G(SCH_1):PAGE14_I159@PURE_QUANTA.GENOA_SP5(CHIPS)':
 'MEB_DATA7': CDS_PINID='MEB_DATA7';
NODE_NAME     J21 254
 '@T6G_MB_LIB.T6G(SCH_1):PAGE89_I348@PURE_QUANTA.SCONN288_DDR506112002KQ(CHIPS)':
 'DQ7_B': CDS_PINID='DQ7_B';
NET_NAME
'M_E_CPU0_SB_DQ<8>'
 '@T6G_MB_LIB.T6G(SCH_1):M_E_CPU0_SB_DQ'<8>:
 C_SIGNAL='@t6g_mb_lib.t6g(sch_1):m_e_cpu0_sb_dq(8)';
NODE_NAME     U25 CH70
 '@T6G_MB_LIB.T6G(SCH_1):PAGE14_I159@PURE_QUANTA.GENOA_SP5(CHIPS)':
 'MEB_DATA8': CDS_PINID='MEB_DATA8';
NODE_NAME     J21 111
 '@T6G_MB_LIB.T6G(SCH_1):PAGE89_I348@PURE_QUANTA.SCONN288_DDR506112002KQ(CHIPS)':
 'DQ8_B': CDS_PINID='DQ8_B';
NET_NAME
'M_E_CPU0_SB_DQ<9>'
 '@T6G_MB_LIB.T6G(SCH_1):M_E_CPU0_SB_DQ'<9>:
 C_SIGNAL='@t6g_mb_lib.t6g(sch_1):m_e_cpu0_sb_dq(9)';
NODE_NAME     U25 CJ69
 '@T6G_MB_LIB.T6G(SCH_1):PAGE14_I159@PURE_QUANTA.GENOA_SP5(CHIPS)':
 'MEB_DATA9': CDS_PINID='MEB_DATA9';
NODE_NAME     J21 113
 '@T6G_MB_LIB.T6G(SCH_1):PAGE89_I348@PURE_QUANTA.SCONN288_DDR506112002KQ(CHIPS)':
 'DQ9_B': CDS_PINID='DQ9_B';
NET_NAME
'M_E_CPU0_SB_DQS_DN<0>'
 '@T6G_MB_LIB.T6G(SCH_1):M_E_CPU0_SB_DQS_DN'<0>:
 C_SIGNAL='@t6g_mb_lib.t6g(sch_1):m_e_cpu0_sb_dqs_dn(0)';
NODE_NAME     U25 CE71
 '@T6G_MB_LIB.T6G(SCH_1):PAGE14_I159@PURE_QUANTA.GENOA_SP5(CHIPS)':
 'MEB_DQS_L0': CDS_PINID='MEB_DQS_L0';
NODE_NAME     J21 105
 '@T6G_MB_LIB.T6G(SCH_1):PAGE89_I410@PURE_QUANTA.SCONN288_DDR506112002KQ(CHIPS)':
 'DQS0_B_C': CDS_PINID='DQS0_B_C';
NET_NAME
'M_E_CPU0_SB_DQS_DN<1>'
 '@T6G_MB_LIB.T6G(SCH_1):M_E_CPU0_SB_DQS_DN'<1>:
 C_SIGNAL='@t6g_mb_lib.t6g(sch_1):m_e_cpu0_sb_dqs_dn(1)';
NODE_NAME     U25 CL71
 '@T6G_MB_LIB.T6G(SCH_1):PAGE14_I159@PURE_QUANTA.GENOA_SP5(CHIPS)':
 'MEB_DQS_L1': CDS_PINID='MEB_DQS_L1';
NODE_NAME     J21 116
 '@T6G_MB_LIB.T6G(SCH_1):PAGE89_I410@PURE_QUANTA.SCONN288_DDR506112002KQ(CHIPS)':
 'DQS1_B_C': CDS_PINID='DQS1_B_C';
NET_NAME
'M_E_CPU0_SB_DQS_DN<2>'
 '@T6G_MB_LIB.T6G(SCH_1):M_E_CPU0_SB_DQS_DN'<2>:
 C_SIGNAL='@t6g_mb_lib.t6g(sch_1):m_e_cpu0_sb_dqs_dn(2)';
NODE_NAME     U25 CU71
 '@T6G_MB_LIB.T6G(SCH_1):PAGE14_I159@PURE_QUANTA.GENOA_SP5(CHIPS)':
 'MEB_DQS_L2': CDS_PINID='MEB_DQS_L2';
NODE_NAME     J21 127
 '@T6G_MB_LIB.T6G(SCH_1):PAGE89_I410@PURE_QUANTA.SCONN288_DDR506112002KQ(CHIPS)':
 'DQS2_B_C': CDS_PINID='DQS2_B_C';
NET_NAME
'M_E_CPU0_SB_DQS_DN<3>'
 '@T6G_MB_LIB.T6G(SCH_1):M_E_CPU0_SB_DQS_DN'<3>:
 C_SIGNAL='@t6g_mb_lib.t6g(sch_1):m_e_cpu0_sb_dqs_dn(3)';
NODE_NAME     U25 DC71
 '@T6G_MB_LIB.T6G(SCH_1):PAGE14_I159@PURE_QUANTA.GENOA_SP5(CHIPS)':
 'MEB_DQS_L3': CDS_PINID='MEB_DQS_L3';
NODE_NAME     J21 138
 '@T6G_MB_LIB.T6G(SCH_1):PAGE89_I410@PURE_QUANTA.SCONN288_DDR506112002KQ(CHIPS)':
 'DQS3_B_C': CDS_PINID='DQS3_B_C';
NET_NAME
'M_E_CPU0_SB_DQS_DN<4>'
 '@T6G_MB_LIB.T6G(SCH_1):M_E_CPU0_SB_DQS_DN'<4>:
 C_SIGNAL='@t6g_mb_lib.t6g(sch_1):m_e_cpu0_sb_dqs_dn(4)';
NODE_NAME     U25 BW69
 '@T6G_MB_LIB.T6G(SCH_1):PAGE14_I159@PURE_QUANTA.GENOA_SP5(CHIPS)':
 'MEB_DQS_L4': CDS_PINID='MEB_DQS_L4';
NODE_NAME     J21 238
 '@T6G_MB_LIB.T6G(SCH_1):PAGE89_I410@PURE_QUANTA.SCONN288_DDR506112002KQ(CHIPS)':
 'DQS4_B_C': CDS_PINID='DQS4_B_C';
NET_NAME
'M_E_CPU0_SB_DQS_DN<5>'
 '@T6G_MB_LIB.T6G(SCH_1):M_E_CPU0_SB_DQS_DN'<5>:
 C_SIGNAL='@t6g_mb_lib.t6g(sch_1):m_e_cpu0_sb_dqs_dn(5)';
NODE_NAME     U25 CE69
 '@T6G_MB_LIB.T6G(SCH_1):PAGE14_I159@PURE_QUANTA.GENOA_SP5(CHIPS)':
 'MEB_DQS_L5': CDS_PINID='MEB_DQS_L5';
NODE_NAME     J21 249
 '@T6G_MB_LIB.T6G(SCH_1):PAGE89_I410@PURE_QUANTA.SCONN288_DDR506112002KQ(CHIPS)':
 'DQS5_B_C||TDQS5_B_C': CDS_PINID='\dqs5_b_c||tdqs5_b_c\';
NET_NAME
'M_E_CPU0_SB_DQS_DN<6>'
 '@T6G_MB_LIB.T6G(SCH_1):M_E_CPU0_SB_DQS_DN'<6>:
 C_SIGNAL='@t6g_mb_lib.t6g(sch_1):m_e_cpu0_sb_dqs_dn(6)';
NODE_NAME     U25 CL69
 '@T6G_MB_LIB.T6G(SCH_1):PAGE14_I159@PURE_QUANTA.GENOA_SP5(CHIPS)':
 'MEB_DQS_L6': CDS_PINID='MEB_DQS_L6';
NODE_NAME     J21 260
 '@T6G_MB_LIB.T6G(SCH_1):PAGE89_I410@PURE_QUANTA.SCONN288_DDR506112002KQ(CHIPS)':
 'DQS6_B_C||TDQS6_B_C': CDS_PINID='\dqs6_b_c||tdqs6_b_c\';
NET_NAME
'M_E_CPU0_SB_DQS_DN<7>'
 '@T6G_MB_LIB.T6G(SCH_1):M_E_CPU0_SB_DQS_DN'<7>:
 C_SIGNAL='@t6g_mb_lib.t6g(sch_1):m_e_cpu0_sb_dqs_dn(7)';
NODE_NAME     U25 CU69
 '@T6G_MB_LIB.T6G(SCH_1):PAGE14_I159@PURE_QUANTA.GENOA_SP5(CHIPS)':
 'MEB_DQS_L7': CDS_PINID='MEB_DQS_L7';
NODE_NAME     J21 271
 '@T6G_MB_LIB.T6G(SCH_1):PAGE89_I410@PURE_QUANTA.SCONN288_DDR506112002KQ(CHIPS)':
 'DQS7_B_C||TDQS7_B_C': CDS_PINID='\dqs7_b_c||tdqs7_b_c\';
NET_NAME
'M_E_CPU0_SB_DQS_DN<8>'
 '@T6G_MB_LIB.T6G(SCH_1):M_E_CPU0_SB_DQS_DN'<8>:
 C_SIGNAL='@t6g_mb_lib.t6g(sch_1):m_e_cpu0_sb_dqs_dn(8)';
NODE_NAME     U25 DC69
 '@T6G_MB_LIB.T6G(SCH_1):PAGE14_I159@PURE_QUANTA.GENOA_SP5(CHIPS)':
 'MEB_DQS_L8': CDS_PINID='MEB_DQS_L8';
NODE_NAME     J21 282
 '@T6G_MB_LIB.T6G(SCH_1):PAGE89_I410@PURE_QUANTA.SCONN288_DDR506112002KQ(CHIPS)':
 'DQS8_B_C||TDQS8_B_C': CDS_PINID='\dqs8_b_c||tdqs8_b_c\';
NET_NAME
'M_E_CPU0_SB_DQS_DN<9>'
 '@T6G_MB_LIB.T6G(SCH_1):M_E_CPU0_SB_DQS_DN'<9>:
 C_SIGNAL='@t6g_mb_lib.t6g(sch_1):m_e_cpu0_sb_dqs_dn(9)';
NODE_NAME     U25 BW71
 '@T6G_MB_LIB.T6G(SCH_1):PAGE14_I159@PURE_QUANTA.GENOA_SP5(CHIPS)':
 'MEB_DQS_L9': CDS_PINID='MEB_DQS_L9';
NODE_NAME     J21 94
 '@T6G_MB_LIB.T6G(SCH_1):PAGE89_I410@PURE_QUANTA.SCONN288_DDR506112002KQ(CHIPS)':
 'DQS9_B_C||TDQS9_B_C': CDS_PINID='\dqs9_b_c||tdqs9_b_c\';
NET_NAME
'M_E_CPU0_SB_DQS_DP<0>'
 '@T6G_MB_LIB.T6G(SCH_1):M_E_CPU0_SB_DQS_DP'<0>:
 C_SIGNAL='@t6g_mb_lib.t6g(sch_1):m_e_cpu0_sb_dqs_dp(0)';
NODE_NAME     U25 CD70
 '@T6G_MB_LIB.T6G(SCH_1):PAGE14_I159@PURE_QUANTA.GENOA_SP5(CHIPS)':
 'MEB_DQS_H0': CDS_PINID='MEB_DQS_H0';
NODE_NAME     J21 104
 '@T6G_MB_LIB.T6G(SCH_1):PAGE89_I410@PURE_QUANTA.SCONN288_DDR506112002KQ(CHIPS)':
 'DQS0_B_T': CDS_PINID='DQS0_B_T';
NET_NAME
'M_E_CPU0_SB_DQS_DP<1>'
 '@T6G_MB_LIB.T6G(SCH_1):M_E_CPU0_SB_DQS_DP'<1>:
 C_SIGNAL='@t6g_mb_lib.t6g(sch_1):m_e_cpu0_sb_dqs_dp(1)';
NODE_NAME     U25 CK70
 '@T6G_MB_LIB.T6G(SCH_1):PAGE14_I159@PURE_QUANTA.GENOA_SP5(CHIPS)':
 'MEB_DQS_H1': CDS_PINID='MEB_DQS_H1';
NODE_NAME     J21 115
 '@T6G_MB_LIB.T6G(SCH_1):PAGE89_I410@PURE_QUANTA.SCONN288_DDR506112002KQ(CHIPS)':
 'DQS1_B_T': CDS_PINID='DQS1_B_T';
NET_NAME
'M_E_CPU0_SB_DQS_DP<2>'
 '@T6G_MB_LIB.T6G(SCH_1):M_E_CPU0_SB_DQS_DP'<2>:
 C_SIGNAL='@t6g_mb_lib.t6g(sch_1):m_e_cpu0_sb_dqs_dp(2)';
NODE_NAME     U25 CT70
 '@T6G_MB_LIB.T6G(SCH_1):PAGE14_I159@PURE_QUANTA.GENOA_SP5(CHIPS)':
 'MEB_DQS_H2': CDS_PINID='MEB_DQS_H2';
NODE_NAME     J21 126
 '@T6G_MB_LIB.T6G(SCH_1):PAGE89_I410@PURE_QUANTA.SCONN288_DDR506112002KQ(CHIPS)':
 'DQS2_B_T': CDS_PINID='DQS2_B_T';
NET_NAME
'M_E_CPU0_SB_DQS_DP<3>'
 '@T6G_MB_LIB.T6G(SCH_1):M_E_CPU0_SB_DQS_DP'<3>:
 C_SIGNAL='@t6g_mb_lib.t6g(sch_1):m_e_cpu0_sb_dqs_dp(3)';
NODE_NAME     U25 DB70
 '@T6G_MB_LIB.T6G(SCH_1):PAGE14_I159@PURE_QUANTA.GENOA_SP5(CHIPS)':
 'MEB_DQS_H3': CDS_PINID='MEB_DQS_H3';
NODE_NAME     J21 137
 '@T6G_MB_LIB.T6G(SCH_1):PAGE89_I410@PURE_QUANTA.SCONN288_DDR506112002KQ(CHIPS)':
 'DQS3_B_T': CDS_PINID='DQS3_B_T';
NET_NAME
'M_E_CPU0_SB_DQS_DP<4>'
 '@T6G_MB_LIB.T6G(SCH_1):M_E_CPU0_SB_DQS_DP'<4>:
 C_SIGNAL='@t6g_mb_lib.t6g(sch_1):m_e_cpu0_sb_dqs_dp(4)';
NODE_NAME     U25 BY69
 '@T6G_MB_LIB.T6G(SCH_1):PAGE14_I159@PURE_QUANTA.GENOA_SP5(CHIPS)':
 'MEB_DQS_H4': CDS_PINID='MEB_DQS_H4';
NODE_NAME     J21 239
 '@T6G_MB_LIB.T6G(SCH_1):PAGE89_I410@PURE_QUANTA.SCONN288_DDR506112002KQ(CHIPS)':
 'DQS4_B_T': CDS_PINID='DQS4_B_T';
NET_NAME
'M_E_CPU0_SB_DQS_DP<5>'
 '@T6G_MB_LIB.T6G(SCH_1):M_E_CPU0_SB_DQS_DP'<5>:
 C_SIGNAL='@t6g_mb_lib.t6g(sch_1):m_e_cpu0_sb_dqs_dp(5)';
NODE_NAME     U25 CF69
 '@T6G_MB_LIB.T6G(SCH_1):PAGE14_I159@PURE_QUANTA.GENOA_SP5(CHIPS)':
 'MEB_DQS_H5': CDS_PINID='MEB_DQS_H5';
NODE_NAME     J21 250
 '@T6G_MB_LIB.T6G(SCH_1):PAGE89_I410@PURE_QUANTA.SCONN288_DDR506112002KQ(CHIPS)':
 'DQS5_B_T||TDQS5_B_T': CDS_PINID='\dqs5_b_t||tdqs5_b_t\';
NET_NAME
'M_E_CPU0_SB_DQS_DP<6>'
 '@T6G_MB_LIB.T6G(SCH_1):M_E_CPU0_SB_DQS_DP'<6>:
 C_SIGNAL='@t6g_mb_lib.t6g(sch_1):m_e_cpu0_sb_dqs_dp(6)';
NODE_NAME     U25 CM69
 '@T6G_MB_LIB.T6G(SCH_1):PAGE14_I159@PURE_QUANTA.GENOA_SP5(CHIPS)':
 'MEB_DQS_H6': CDS_PINID='MEB_DQS_H6';
NODE_NAME     J21 261
 '@T6G_MB_LIB.T6G(SCH_1):PAGE89_I410@PURE_QUANTA.SCONN288_DDR506112002KQ(CHIPS)':
 'DQS6_B_T||TDQS6_B_T': CDS_PINID='\dqs6_b_t||tdqs6_b_t\';
NET_NAME
'M_E_CPU0_SB_DQS_DP<7>'
 '@T6G_MB_LIB.T6G(SCH_1):M_E_CPU0_SB_DQS_DP'<7>:
 C_SIGNAL='@t6g_mb_lib.t6g(sch_1):m_e_cpu0_sb_dqs_dp(7)';
NODE_NAME     U25 CV69
 '@T6G_MB_LIB.T6G(SCH_1):PAGE14_I159@PURE_QUANTA.GENOA_SP5(CHIPS)':
 'MEB_DQS_H7': CDS_PINID='MEB_DQS_H7';
NODE_NAME     J21 272
 '@T6G_MB_LIB.T6G(SCH_1):PAGE89_I410@PURE_QUANTA.SCONN288_DDR506112002KQ(CHIPS)':
 'DQS7_B_T||TDQS7_B_T': CDS_PINID='\dqs7_b_t||tdqs7_b_t\';
NET_NAME
'M_E_CPU0_SB_DQS_DP<8>'
 '@T6G_MB_LIB.T6G(SCH_1):M_E_CPU0_SB_DQS_DP'<8>:
 C_SIGNAL='@t6g_mb_lib.t6g(sch_1):m_e_cpu0_sb_dqs_dp(8)';
NODE_NAME     U25 DD69
 '@T6G_MB_LIB.T6G(SCH_1):PAGE14_I159@PURE_QUANTA.GENOA_SP5(CHIPS)':
 'MEB_DQS_H8': CDS_PINID='MEB_DQS_H8';
NODE_NAME     J21 283
 '@T6G_MB_LIB.T6G(SCH_1):PAGE89_I410@PURE_QUANTA.SCONN288_DDR506112002KQ(CHIPS)':
 'DQS8_B_T||TDQS8_B_T': CDS_PINID='\dqs8_b_t||tdqs8_b_t\';
NET_NAME
'M_E_CPU0_SB_DQS_DP<9>'
 '@T6G_MB_LIB.T6G(SCH_1):M_E_CPU0_SB_DQS_DP'<9>:
 C_SIGNAL='@t6g_mb_lib.t6g(sch_1):m_e_cpu0_sb_dqs_dp(9)';
NODE_NAME     U25 BV70
 '@T6G_MB_LIB.T6G(SCH_1):PAGE14_I159@PURE_QUANTA.GENOA_SP5(CHIPS)':
 'MEB_DQS_H9': CDS_PINID='MEB_DQS_H9';
NODE_NAME     J21 93
 '@T6G_MB_LIB.T6G(SCH_1):PAGE89_I410@PURE_QUANTA.SCONN288_DDR506112002KQ(CHIPS)':
 'DQS9_B_T||TDQS9_B_T||DBI4_B_N': CDS_PINID='\dqs9_b_t||tdqs9_b_t||dbi4_b_n\';
NET_NAME
'M_E_CPU0_SB_PAR'
 '@T6G_MB_LIB.T6G(SCH_1):M_E_CPU0_SB_PAR':
 C_SIGNAL='@t6g_mb_lib.t6g(sch_1):m_e_cpu0_sb_par';
NODE_NAME     U25 BL71
 '@T6G_MB_LIB.T6G(SCH_1):PAGE14_I159@PURE_QUANTA.GENOA_SP5(CHIPS)':
 'MEB_PAR': CDS_PINID='MEB_PAR';
NODE_NAME     J21 227
 '@T6G_MB_LIB.T6G(SCH_1):PAGE89_I348@PURE_QUANTA.SCONN288_DDR506112002KQ(CHIPS)':
 'PAR_B': CDS_PINID='PAR_B';
NET_NAME
'M_E_CPU0_SB_RSP<0>'
 '@T6G_MB_LIB.T6G(SCH_1):M_E_CPU0_SB_RSP'<0>:
 C_SIGNAL='@t6g_mb_lib.t6g(sch_1):m_e_cpu0_sb_rsp(0)';
NODE_NAME     U25 BP70
 '@T6G_MB_LIB.T6G(SCH_1):PAGE14_I159@PURE_QUANTA.GENOA_SP5(CHIPS)':
 'MEB0_RSP_L': CDS_PINID='MEB0_RSP_L';
NODE_NAME     J21 87
 '@T6G_MB_LIB.T6G(SCH_1):PAGE89_I348@PURE_QUANTA.SCONN288_DDR506112002KQ(CHIPS)':
 'LBS||RSP_B_N': CDS_PINID='\lbs||rsp_b_n\';
NET_NAME
'M_E_CPU1_ALERT_N'
 '@T6G_MB_LIB.T6G(SCH_1):M_E_CPU1_ALERT_N':
 C_SIGNAL='@t6g_mb_lib.t6g(sch_1):m_e_cpu1_alert_n';
NODE_NAME     R504 1
 '@T6G_MB_LIB.T6G(SCH_1):PAGE41_I314@PURE_QUANTA.Q_RES(CHIPS)':
 'A': CDS_PINID='A';
NODE_NAME     J32 62
 '@T6G_MB_LIB.T6G(SCH_1):PAGE101_I52@PURE_QUANTA.SCONN288_DDR506112002KQ(CHIPS)':
 'ALERT_N': CDS_PINID='ALERT_N';
NET_NAME
'M_E_CPU1_ALERT_R_N'
 '@T6G_MB_LIB.T6G(SCH_1):M_E_CPU1_ALERT_R_N':
 C_SIGNAL='@t6g_mb_lib.t6g(sch_1):m_e_cpu1_alert_r_n';
NODE_NAME     U26 AT69
 '@T6G_MB_LIB.T6G(SCH_1):PAGE41_I159@PURE_QUANTA.GENOA_SP5(CHIPS)':
 'ME_ALERT_L': CDS_PINID='ME_ALERT_L';
NODE_NAME     R504 2
 '@T6G_MB_LIB.T6G(SCH_1):PAGE41_I314@PURE_QUANTA.Q_RES(CHIPS)':
 'B': CDS_PINID='B';
NET_NAME
'M_E_CPU1_CLK_DN<0>'
 '@T6G_MB_LIB.T6G(SCH_1):M_E_CPU1_CLK_DN'<0>:
 C_SIGNAL='@t6g_mb_lib.t6g(sch_1):m_e_cpu1_clk_dn(0)';
NODE_NAME     U26 BD70
 '@T6G_MB_LIB.T6G(SCH_1):PAGE41_I159@PURE_QUANTA.GENOA_SP5(CHIPS)':
 'ME0_CLK_L': CDS_PINID='ME0_CLK_L';
NODE_NAME     J32 218
 '@T6G_MB_LIB.T6G(SCH_1):PAGE101_I52@PURE_QUANTA.SCONN288_DDR506112002KQ(CHIPS)':
 'CK_C': CDS_PINID='CK_C';
NET_NAME
'M_E_CPU1_CLK_DP<0>'
 '@T6G_MB_LIB.T6G(SCH_1):M_E_CPU1_CLK_DP'<0>:
 C_SIGNAL='@t6g_mb_lib.t6g(sch_1):m_e_cpu1_clk_dp(0)';
NODE_NAME     U26 BC71
 '@T6G_MB_LIB.T6G(SCH_1):PAGE41_I159@PURE_QUANTA.GENOA_SP5(CHIPS)':
 'ME0_CLK_H': CDS_PINID='ME0_CLK_H';
NODE_NAME     J32 217
 '@T6G_MB_LIB.T6G(SCH_1):PAGE101_I52@PURE_QUANTA.SCONN288_DDR506112002KQ(CHIPS)':
 'CK_T': CDS_PINID='CK_T';
NET_NAME
'M_E_CPU1_RESET_N'
 '@T6G_MB_LIB.T6G(SCH_1):M_E_CPU1_RESET_N':
 C_SIGNAL='@t6g_mb_lib.t6g(sch_1):m_e_cpu1_reset_n';
NODE_NAME     U26 AU69
 '@T6G_MB_LIB.T6G(SCH_1):PAGE41_I159@PURE_QUANTA.GENOA_SP5(CHIPS)':
 'ME_RESET_L': CDS_PINID='ME_RESET_L';
NODE_NAME     J32 207
 '@T6G_MB_LIB.T6G(SCH_1):PAGE101_I52@PURE_QUANTA.SCONN288_DDR506112002KQ(CHIPS)':
 'RESET_N': CDS_PINID='RESET_N';
NET_NAME
'M_E_CPU1_SA_CA<0>'
 '@T6G_MB_LIB.T6G(SCH_1):M_E_CPU1_SA_CA'<0>:
 C_SIGNAL='@t6g_mb_lib.t6g(sch_1):m_e_cpu1_sa_ca(0)';
NODE_NAME     U26 AW71
 '@T6G_MB_LIB.T6G(SCH_1):PAGE41_I159@PURE_QUANTA.GENOA_SP5(CHIPS)':
 'MEA_CA0': CDS_PINID='MEA_CA0';
NODE_NAME     J32 66
 '@T6G_MB_LIB.T6G(SCH_1):PAGE101_I52@PURE_QUANTA.SCONN288_DDR506112002KQ(CHIPS)':
 'CA0_A': CDS_PINID='CA0_A';
NET_NAME
'M_E_CPU1_SA_CA<1>'
 '@T6G_MB_LIB.T6G(SCH_1):M_E_CPU1_SA_CA'<1>:
 C_SIGNAL='@t6g_mb_lib.t6g(sch_1):m_e_cpu1_sa_ca(1)';
NODE_NAME     U26 AY70
 '@T6G_MB_LIB.T6G(SCH_1):PAGE41_I159@PURE_QUANTA.GENOA_SP5(CHIPS)':
 'MEA_CA1': CDS_PINID='MEA_CA1';
NODE_NAME     J32 211
 '@T6G_MB_LIB.T6G(SCH_1):PAGE101_I52@PURE_QUANTA.SCONN288_DDR506112002KQ(CHIPS)':
 'CA1_A': CDS_PINID='CA1_A';
NET_NAME
'M_E_CPU1_SA_CA<2>'
 '@T6G_MB_LIB.T6G(SCH_1):M_E_CPU1_SA_CA'<2>:
 C_SIGNAL='@t6g_mb_lib.t6g(sch_1):m_e_cpu1_sa_ca(2)';
NODE_NAME     U26 AY69
 '@T6G_MB_LIB.T6G(SCH_1):PAGE41_I159@PURE_QUANTA.GENOA_SP5(CHIPS)':
 'MEA_CA2': CDS_PINID='MEA_CA2';
NODE_NAME     J32 68
 '@T6G_MB_LIB.T6G(SCH_1):PAGE101_I52@PURE_QUANTA.SCONN288_DDR506112002KQ(CHIPS)':
 'CA2_A': CDS_PINID='CA2_A';
NET_NAME
'M_E_CPU1_SA_CA<3>'
 '@T6G_MB_LIB.T6G(SCH_1):M_E_CPU1_SA_CA'<3>:
 C_SIGNAL='@t6g_mb_lib.t6g(sch_1):m_e_cpu1_sa_ca(3)';
NODE_NAME     U26 BA69
 '@T6G_MB_LIB.T6G(SCH_1):PAGE41_I159@PURE_QUANTA.GENOA_SP5(CHIPS)':
 'MEA_CA3': CDS_PINID='MEA_CA3';
NODE_NAME     J32 213
 '@T6G_MB_LIB.T6G(SCH_1):PAGE101_I52@PURE_QUANTA.SCONN288_DDR506112002KQ(CHIPS)':
 'CA3_A': CDS_PINID='CA3_A';
NET_NAME
'M_E_CPU1_SA_CA<4>'
 '@T6G_MB_LIB.T6G(SCH_1):M_E_CPU1_SA_CA'<4>:
 C_SIGNAL='@t6g_mb_lib.t6g(sch_1):m_e_cpu1_sa_ca(4)';
NODE_NAME     U26 BA71
 '@T6G_MB_LIB.T6G(SCH_1):PAGE41_I159@PURE_QUANTA.GENOA_SP5(CHIPS)':
 'MEA_CA4': CDS_PINID='MEA_CA4';
NODE_NAME     J32 70
 '@T6G_MB_LIB.T6G(SCH_1):PAGE101_I52@PURE_QUANTA.SCONN288_DDR506112002KQ(CHIPS)':
 'CA4_A': CDS_PINID='CA4_A';
NET_NAME
'M_E_CPU1_SA_CA<5>'
 '@T6G_MB_LIB.T6G(SCH_1):M_E_CPU1_SA_CA'<5>:
 C_SIGNAL='@t6g_mb_lib.t6g(sch_1):m_e_cpu1_sa_ca(5)';
NODE_NAME     U26 BB70
 '@T6G_MB_LIB.T6G(SCH_1):PAGE41_I159@PURE_QUANTA.GENOA_SP5(CHIPS)':
 'MEA_CA5': CDS_PINID='MEA_CA5';
NODE_NAME     J32 215
 '@T6G_MB_LIB.T6G(SCH_1):PAGE101_I52@PURE_QUANTA.SCONN288_DDR506112002KQ(CHIPS)':
 'CA5_A': CDS_PINID='CA5_A';
NET_NAME
'M_E_CPU1_SA_CA<6>'
 '@T6G_MB_LIB.T6G(SCH_1):M_E_CPU1_SA_CA'<6>:
 C_SIGNAL='@t6g_mb_lib.t6g(sch_1):m_e_cpu1_sa_ca(6)';
NODE_NAME     U26 BB69
 '@T6G_MB_LIB.T6G(SCH_1):PAGE41_I159@PURE_QUANTA.GENOA_SP5(CHIPS)':
 'MEA_CA6': CDS_PINID='MEA_CA6';
NODE_NAME     J32 72
 '@T6G_MB_LIB.T6G(SCH_1):PAGE101_I52@PURE_QUANTA.SCONN288_DDR506112002KQ(CHIPS)':
 'CA6_A': CDS_PINID='CA6_A';
NET_NAME
'M_E_CPU1_SA_CB<0>'
 '@T6G_MB_LIB.T6G(SCH_1):M_E_CPU1_SA_CB'<0>:
 C_SIGNAL='@t6g_mb_lib.t6g(sch_1):m_e_cpu1_sa_cb(0)';
NODE_NAME     U26 AJ71
 '@T6G_MB_LIB.T6G(SCH_1):PAGE41_I159@PURE_QUANTA.GENOA_SP5(CHIPS)':
 'MEA_CHECK0': CDS_PINID='MEA_CHECK0';
NODE_NAME     J32 51
 '@T6G_MB_LIB.T6G(SCH_1):PAGE101_I52@PURE_QUANTA.SCONN288_DDR506112002KQ(CHIPS)':
 'CB0_A': CDS_PINID='CB0_A';
NET_NAME
'M_E_CPU1_SA_CB<1>'
 '@T6G_MB_LIB.T6G(SCH_1):M_E_CPU1_SA_CB'<1>:
 C_SIGNAL='@t6g_mb_lib.t6g(sch_1):m_e_cpu1_sa_cb(1)';
NODE_NAME     U26 AK69
 '@T6G_MB_LIB.T6G(SCH_1):PAGE41_I159@PURE_QUANTA.GENOA_SP5(CHIPS)':
 'MEA_CHECK1': CDS_PINID='MEA_CHECK1';
NODE_NAME     J32 53
 '@T6G_MB_LIB.T6G(SCH_1):PAGE101_I52@PURE_QUANTA.SCONN288_DDR506112002KQ(CHIPS)':
 'CB1_A': CDS_PINID='CB1_A';
NET_NAME
'M_E_CPU1_SA_CB<2>'
 '@T6G_MB_LIB.T6G(SCH_1):M_E_CPU1_SA_CB'<2>:
 C_SIGNAL='@t6g_mb_lib.t6g(sch_1):m_e_cpu1_sa_cb(2)';
NODE_NAME     U26 AK70
 '@T6G_MB_LIB.T6G(SCH_1):PAGE41_I159@PURE_QUANTA.GENOA_SP5(CHIPS)':
 'MEA_CHECK2': CDS_PINID='MEA_CHECK2';
NODE_NAME     J32 196
 '@T6G_MB_LIB.T6G(SCH_1):PAGE101_I52@PURE_QUANTA.SCONN288_DDR506112002KQ(CHIPS)':
 'CB2_A': CDS_PINID='CB2_A';
NET_NAME
'M_E_CPU1_SA_CB<3>'
 '@T6G_MB_LIB.T6G(SCH_1):M_E_CPU1_SA_CB'<3>:
 C_SIGNAL='@t6g_mb_lib.t6g(sch_1):m_e_cpu1_sa_cb(3)';
NODE_NAME     U26 AL69
 '@T6G_MB_LIB.T6G(SCH_1):PAGE41_I159@PURE_QUANTA.GENOA_SP5(CHIPS)':
 'MEA_CHECK3': CDS_PINID='MEA_CHECK3';
NODE_NAME     J32 198
 '@T6G_MB_LIB.T6G(SCH_1):PAGE101_I52@PURE_QUANTA.SCONN288_DDR506112002KQ(CHIPS)':
 'CB3_A': CDS_PINID='CB3_A';
NET_NAME
'M_E_CPU1_SA_CB<4>'
 '@T6G_MB_LIB.T6G(SCH_1):M_E_CPU1_SA_CB'<4>:
 C_SIGNAL='@t6g_mb_lib.t6g(sch_1):m_e_cpu1_sa_cb(4)';
NODE_NAME     U26 AN71
 '@T6G_MB_LIB.T6G(SCH_1):PAGE41_I159@PURE_QUANTA.GENOA_SP5(CHIPS)':
 'MEA_CHECK4': CDS_PINID='MEA_CHECK4';
NODE_NAME     J32 58
 '@T6G_MB_LIB.T6G(SCH_1):PAGE101_I52@PURE_QUANTA.SCONN288_DDR506112002KQ(CHIPS)':
 'CB4_A': CDS_PINID='CB4_A';
NET_NAME
'M_E_CPU1_SA_CB<5>'
 '@T6G_MB_LIB.T6G(SCH_1):M_E_CPU1_SA_CB'<5>:
 C_SIGNAL='@t6g_mb_lib.t6g(sch_1):m_e_cpu1_sa_cb(5)';
NODE_NAME     U26 AP69
 '@T6G_MB_LIB.T6G(SCH_1):PAGE41_I159@PURE_QUANTA.GENOA_SP5(CHIPS)':
 'MEA_CHECK5': CDS_PINID='MEA_CHECK5';
NODE_NAME     J32 60
 '@T6G_MB_LIB.T6G(SCH_1):PAGE101_I52@PURE_QUANTA.SCONN288_DDR506112002KQ(CHIPS)':
 'CB5_A': CDS_PINID='CB5_A';
NET_NAME
'M_E_CPU1_SA_CB<6>'
 '@T6G_MB_LIB.T6G(SCH_1):M_E_CPU1_SA_CB'<6>:
 C_SIGNAL='@t6g_mb_lib.t6g(sch_1):m_e_cpu1_sa_cb(6)';
NODE_NAME     U26 AP70
 '@T6G_MB_LIB.T6G(SCH_1):PAGE41_I159@PURE_QUANTA.GENOA_SP5(CHIPS)':
 'MEA_CHECK6': CDS_PINID='MEA_CHECK6';
NODE_NAME     J32 203
 '@T6G_MB_LIB.T6G(SCH_1):PAGE101_I52@PURE_QUANTA.SCONN288_DDR506112002KQ(CHIPS)':
 'CB6_A': CDS_PINID='CB6_A';
NET_NAME
'M_E_CPU1_SA_CB<7>'
 '@T6G_MB_LIB.T6G(SCH_1):M_E_CPU1_SA_CB'<7>:
 C_SIGNAL='@t6g_mb_lib.t6g(sch_1):m_e_cpu1_sa_cb(7)';
NODE_NAME     U26 AR69
 '@T6G_MB_LIB.T6G(SCH_1):PAGE41_I159@PURE_QUANTA.GENOA_SP5(CHIPS)':
 'MEA_CHECK7': CDS_PINID='MEA_CHECK7';
NODE_NAME     J32 205
 '@T6G_MB_LIB.T6G(SCH_1):PAGE101_I52@PURE_QUANTA.SCONN288_DDR506112002KQ(CHIPS)':
 'CB7_A': CDS_PINID='CB7_A';
NET_NAME
'M_E_CPU1_SA_CS_N<0>'
 '@T6G_MB_LIB.T6G(SCH_1):M_E_CPU1_SA_CS_N'<0>:
 C_SIGNAL='@t6g_mb_lib.t6g(sch_1):m_e_cpu1_sa_cs_n(0)';
NODE_NAME     U26 AV70
 '@T6G_MB_LIB.T6G(SCH_1):PAGE41_I159@PURE_QUANTA.GENOA_SP5(CHIPS)':
 'MEA0_CS_L0': CDS_PINID='MEA0_CS_L0';
NODE_NAME     J32 64
 '@T6G_MB_LIB.T6G(SCH_1):PAGE101_I52@PURE_QUANTA.SCONN288_DDR506112002KQ(CHIPS)':
 'CS0_A_N': CDS_PINID='CS0_A_N';
NET_NAME
'M_E_CPU1_SA_CS_N<1>'
 '@T6G_MB_LIB.T6G(SCH_1):M_E_CPU1_SA_CS_N'<1>:
 C_SIGNAL='@t6g_mb_lib.t6g(sch_1):m_e_cpu1_sa_cs_n(1)';
NODE_NAME     U26 AW69
 '@T6G_MB_LIB.T6G(SCH_1):PAGE41_I159@PURE_QUANTA.GENOA_SP5(CHIPS)':
 'MEA0_CS_L1': CDS_PINID='MEA0_CS_L1';
NODE_NAME     J32 209
 '@T6G_MB_LIB.T6G(SCH_1):PAGE101_I52@PURE_QUANTA.SCONN288_DDR506112002KQ(CHIPS)':
 'CS1_A_N': CDS_PINID='CS1_A_N';
NET_NAME
'M_E_CPU1_SA_DQ<0>'
 '@T6G_MB_LIB.T6G(SCH_1):M_E_CPU1_SA_DQ'<0>:
 C_SIGNAL='@t6g_mb_lib.t6g(sch_1):m_e_cpu1_sa_dq(0)';
NODE_NAME     U26 E71
 '@T6G_MB_LIB.T6G(SCH_1):PAGE41_I159@PURE_QUANTA.GENOA_SP5(CHIPS)':
 'MEA_DATA0': CDS_PINID='MEA_DATA0';
NODE_NAME     J32 7
 '@T6G_MB_LIB.T6G(SCH_1):PAGE101_I52@PURE_QUANTA.SCONN288_DDR506112002KQ(CHIPS)':
 'DQ0_A': CDS_PINID='DQ0_A';
NET_NAME
'M_E_CPU1_SA_DQ<10>'
 '@T6G_MB_LIB.T6G(SCH_1):M_E_CPU1_SA_DQ'<10>:
 C_SIGNAL='@t6g_mb_lib.t6g(sch_1):m_e_cpu1_sa_dq(10)';
NODE_NAME     U26 M70
 '@T6G_MB_LIB.T6G(SCH_1):PAGE41_I159@PURE_QUANTA.GENOA_SP5(CHIPS)':
 'MEA_DATA10': CDS_PINID='MEA_DATA10';
NODE_NAME     J32 163
 '@T6G_MB_LIB.T6G(SCH_1):PAGE101_I52@PURE_QUANTA.SCONN288_DDR506112002KQ(CHIPS)':
 'DQ10_A': CDS_PINID='DQ10_A';
NET_NAME
'M_E_CPU1_SA_DQ<11>'
 '@T6G_MB_LIB.T6G(SCH_1):M_E_CPU1_SA_DQ'<11>:
 C_SIGNAL='@t6g_mb_lib.t6g(sch_1):m_e_cpu1_sa_dq(11)';
NODE_NAME     U26 N69
 '@T6G_MB_LIB.T6G(SCH_1):PAGE41_I159@PURE_QUANTA.GENOA_SP5(CHIPS)':
 'MEA_DATA11': CDS_PINID='MEA_DATA11';
NODE_NAME     J32 165
 '@T6G_MB_LIB.T6G(SCH_1):PAGE101_I52@PURE_QUANTA.SCONN288_DDR506112002KQ(CHIPS)':
 'DQ11_A': CDS_PINID='DQ11_A';
NET_NAME
'M_E_CPU1_SA_DQ<12>'
 '@T6G_MB_LIB.T6G(SCH_1):M_E_CPU1_SA_DQ'<12>:
 C_SIGNAL='@t6g_mb_lib.t6g(sch_1):m_e_cpu1_sa_dq(12)';
NODE_NAME     U26 R71
 '@T6G_MB_LIB.T6G(SCH_1):PAGE41_I159@PURE_QUANTA.GENOA_SP5(CHIPS)':
 'MEA_DATA12': CDS_PINID='MEA_DATA12';
NODE_NAME     J32 25
 '@T6G_MB_LIB.T6G(SCH_1):PAGE101_I52@PURE_QUANTA.SCONN288_DDR506112002KQ(CHIPS)':
 'DQ12_A': CDS_PINID='DQ12_A';
NET_NAME
'M_E_CPU1_SA_DQ<13>'
 '@T6G_MB_LIB.T6G(SCH_1):M_E_CPU1_SA_DQ'<13>:
 C_SIGNAL='@t6g_mb_lib.t6g(sch_1):m_e_cpu1_sa_dq(13)';
NODE_NAME     U26 T69
 '@T6G_MB_LIB.T6G(SCH_1):PAGE41_I159@PURE_QUANTA.GENOA_SP5(CHIPS)':
 'MEA_DATA13': CDS_PINID='MEA_DATA13';
NODE_NAME     J32 27
 '@T6G_MB_LIB.T6G(SCH_1):PAGE101_I52@PURE_QUANTA.SCONN288_DDR506112002KQ(CHIPS)':
 'DQ13_A': CDS_PINID='DQ13_A';
NET_NAME
'M_E_CPU1_SA_DQ<14>'
 '@T6G_MB_LIB.T6G(SCH_1):M_E_CPU1_SA_DQ'<14>:
 C_SIGNAL='@t6g_mb_lib.t6g(sch_1):m_e_cpu1_sa_dq(14)';
NODE_NAME     U26 T70
 '@T6G_MB_LIB.T6G(SCH_1):PAGE41_I159@PURE_QUANTA.GENOA_SP5(CHIPS)':
 'MEA_DATA14': CDS_PINID='MEA_DATA14';
NODE_NAME     J32 170
 '@T6G_MB_LIB.T6G(SCH_1):PAGE101_I52@PURE_QUANTA.SCONN288_DDR506112002KQ(CHIPS)':
 'DQ14_A': CDS_PINID='DQ14_A';
NET_NAME
'M_E_CPU1_SA_DQ<15>'
 '@T6G_MB_LIB.T6G(SCH_1):M_E_CPU1_SA_DQ'<15>:
 C_SIGNAL='@t6g_mb_lib.t6g(sch_1):m_e_cpu1_sa_dq(15)';
NODE_NAME     U26 U69
 '@T6G_MB_LIB.T6G(SCH_1):PAGE41_I159@PURE_QUANTA.GENOA_SP5(CHIPS)':
 'MEA_DATA15': CDS_PINID='MEA_DATA15';
NODE_NAME     J32 172
 '@T6G_MB_LIB.T6G(SCH_1):PAGE101_I52@PURE_QUANTA.SCONN288_DDR506112002KQ(CHIPS)':
 'DQ15_A': CDS_PINID='DQ15_A';
NET_NAME
'M_E_CPU1_SA_DQ<16>'
 '@T6G_MB_LIB.T6G(SCH_1):M_E_CPU1_SA_DQ'<16>:
 C_SIGNAL='@t6g_mb_lib.t6g(sch_1):m_e_cpu1_sa_dq(16)';
NODE_NAME     U26 U71
 '@T6G_MB_LIB.T6G(SCH_1):PAGE41_I159@PURE_QUANTA.GENOA_SP5(CHIPS)':
 'MEA_DATA16': CDS_PINID='MEA_DATA16';
NODE_NAME     J32 29
 '@T6G_MB_LIB.T6G(SCH_1):PAGE101_I52@PURE_QUANTA.SCONN288_DDR506112002KQ(CHIPS)':
 'DQ16_A': CDS_PINID='DQ16_A';
NET_NAME
'M_E_CPU1_SA_DQ<17>'
 '@T6G_MB_LIB.T6G(SCH_1):M_E_CPU1_SA_DQ'<17>:
 C_SIGNAL='@t6g_mb_lib.t6g(sch_1):m_e_cpu1_sa_dq(17)';
NODE_NAME     U26 V69
 '@T6G_MB_LIB.T6G(SCH_1):PAGE41_I159@PURE_QUANTA.GENOA_SP5(CHIPS)':
 'MEA_DATA17': CDS_PINID='MEA_DATA17';
NODE_NAME     J32 31
 '@T6G_MB_LIB.T6G(SCH_1):PAGE101_I52@PURE_QUANTA.SCONN288_DDR506112002KQ(CHIPS)':
 'DQ17_A': CDS_PINID='DQ17_A';
NET_NAME
'M_E_CPU1_SA_DQ<18>'
 '@T6G_MB_LIB.T6G(SCH_1):M_E_CPU1_SA_DQ'<18>:
 C_SIGNAL='@t6g_mb_lib.t6g(sch_1):m_e_cpu1_sa_dq(18)';
NODE_NAME     U26 V70
 '@T6G_MB_LIB.T6G(SCH_1):PAGE41_I159@PURE_QUANTA.GENOA_SP5(CHIPS)':
 'MEA_DATA18': CDS_PINID='MEA_DATA18';
NODE_NAME     J32 174
 '@T6G_MB_LIB.T6G(SCH_1):PAGE101_I52@PURE_QUANTA.SCONN288_DDR506112002KQ(CHIPS)':
 'DQ18_A': CDS_PINID='DQ18_A';
NET_NAME
'M_E_CPU1_SA_DQ<19>'
 '@T6G_MB_LIB.T6G(SCH_1):M_E_CPU1_SA_DQ'<19>:
 C_SIGNAL='@t6g_mb_lib.t6g(sch_1):m_e_cpu1_sa_dq(19)';
NODE_NAME     U26 W69
 '@T6G_MB_LIB.T6G(SCH_1):PAGE41_I159@PURE_QUANTA.GENOA_SP5(CHIPS)':
 'MEA_DATA19': CDS_PINID='MEA_DATA19';
NODE_NAME     J32 176
 '@T6G_MB_LIB.T6G(SCH_1):PAGE101_I52@PURE_QUANTA.SCONN288_DDR506112002KQ(CHIPS)':
 'DQ19_A': CDS_PINID='DQ19_A';
NET_NAME
'M_E_CPU1_SA_DQ<1>'
 '@T6G_MB_LIB.T6G(SCH_1):M_E_CPU1_SA_DQ'<1>:
 C_SIGNAL='@t6g_mb_lib.t6g(sch_1):m_e_cpu1_sa_dq(1)';
NODE_NAME     U26 F69
 '@T6G_MB_LIB.T6G(SCH_1):PAGE41_I159@PURE_QUANTA.GENOA_SP5(CHIPS)':
 'MEA_DATA1': CDS_PINID='MEA_DATA1';
NODE_NAME     J32 9
 '@T6G_MB_LIB.T6G(SCH_1):PAGE101_I52@PURE_QUANTA.SCONN288_DDR506112002KQ(CHIPS)':
 'DQ1_A': CDS_PINID='DQ1_A';
NET_NAME
'M_E_CPU1_SA_DQ<20>'
 '@T6G_MB_LIB.T6G(SCH_1):M_E_CPU1_SA_DQ'<20>:
 C_SIGNAL='@t6g_mb_lib.t6g(sch_1):m_e_cpu1_sa_dq(20)';
NODE_NAME     U26 AA71
 '@T6G_MB_LIB.T6G(SCH_1):PAGE41_I159@PURE_QUANTA.GENOA_SP5(CHIPS)':
 'MEA_DATA20': CDS_PINID='MEA_DATA20';
NODE_NAME     J32 36
 '@T6G_MB_LIB.T6G(SCH_1):PAGE101_I52@PURE_QUANTA.SCONN288_DDR506112002KQ(CHIPS)':
 'DQ20_A': CDS_PINID='DQ20_A';
NET_NAME
'M_E_CPU1_SA_DQ<21>'
 '@T6G_MB_LIB.T6G(SCH_1):M_E_CPU1_SA_DQ'<21>:
 C_SIGNAL='@t6g_mb_lib.t6g(sch_1):m_e_cpu1_sa_dq(21)';
NODE_NAME     U26 AB69
 '@T6G_MB_LIB.T6G(SCH_1):PAGE41_I159@PURE_QUANTA.GENOA_SP5(CHIPS)':
 'MEA_DATA21': CDS_PINID='MEA_DATA21';
NODE_NAME     J32 38
 '@T6G_MB_LIB.T6G(SCH_1):PAGE101_I52@PURE_QUANTA.SCONN288_DDR506112002KQ(CHIPS)':
 'DQ21_A': CDS_PINID='DQ21_A';
NET_NAME
'M_E_CPU1_SA_DQ<22>'
 '@T6G_MB_LIB.T6G(SCH_1):M_E_CPU1_SA_DQ'<22>:
 C_SIGNAL='@t6g_mb_lib.t6g(sch_1):m_e_cpu1_sa_dq(22)';
NODE_NAME     U26 AB70
 '@T6G_MB_LIB.T6G(SCH_1):PAGE41_I159@PURE_QUANTA.GENOA_SP5(CHIPS)':
 'MEA_DATA22': CDS_PINID='MEA_DATA22';
NODE_NAME     J32 181
 '@T6G_MB_LIB.T6G(SCH_1):PAGE101_I52@PURE_QUANTA.SCONN288_DDR506112002KQ(CHIPS)':
 'DQ22_A': CDS_PINID='DQ22_A';
NET_NAME
'M_E_CPU1_SA_DQ<23>'
 '@T6G_MB_LIB.T6G(SCH_1):M_E_CPU1_SA_DQ'<23>:
 C_SIGNAL='@t6g_mb_lib.t6g(sch_1):m_e_cpu1_sa_dq(23)';
NODE_NAME     U26 AC69
 '@T6G_MB_LIB.T6G(SCH_1):PAGE41_I159@PURE_QUANTA.GENOA_SP5(CHIPS)':
 'MEA_DATA23': CDS_PINID='MEA_DATA23';
NODE_NAME     J32 183
 '@T6G_MB_LIB.T6G(SCH_1):PAGE101_I52@PURE_QUANTA.SCONN288_DDR506112002KQ(CHIPS)':
 'DQ23_A': CDS_PINID='DQ23_A';
NET_NAME
'M_E_CPU1_SA_DQ<24>'
 '@T6G_MB_LIB.T6G(SCH_1):M_E_CPU1_SA_DQ'<24>:
 C_SIGNAL='@t6g_mb_lib.t6g(sch_1):m_e_cpu1_sa_dq(24)';
NODE_NAME     U26 AC71
 '@T6G_MB_LIB.T6G(SCH_1):PAGE41_I159@PURE_QUANTA.GENOA_SP5(CHIPS)':
 'MEA_DATA24': CDS_PINID='MEA_DATA24';
NODE_NAME     J32 40
 '@T6G_MB_LIB.T6G(SCH_1):PAGE101_I52@PURE_QUANTA.SCONN288_DDR506112002KQ(CHIPS)':
 'DQ24_A': CDS_PINID='DQ24_A';
NET_NAME
'M_E_CPU1_SA_DQ<25>'
 '@T6G_MB_LIB.T6G(SCH_1):M_E_CPU1_SA_DQ'<25>:
 C_SIGNAL='@t6g_mb_lib.t6g(sch_1):m_e_cpu1_sa_dq(25)';
NODE_NAME     U26 AD69
 '@T6G_MB_LIB.T6G(SCH_1):PAGE41_I159@PURE_QUANTA.GENOA_SP5(CHIPS)':
 'MEA_DATA25': CDS_PINID='MEA_DATA25';
NODE_NAME     J32 42
 '@T6G_MB_LIB.T6G(SCH_1):PAGE101_I52@PURE_QUANTA.SCONN288_DDR506112002KQ(CHIPS)':
 'DQ25_A': CDS_PINID='DQ25_A';
NET_NAME
'M_E_CPU1_SA_DQ<26>'
 '@T6G_MB_LIB.T6G(SCH_1):M_E_CPU1_SA_DQ'<26>:
 C_SIGNAL='@t6g_mb_lib.t6g(sch_1):m_e_cpu1_sa_dq(26)';
NODE_NAME     U26 AD70
 '@T6G_MB_LIB.T6G(SCH_1):PAGE41_I159@PURE_QUANTA.GENOA_SP5(CHIPS)':
 'MEA_DATA26': CDS_PINID='MEA_DATA26';
NODE_NAME     J32 185
 '@T6G_MB_LIB.T6G(SCH_1):PAGE101_I52@PURE_QUANTA.SCONN288_DDR506112002KQ(CHIPS)':
 'DQ26_A': CDS_PINID='DQ26_A';
NET_NAME
'M_E_CPU1_SA_DQ<27>'
 '@T6G_MB_LIB.T6G(SCH_1):M_E_CPU1_SA_DQ'<27>:
 C_SIGNAL='@t6g_mb_lib.t6g(sch_1):m_e_cpu1_sa_dq(27)';
NODE_NAME     U26 AE69
 '@T6G_MB_LIB.T6G(SCH_1):PAGE41_I159@PURE_QUANTA.GENOA_SP5(CHIPS)':
 'MEA_DATA27': CDS_PINID='MEA_DATA27';
NODE_NAME     J32 187
 '@T6G_MB_LIB.T6G(SCH_1):PAGE101_I52@PURE_QUANTA.SCONN288_DDR506112002KQ(CHIPS)':
 'DQ27_A': CDS_PINID='DQ27_A';
NET_NAME
'M_E_CPU1_SA_DQ<28>'
 '@T6G_MB_LIB.T6G(SCH_1):M_E_CPU1_SA_DQ'<28>:
 C_SIGNAL='@t6g_mb_lib.t6g(sch_1):m_e_cpu1_sa_dq(28)';
NODE_NAME     U26 AG71
 '@T6G_MB_LIB.T6G(SCH_1):PAGE41_I159@PURE_QUANTA.GENOA_SP5(CHIPS)':
 'MEA_DATA28': CDS_PINID='MEA_DATA28';
NODE_NAME     J32 47
 '@T6G_MB_LIB.T6G(SCH_1):PAGE101_I52@PURE_QUANTA.SCONN288_DDR506112002KQ(CHIPS)':
 'DQ28_A': CDS_PINID='DQ28_A';
NET_NAME
'M_E_CPU1_SA_DQ<29>'
 '@T6G_MB_LIB.T6G(SCH_1):M_E_CPU1_SA_DQ'<29>:
 C_SIGNAL='@t6g_mb_lib.t6g(sch_1):m_e_cpu1_sa_dq(29)';
NODE_NAME     U26 AH69
 '@T6G_MB_LIB.T6G(SCH_1):PAGE41_I159@PURE_QUANTA.GENOA_SP5(CHIPS)':
 'MEA_DATA29': CDS_PINID='MEA_DATA29';
NODE_NAME     J32 49
 '@T6G_MB_LIB.T6G(SCH_1):PAGE101_I52@PURE_QUANTA.SCONN288_DDR506112002KQ(CHIPS)':
 'DQ29_A': CDS_PINID='DQ29_A';
NET_NAME
'M_E_CPU1_SA_DQ<2>'
 '@T6G_MB_LIB.T6G(SCH_1):M_E_CPU1_SA_DQ'<2>:
 C_SIGNAL='@t6g_mb_lib.t6g(sch_1):m_e_cpu1_sa_dq(2)';
NODE_NAME     U26 F70
 '@T6G_MB_LIB.T6G(SCH_1):PAGE41_I159@PURE_QUANTA.GENOA_SP5(CHIPS)':
 'MEA_DATA2': CDS_PINID='MEA_DATA2';
NODE_NAME     J32 152
 '@T6G_MB_LIB.T6G(SCH_1):PAGE101_I52@PURE_QUANTA.SCONN288_DDR506112002KQ(CHIPS)':
 'DQ2_A': CDS_PINID='DQ2_A';
NET_NAME
'M_E_CPU1_SA_DQ<30>'
 '@T6G_MB_LIB.T6G(SCH_1):M_E_CPU1_SA_DQ'<30>:
 C_SIGNAL='@t6g_mb_lib.t6g(sch_1):m_e_cpu1_sa_dq(30)';
NODE_NAME     U26 AH70
 '@T6G_MB_LIB.T6G(SCH_1):PAGE41_I159@PURE_QUANTA.GENOA_SP5(CHIPS)':
 'MEA_DATA30': CDS_PINID='MEA_DATA30';
NODE_NAME     J32 192
 '@T6G_MB_LIB.T6G(SCH_1):PAGE101_I52@PURE_QUANTA.SCONN288_DDR506112002KQ(CHIPS)':
 'DQ30_A': CDS_PINID='DQ30_A';
NET_NAME
'M_E_CPU1_SA_DQ<31>'
 '@T6G_MB_LIB.T6G(SCH_1):M_E_CPU1_SA_DQ'<31>:
 C_SIGNAL='@t6g_mb_lib.t6g(sch_1):m_e_cpu1_sa_dq(31)';
NODE_NAME     U26 AJ69
 '@T6G_MB_LIB.T6G(SCH_1):PAGE41_I159@PURE_QUANTA.GENOA_SP5(CHIPS)':
 'MEA_DATA31': CDS_PINID='MEA_DATA31';
NODE_NAME     J32 194
 '@T6G_MB_LIB.T6G(SCH_1):PAGE101_I52@PURE_QUANTA.SCONN288_DDR506112002KQ(CHIPS)':
 'DQ31_A': CDS_PINID='DQ31_A';
NET_NAME
'M_E_CPU1_SA_DQ<3>'
 '@T6G_MB_LIB.T6G(SCH_1):M_E_CPU1_SA_DQ'<3>:
 C_SIGNAL='@t6g_mb_lib.t6g(sch_1):m_e_cpu1_sa_dq(3)';
NODE_NAME     U26 G69
 '@T6G_MB_LIB.T6G(SCH_1):PAGE41_I159@PURE_QUANTA.GENOA_SP5(CHIPS)':
 'MEA_DATA3': CDS_PINID='MEA_DATA3';
NODE_NAME     J32 154
 '@T6G_MB_LIB.T6G(SCH_1):PAGE101_I52@PURE_QUANTA.SCONN288_DDR506112002KQ(CHIPS)':
 'DQ3_A': CDS_PINID='DQ3_A';
NET_NAME
'M_E_CPU1_SA_DQ<4>'
 '@T6G_MB_LIB.T6G(SCH_1):M_E_CPU1_SA_DQ'<4>:
 C_SIGNAL='@t6g_mb_lib.t6g(sch_1):m_e_cpu1_sa_dq(4)';
NODE_NAME     U26 J71
 '@T6G_MB_LIB.T6G(SCH_1):PAGE41_I159@PURE_QUANTA.GENOA_SP5(CHIPS)':
 'MEA_DATA4': CDS_PINID='MEA_DATA4';
NODE_NAME     J32 14
 '@T6G_MB_LIB.T6G(SCH_1):PAGE101_I52@PURE_QUANTA.SCONN288_DDR506112002KQ(CHIPS)':
 'DQ4_A': CDS_PINID='DQ4_A';
NET_NAME
'M_E_CPU1_SA_DQ<5>'
 '@T6G_MB_LIB.T6G(SCH_1):M_E_CPU1_SA_DQ'<5>:
 C_SIGNAL='@t6g_mb_lib.t6g(sch_1):m_e_cpu1_sa_dq(5)';
NODE_NAME     U26 K69
 '@T6G_MB_LIB.T6G(SCH_1):PAGE41_I159@PURE_QUANTA.GENOA_SP5(CHIPS)':
 'MEA_DATA5': CDS_PINID='MEA_DATA5';
NODE_NAME     J32 16
 '@T6G_MB_LIB.T6G(SCH_1):PAGE101_I52@PURE_QUANTA.SCONN288_DDR506112002KQ(CHIPS)':
 'DQ5_A': CDS_PINID='DQ5_A';
NET_NAME
'M_E_CPU1_SA_DQ<6>'
 '@T6G_MB_LIB.T6G(SCH_1):M_E_CPU1_SA_DQ'<6>:
 C_SIGNAL='@t6g_mb_lib.t6g(sch_1):m_e_cpu1_sa_dq(6)';
NODE_NAME     U26 K70
 '@T6G_MB_LIB.T6G(SCH_1):PAGE41_I159@PURE_QUANTA.GENOA_SP5(CHIPS)':
 'MEA_DATA6': CDS_PINID='MEA_DATA6';
NODE_NAME     J32 159
 '@T6G_MB_LIB.T6G(SCH_1):PAGE101_I52@PURE_QUANTA.SCONN288_DDR506112002KQ(CHIPS)':
 'DQ6_A': CDS_PINID='DQ6_A';
NET_NAME
'M_E_CPU1_SA_DQ<7>'
 '@T6G_MB_LIB.T6G(SCH_1):M_E_CPU1_SA_DQ'<7>:
 C_SIGNAL='@t6g_mb_lib.t6g(sch_1):m_e_cpu1_sa_dq(7)';
NODE_NAME     U26 L69
 '@T6G_MB_LIB.T6G(SCH_1):PAGE41_I159@PURE_QUANTA.GENOA_SP5(CHIPS)':
 'MEA_DATA7': CDS_PINID='MEA_DATA7';
NODE_NAME     J32 161
 '@T6G_MB_LIB.T6G(SCH_1):PAGE101_I52@PURE_QUANTA.SCONN288_DDR506112002KQ(CHIPS)':
 'DQ7_A': CDS_PINID='DQ7_A';
NET_NAME
'M_E_CPU1_SA_DQ<8>'
 '@T6G_MB_LIB.T6G(SCH_1):M_E_CPU1_SA_DQ'<8>:
 C_SIGNAL='@t6g_mb_lib.t6g(sch_1):m_e_cpu1_sa_dq(8)';
NODE_NAME     U26 L71
 '@T6G_MB_LIB.T6G(SCH_1):PAGE41_I159@PURE_QUANTA.GENOA_SP5(CHIPS)':
 'MEA_DATA8': CDS_PINID='MEA_DATA8';
NODE_NAME     J32 18
 '@T6G_MB_LIB.T6G(SCH_1):PAGE101_I52@PURE_QUANTA.SCONN288_DDR506112002KQ(CHIPS)':
 'DQ8_A': CDS_PINID='DQ8_A';
NET_NAME
'M_E_CPU1_SA_DQ<9>'
 '@T6G_MB_LIB.T6G(SCH_1):M_E_CPU1_SA_DQ'<9>:
 C_SIGNAL='@t6g_mb_lib.t6g(sch_1):m_e_cpu1_sa_dq(9)';
NODE_NAME     U26 M69
 '@T6G_MB_LIB.T6G(SCH_1):PAGE41_I159@PURE_QUANTA.GENOA_SP5(CHIPS)':
 'MEA_DATA9': CDS_PINID='MEA_DATA9';
NODE_NAME     J32 20
 '@T6G_MB_LIB.T6G(SCH_1):PAGE101_I52@PURE_QUANTA.SCONN288_DDR506112002KQ(CHIPS)':
 'DQ9_A': CDS_PINID='DQ9_A';
NET_NAME
'M_E_CPU1_SA_DQS_DN<0>'
 '@T6G_MB_LIB.T6G(SCH_1):M_E_CPU1_SA_DQS_DN'<0>:
 C_SIGNAL='@t6g_mb_lib.t6g(sch_1):m_e_cpu1_sa_dqs_dn(0)';
NODE_NAME     U26 H70
 '@T6G_MB_LIB.T6G(SCH_1):PAGE41_I159@PURE_QUANTA.GENOA_SP5(CHIPS)':
 'MEA_DQS_L0': CDS_PINID='MEA_DQS_L0';
NODE_NAME     J32 12
 '@T6G_MB_LIB.T6G(SCH_1):PAGE101_I236@PURE_QUANTA.SCONN288_DDR506112002KQ(CHIPS)':
 'DQS0_A_C': CDS_PINID='DQS0_A_C';
NET_NAME
'M_E_CPU1_SA_DQS_DN<1>'
 '@T6G_MB_LIB.T6G(SCH_1):M_E_CPU1_SA_DQS_DN'<1>:
 C_SIGNAL='@t6g_mb_lib.t6g(sch_1):m_e_cpu1_sa_dqs_dn(1)';
NODE_NAME     U26 P70
 '@T6G_MB_LIB.T6G(SCH_1):PAGE41_I159@PURE_QUANTA.GENOA_SP5(CHIPS)':
 'MEA_DQS_L1': CDS_PINID='MEA_DQS_L1';
NODE_NAME     J32 23
 '@T6G_MB_LIB.T6G(SCH_1):PAGE101_I236@PURE_QUANTA.SCONN288_DDR506112002KQ(CHIPS)':
 'DQS1_A_C': CDS_PINID='DQS1_A_C';
NET_NAME
'M_E_CPU1_SA_DQS_DN<2>'
 '@T6G_MB_LIB.T6G(SCH_1):M_E_CPU1_SA_DQS_DN'<2>:
 C_SIGNAL='@t6g_mb_lib.t6g(sch_1):m_e_cpu1_sa_dqs_dn(2)';
NODE_NAME     U26 Y70
 '@T6G_MB_LIB.T6G(SCH_1):PAGE41_I159@PURE_QUANTA.GENOA_SP5(CHIPS)':
 'MEA_DQS_L2': CDS_PINID='MEA_DQS_L2';
NODE_NAME     J32 34
 '@T6G_MB_LIB.T6G(SCH_1):PAGE101_I236@PURE_QUANTA.SCONN288_DDR506112002KQ(CHIPS)':
 'DQS2_A_C': CDS_PINID='DQS2_A_C';
NET_NAME
'M_E_CPU1_SA_DQS_DN<3>'
 '@T6G_MB_LIB.T6G(SCH_1):M_E_CPU1_SA_DQS_DN'<3>:
 C_SIGNAL='@t6g_mb_lib.t6g(sch_1):m_e_cpu1_sa_dqs_dn(3)';
NODE_NAME     U26 AF70
 '@T6G_MB_LIB.T6G(SCH_1):PAGE41_I159@PURE_QUANTA.GENOA_SP5(CHIPS)':
 'MEA_DQS_L3': CDS_PINID='MEA_DQS_L3';
NODE_NAME     J32 45
 '@T6G_MB_LIB.T6G(SCH_1):PAGE101_I236@PURE_QUANTA.SCONN288_DDR506112002KQ(CHIPS)':
 'DQS3_A_C': CDS_PINID='DQS3_A_C';
NET_NAME
'M_E_CPU1_SA_DQS_DN<4>'
 '@T6G_MB_LIB.T6G(SCH_1):M_E_CPU1_SA_DQS_DN'<4>:
 C_SIGNAL='@t6g_mb_lib.t6g(sch_1):m_e_cpu1_sa_dqs_dn(4)';
NODE_NAME     U26 AM70
 '@T6G_MB_LIB.T6G(SCH_1):PAGE41_I159@PURE_QUANTA.GENOA_SP5(CHIPS)':
 'MEA_DQS_L4': CDS_PINID='MEA_DQS_L4';
NODE_NAME     J32 56
 '@T6G_MB_LIB.T6G(SCH_1):PAGE101_I236@PURE_QUANTA.SCONN288_DDR506112002KQ(CHIPS)':
 'DQS4_A_C': CDS_PINID='DQS4_A_C';
NET_NAME
'M_E_CPU1_SA_DQS_DN<5>'
 '@T6G_MB_LIB.T6G(SCH_1):M_E_CPU1_SA_DQS_DN'<5>:
 C_SIGNAL='@t6g_mb_lib.t6g(sch_1):m_e_cpu1_sa_dqs_dn(5)';
NODE_NAME     U26 H69
 '@T6G_MB_LIB.T6G(SCH_1):PAGE41_I159@PURE_QUANTA.GENOA_SP5(CHIPS)':
 'MEA_DQS_L5': CDS_PINID='MEA_DQS_L5';
NODE_NAME     J32 156
 '@T6G_MB_LIB.T6G(SCH_1):PAGE101_I236@PURE_QUANTA.SCONN288_DDR506112002KQ(CHIPS)':
 'DQS5_A_C||TDQS5_A_C||DQS5_A_T||TDQS5_A_T': CDS_PINID='\dqs5_a_c||tdqs5_a_c||dqs5_a_t||tdqs5_a_t\';
NET_NAME
'M_E_CPU1_SA_DQS_DN<6>'
 '@T6G_MB_LIB.T6G(SCH_1):M_E_CPU1_SA_DQS_DN'<6>:
 C_SIGNAL='@t6g_mb_lib.t6g(sch_1):m_e_cpu1_sa_dqs_dn(6)';
NODE_NAME     U26 P69
 '@T6G_MB_LIB.T6G(SCH_1):PAGE41_I159@PURE_QUANTA.GENOA_SP5(CHIPS)':
 'MEA_DQS_L6': CDS_PINID='MEA_DQS_L6';
NODE_NAME     J32 167
 '@T6G_MB_LIB.T6G(SCH_1):PAGE101_I236@PURE_QUANTA.SCONN288_DDR506112002KQ(CHIPS)':
 'DQS6_A_C||TDQS6_A_C||DQS6_A_T||TDQS6_A_T': CDS_PINID='\dqs6_a_c||tdqs6_a_c||dqs6_a_t||tdqs6_a_t\';
NET_NAME
'M_E_CPU1_SA_DQS_DN<7>'
 '@T6G_MB_LIB.T6G(SCH_1):M_E_CPU1_SA_DQS_DN'<7>:
 C_SIGNAL='@t6g_mb_lib.t6g(sch_1):m_e_cpu1_sa_dqs_dn(7)';
NODE_NAME     U26 Y69
 '@T6G_MB_LIB.T6G(SCH_1):PAGE41_I159@PURE_QUANTA.GENOA_SP5(CHIPS)':
 'MEA_DQS_L7': CDS_PINID='MEA_DQS_L7';
NODE_NAME     J32 178
 '@T6G_MB_LIB.T6G(SCH_1):PAGE101_I236@PURE_QUANTA.SCONN288_DDR506112002KQ(CHIPS)':
 'DQS7_A_C||TDQS7_A_C': CDS_PINID='\dqs7_a_c||tdqs7_a_c\';
NET_NAME
'M_E_CPU1_SA_DQS_DN<8>'
 '@T6G_MB_LIB.T6G(SCH_1):M_E_CPU1_SA_DQS_DN'<8>:
 C_SIGNAL='@t6g_mb_lib.t6g(sch_1):m_e_cpu1_sa_dqs_dn(8)';
NODE_NAME     U26 AF69
 '@T6G_MB_LIB.T6G(SCH_1):PAGE41_I159@PURE_QUANTA.GENOA_SP5(CHIPS)':
 'MEA_DQS_L8': CDS_PINID='MEA_DQS_L8';
NODE_NAME     J32 189
 '@T6G_MB_LIB.T6G(SCH_1):PAGE101_I236@PURE_QUANTA.SCONN288_DDR506112002KQ(CHIPS)':
 'DQS8_A_C||TDQS8_A_C': CDS_PINID='\dqs8_a_c||tdqs8_a_c\';
NET_NAME
'M_E_CPU1_SA_DQS_DN<9>'
 '@T6G_MB_LIB.T6G(SCH_1):M_E_CPU1_SA_DQS_DN'<9>:
 C_SIGNAL='@t6g_mb_lib.t6g(sch_1):m_e_cpu1_sa_dqs_dn(9)';
NODE_NAME     U26 AM69
 '@T6G_MB_LIB.T6G(SCH_1):PAGE41_I159@PURE_QUANTA.GENOA_SP5(CHIPS)':
 'MEA_DQS_L9': CDS_PINID='MEA_DQS_L9';
NODE_NAME     J32 200
 '@T6G_MB_LIB.T6G(SCH_1):PAGE101_I236@PURE_QUANTA.SCONN288_DDR506112002KQ(CHIPS)':
 'DQS9_A_C||TDQS9_A_C': CDS_PINID='\dqs9_a_c||tdqs9_a_c\';
NET_NAME
'M_E_CPU1_SA_DQS_DP<0>'
 '@T6G_MB_LIB.T6G(SCH_1):M_E_CPU1_SA_DQS_DP'<0>:
 C_SIGNAL='@t6g_mb_lib.t6g(sch_1):m_e_cpu1_sa_dqs_dp(0)';
NODE_NAME     U26 G71
 '@T6G_MB_LIB.T6G(SCH_1):PAGE41_I159@PURE_QUANTA.GENOA_SP5(CHIPS)':
 'MEA_DQS_H0': CDS_PINID='MEA_DQS_H0';
NODE_NAME     J32 11
 '@T6G_MB_LIB.T6G(SCH_1):PAGE101_I236@PURE_QUANTA.SCONN288_DDR506112002KQ(CHIPS)':
 'DQS0_A_T': CDS_PINID='DQS0_A_T';
NET_NAME
'M_E_CPU1_SA_DQS_DP<1>'
 '@T6G_MB_LIB.T6G(SCH_1):M_E_CPU1_SA_DQS_DP'<1>:
 C_SIGNAL='@t6g_mb_lib.t6g(sch_1):m_e_cpu1_sa_dqs_dp(1)';
NODE_NAME     U26 N71
 '@T6G_MB_LIB.T6G(SCH_1):PAGE41_I159@PURE_QUANTA.GENOA_SP5(CHIPS)':
 'MEA_DQS_H1': CDS_PINID='MEA_DQS_H1';
NODE_NAME     J32 22
 '@T6G_MB_LIB.T6G(SCH_1):PAGE101_I236@PURE_QUANTA.SCONN288_DDR506112002KQ(CHIPS)':
 'DQS1_A_T': CDS_PINID='DQS1_A_T';
NET_NAME
'M_E_CPU1_SA_DQS_DP<2>'
 '@T6G_MB_LIB.T6G(SCH_1):M_E_CPU1_SA_DQS_DP'<2>:
 C_SIGNAL='@t6g_mb_lib.t6g(sch_1):m_e_cpu1_sa_dqs_dp(2)';
NODE_NAME     U26 W71
 '@T6G_MB_LIB.T6G(SCH_1):PAGE41_I159@PURE_QUANTA.GENOA_SP5(CHIPS)':
 'MEA_DQS_H2': CDS_PINID='MEA_DQS_H2';
NODE_NAME     J32 33
 '@T6G_MB_LIB.T6G(SCH_1):PAGE101_I236@PURE_QUANTA.SCONN288_DDR506112002KQ(CHIPS)':
 'DQS2_A_T': CDS_PINID='DQS2_A_T';
NET_NAME
'M_E_CPU1_SA_DQS_DP<3>'
 '@T6G_MB_LIB.T6G(SCH_1):M_E_CPU1_SA_DQS_DP'<3>:
 C_SIGNAL='@t6g_mb_lib.t6g(sch_1):m_e_cpu1_sa_dqs_dp(3)';
NODE_NAME     U26 AE71
 '@T6G_MB_LIB.T6G(SCH_1):PAGE41_I159@PURE_QUANTA.GENOA_SP5(CHIPS)':
 'MEA_DQS_H3': CDS_PINID='MEA_DQS_H3';
NODE_NAME     J32 44
 '@T6G_MB_LIB.T6G(SCH_1):PAGE101_I236@PURE_QUANTA.SCONN288_DDR506112002KQ(CHIPS)':
 'DQS3_A_T': CDS_PINID='DQS3_A_T';
NET_NAME
'M_E_CPU1_SA_DQS_DP<4>'
 '@T6G_MB_LIB.T6G(SCH_1):M_E_CPU1_SA_DQS_DP'<4>:
 C_SIGNAL='@t6g_mb_lib.t6g(sch_1):m_e_cpu1_sa_dqs_dp(4)';
NODE_NAME     U26 AL71
 '@T6G_MB_LIB.T6G(SCH_1):PAGE41_I159@PURE_QUANTA.GENOA_SP5(CHIPS)':
 'MEA_DQS_H4': CDS_PINID='MEA_DQS_H4';
NODE_NAME     J32 55
 '@T6G_MB_LIB.T6G(SCH_1):PAGE101_I236@PURE_QUANTA.SCONN288_DDR506112002KQ(CHIPS)':
 'DQS4_A_T': CDS_PINID='DQS4_A_T';
NET_NAME
'M_E_CPU1_SA_DQS_DP<5>'
 '@T6G_MB_LIB.T6G(SCH_1):M_E_CPU1_SA_DQS_DP'<5>:
 C_SIGNAL='@t6g_mb_lib.t6g(sch_1):m_e_cpu1_sa_dqs_dp(5)';
NODE_NAME     U26 J69
 '@T6G_MB_LIB.T6G(SCH_1):PAGE41_I159@PURE_QUANTA.GENOA_SP5(CHIPS)':
 'MEA_DQS_H5': CDS_PINID='MEA_DQS_H5';
NODE_NAME     J32 157
 '@T6G_MB_LIB.T6G(SCH_1):PAGE101_I236@PURE_QUANTA.SCONN288_DDR506112002KQ(CHIPS)':
 'DQS5_A_T||TDQS5_A_T': CDS_PINID='\dqs5_a_t||tdqs5_a_t\';
NET_NAME
'M_E_CPU1_SA_DQS_DP<6>'
 '@T6G_MB_LIB.T6G(SCH_1):M_E_CPU1_SA_DQS_DP'<6>:
 C_SIGNAL='@t6g_mb_lib.t6g(sch_1):m_e_cpu1_sa_dqs_dp(6)';
NODE_NAME     U26 R69
 '@T6G_MB_LIB.T6G(SCH_1):PAGE41_I159@PURE_QUANTA.GENOA_SP5(CHIPS)':
 'MEA_DQS_H6': CDS_PINID='MEA_DQS_H6';
NODE_NAME     J32 168
 '@T6G_MB_LIB.T6G(SCH_1):PAGE101_I236@PURE_QUANTA.SCONN288_DDR506112002KQ(CHIPS)':
 'DQS6_A_T||TDQS6_A_T': CDS_PINID='\dqs6_a_t||tdqs6_a_t\';
NET_NAME
'M_E_CPU1_SA_DQS_DP<7>'
 '@T6G_MB_LIB.T6G(SCH_1):M_E_CPU1_SA_DQS_DP'<7>:
 C_SIGNAL='@t6g_mb_lib.t6g(sch_1):m_e_cpu1_sa_dqs_dp(7)';
NODE_NAME     U26 AA69
 '@T6G_MB_LIB.T6G(SCH_1):PAGE41_I159@PURE_QUANTA.GENOA_SP5(CHIPS)':
 'MEA_DQS_H7': CDS_PINID='MEA_DQS_H7';
NODE_NAME     J32 179
 '@T6G_MB_LIB.T6G(SCH_1):PAGE101_I236@PURE_QUANTA.SCONN288_DDR506112002KQ(CHIPS)':
 'DQS7_A_T||TDQS7_A_T': CDS_PINID='\dqs7_a_t||tdqs7_a_t\';
NET_NAME
'M_E_CPU1_SA_DQS_DP<8>'
 '@T6G_MB_LIB.T6G(SCH_1):M_E_CPU1_SA_DQS_DP'<8>:
 C_SIGNAL='@t6g_mb_lib.t6g(sch_1):m_e_cpu1_sa_dqs_dp(8)';
NODE_NAME     U26 AG69
 '@T6G_MB_LIB.T6G(SCH_1):PAGE41_I159@PURE_QUANTA.GENOA_SP5(CHIPS)':
 'MEA_DQS_H8': CDS_PINID='MEA_DQS_H8';
NODE_NAME     J32 190
 '@T6G_MB_LIB.T6G(SCH_1):PAGE101_I236@PURE_QUANTA.SCONN288_DDR506112002KQ(CHIPS)':
 'DQS8_A_T||TDQS8_A_T': CDS_PINID='\dqs8_a_t||tdqs8_a_t\';
NET_NAME
'M_E_CPU1_SA_DQS_DP<9>'
 '@T6G_MB_LIB.T6G(SCH_1):M_E_CPU1_SA_DQS_DP'<9>:
 C_SIGNAL='@t6g_mb_lib.t6g(sch_1):m_e_cpu1_sa_dqs_dp(9)';
NODE_NAME     U26 AN69
 '@T6G_MB_LIB.T6G(SCH_1):PAGE41_I159@PURE_QUANTA.GENOA_SP5(CHIPS)':
 'MEA_DQS_H9': CDS_PINID='MEA_DQS_H9';
NODE_NAME     J32 201
 '@T6G_MB_LIB.T6G(SCH_1):PAGE101_I236@PURE_QUANTA.SCONN288_DDR506112002KQ(CHIPS)':
 'DQS9_A_T||TDQS9_A_T': CDS_PINID='\dqs9_a_t||tdqs9_a_t\';
NET_NAME
'M_E_CPU1_SA_PAR'
 '@T6G_MB_LIB.T6G(SCH_1):M_E_CPU1_SA_PAR':
 C_SIGNAL='@t6g_mb_lib.t6g(sch_1):m_e_cpu1_sa_par';
NODE_NAME     U26 BC69
 '@T6G_MB_LIB.T6G(SCH_1):PAGE41_I159@PURE_QUANTA.GENOA_SP5(CHIPS)':
 'MEA_PAR': CDS_PINID='MEA_PAR';
NODE_NAME     J32 74
 '@T6G_MB_LIB.T6G(SCH_1):PAGE101_I52@PURE_QUANTA.SCONN288_DDR506112002KQ(CHIPS)':
 'PAR_A': CDS_PINID='PAR_A';
NET_NAME
'M_E_CPU1_SA_RSP<0>'
 '@T6G_MB_LIB.T6G(SCH_1):M_E_CPU1_SA_RSP'<0>:
 C_SIGNAL='@t6g_mb_lib.t6g(sch_1):m_e_cpu1_sa_rsp(0)';
NODE_NAME     U26 BN69
 '@T6G_MB_LIB.T6G(SCH_1):PAGE41_I159@PURE_QUANTA.GENOA_SP5(CHIPS)':
 'MEA0_RSP_L': CDS_PINID='MEA0_RSP_L';
NODE_NAME     J32 86
 '@T6G_MB_LIB.T6G(SCH_1):PAGE101_I52@PURE_QUANTA.SCONN288_DDR506112002KQ(CHIPS)':
 'LBD||RSP_A_N': CDS_PINID='\lbd||rsp_a_n\';
NET_NAME
'M_E_CPU1_SB_CA<0>'
 '@T6G_MB_LIB.T6G(SCH_1):M_E_CPU1_SB_CA'<0>:
 C_SIGNAL='@t6g_mb_lib.t6g(sch_1):m_e_cpu1_sb_ca(0)';
NODE_NAME     U26 BG69
 '@T6G_MB_LIB.T6G(SCH_1):PAGE41_I159@PURE_QUANTA.GENOA_SP5(CHIPS)':
 'MEB_CA0': CDS_PINID='MEB_CA0';
NODE_NAME     J32 76
 '@T6G_MB_LIB.T6G(SCH_1):PAGE101_I52@PURE_QUANTA.SCONN288_DDR506112002KQ(CHIPS)':
 'CA0_B': CDS_PINID='CA0_B';
NET_NAME
'M_E_CPU1_SB_CA<1>'
 '@T6G_MB_LIB.T6G(SCH_1):M_E_CPU1_SB_CA'<1>:
 C_SIGNAL='@t6g_mb_lib.t6g(sch_1):m_e_cpu1_sb_ca(1)';
NODE_NAME     U26 BH69
 '@T6G_MB_LIB.T6G(SCH_1):PAGE41_I159@PURE_QUANTA.GENOA_SP5(CHIPS)':
 'MEB_CA1': CDS_PINID='MEB_CA1';
NODE_NAME     J32 221
 '@T6G_MB_LIB.T6G(SCH_1):PAGE101_I52@PURE_QUANTA.SCONN288_DDR506112002KQ(CHIPS)':
 'CA1_B': CDS_PINID='CA1_B';
NET_NAME
'M_E_CPU1_SB_CA<2>'
 '@T6G_MB_LIB.T6G(SCH_1):M_E_CPU1_SB_CA'<2>:
 C_SIGNAL='@t6g_mb_lib.t6g(sch_1):m_e_cpu1_sb_ca(2)';
NODE_NAME     U26 BH70
 '@T6G_MB_LIB.T6G(SCH_1):PAGE41_I159@PURE_QUANTA.GENOA_SP5(CHIPS)':
 'MEB_CA2': CDS_PINID='MEB_CA2';
NODE_NAME     J32 78
 '@T6G_MB_LIB.T6G(SCH_1):PAGE101_I52@PURE_QUANTA.SCONN288_DDR506112002KQ(CHIPS)':
 'CA2_B': CDS_PINID='CA2_B';
NET_NAME
'M_E_CPU1_SB_CA<3>'
 '@T6G_MB_LIB.T6G(SCH_1):M_E_CPU1_SB_CA'<3>:
 C_SIGNAL='@t6g_mb_lib.t6g(sch_1):m_e_cpu1_sb_ca(3)';
NODE_NAME     U26 BJ71
 '@T6G_MB_LIB.T6G(SCH_1):PAGE41_I159@PURE_QUANTA.GENOA_SP5(CHIPS)':
 'MEB_CA3': CDS_PINID='MEB_CA3';
NODE_NAME     J32 223
 '@T6G_MB_LIB.T6G(SCH_1):PAGE101_I52@PURE_QUANTA.SCONN288_DDR506112002KQ(CHIPS)':
 'CA3_B': CDS_PINID='CA3_B';
NET_NAME
'M_E_CPU1_SB_CA<4>'
 '@T6G_MB_LIB.T6G(SCH_1):M_E_CPU1_SB_CA'<4>:
 C_SIGNAL='@t6g_mb_lib.t6g(sch_1):m_e_cpu1_sb_ca(4)';
NODE_NAME     U26 BJ69
 '@T6G_MB_LIB.T6G(SCH_1):PAGE41_I159@PURE_QUANTA.GENOA_SP5(CHIPS)':
 'MEB_CA4': CDS_PINID='MEB_CA4';
NODE_NAME     J32 80
 '@T6G_MB_LIB.T6G(SCH_1):PAGE101_I52@PURE_QUANTA.SCONN288_DDR506112002KQ(CHIPS)':
 'CA4_B': CDS_PINID='CA4_B';
NET_NAME
'M_E_CPU1_SB_CA<5>'
 '@T6G_MB_LIB.T6G(SCH_1):M_E_CPU1_SB_CA'<5>:
 C_SIGNAL='@t6g_mb_lib.t6g(sch_1):m_e_cpu1_sb_ca(5)';
NODE_NAME     U26 BK69
 '@T6G_MB_LIB.T6G(SCH_1):PAGE41_I159@PURE_QUANTA.GENOA_SP5(CHIPS)':
 'MEB_CA5': CDS_PINID='MEB_CA5';
NODE_NAME     J32 225
 '@T6G_MB_LIB.T6G(SCH_1):PAGE101_I52@PURE_QUANTA.SCONN288_DDR506112002KQ(CHIPS)':
 'CA5_B': CDS_PINID='CA5_B';
NET_NAME
'M_E_CPU1_SB_CA<6>'
 '@T6G_MB_LIB.T6G(SCH_1):M_E_CPU1_SB_CA'<6>:
 C_SIGNAL='@t6g_mb_lib.t6g(sch_1):m_e_cpu1_sb_ca(6)';
NODE_NAME     U26 BK70
 '@T6G_MB_LIB.T6G(SCH_1):PAGE41_I159@PURE_QUANTA.GENOA_SP5(CHIPS)':
 'MEB_CA6': CDS_PINID='MEB_CA6';
NODE_NAME     J32 82
 '@T6G_MB_LIB.T6G(SCH_1):PAGE101_I52@PURE_QUANTA.SCONN288_DDR506112002KQ(CHIPS)':
 'CA6_B': CDS_PINID='CA6_B';
NET_NAME
'M_E_CPU1_SB_CB<0>'
 '@T6G_MB_LIB.T6G(SCH_1):M_E_CPU1_SB_CB'<0>:
 C_SIGNAL='@t6g_mb_lib.t6g(sch_1):m_e_cpu1_sb_cb(0)';
NODE_NAME     U26 BY70
 '@T6G_MB_LIB.T6G(SCH_1):PAGE41_I159@PURE_QUANTA.GENOA_SP5(CHIPS)':
 'MEB_CHECK0': CDS_PINID='MEB_CHECK0';
NODE_NAME     J32 96
 '@T6G_MB_LIB.T6G(SCH_1):PAGE101_I52@PURE_QUANTA.SCONN288_DDR506112002KQ(CHIPS)':
 'CB0_B': CDS_PINID='CB0_B';
NET_NAME
'M_E_CPU1_SB_CB<1>'
 '@T6G_MB_LIB.T6G(SCH_1):M_E_CPU1_SB_CB'<1>:
 C_SIGNAL='@t6g_mb_lib.t6g(sch_1):m_e_cpu1_sb_cb(1)';
NODE_NAME     U26 CA69
 '@T6G_MB_LIB.T6G(SCH_1):PAGE41_I159@PURE_QUANTA.GENOA_SP5(CHIPS)':
 'MEB_CHECK1': CDS_PINID='MEB_CHECK1';
NODE_NAME     J32 98
 '@T6G_MB_LIB.T6G(SCH_1):PAGE101_I52@PURE_QUANTA.SCONN288_DDR506112002KQ(CHIPS)':
 'CB1_B': CDS_PINID='CB1_B';
NET_NAME
'M_E_CPU1_SB_CB<2>'
 '@T6G_MB_LIB.T6G(SCH_1):M_E_CPU1_SB_CB'<2>:
 C_SIGNAL='@t6g_mb_lib.t6g(sch_1):m_e_cpu1_sb_cb(2)';
NODE_NAME     U26 CA71
 '@T6G_MB_LIB.T6G(SCH_1):PAGE41_I159@PURE_QUANTA.GENOA_SP5(CHIPS)':
 'MEB_CHECK2': CDS_PINID='MEB_CHECK2';
NODE_NAME     J32 241
 '@T6G_MB_LIB.T6G(SCH_1):PAGE101_I52@PURE_QUANTA.SCONN288_DDR506112002KQ(CHIPS)':
 'CB2_B': CDS_PINID='CB2_B';
NET_NAME
'M_E_CPU1_SB_CB<3>'
 '@T6G_MB_LIB.T6G(SCH_1):M_E_CPU1_SB_CB'<3>:
 C_SIGNAL='@t6g_mb_lib.t6g(sch_1):m_e_cpu1_sb_cb(3)';
NODE_NAME     U26 CB69
 '@T6G_MB_LIB.T6G(SCH_1):PAGE41_I159@PURE_QUANTA.GENOA_SP5(CHIPS)':
 'MEB_CHECK3': CDS_PINID='MEB_CHECK3';
NODE_NAME     J32 243
 '@T6G_MB_LIB.T6G(SCH_1):PAGE101_I52@PURE_QUANTA.SCONN288_DDR506112002KQ(CHIPS)':
 'CB3_B': CDS_PINID='CB3_B';
NET_NAME
'M_E_CPU1_SB_CB<4>'
 '@T6G_MB_LIB.T6G(SCH_1):M_E_CPU1_SB_CB'<4>:
 C_SIGNAL='@t6g_mb_lib.t6g(sch_1):m_e_cpu1_sb_cb(4)';
NODE_NAME     U26 BT70
 '@T6G_MB_LIB.T6G(SCH_1):PAGE41_I159@PURE_QUANTA.GENOA_SP5(CHIPS)':
 'MEB_CHECK4': CDS_PINID='MEB_CHECK4';
NODE_NAME     J32 89
 '@T6G_MB_LIB.T6G(SCH_1):PAGE101_I52@PURE_QUANTA.SCONN288_DDR506112002KQ(CHIPS)':
 'CB4_B': CDS_PINID='CB4_B';
NET_NAME
'M_E_CPU1_SB_CB<5>'
 '@T6G_MB_LIB.T6G(SCH_1):M_E_CPU1_SB_CB'<5>:
 C_SIGNAL='@t6g_mb_lib.t6g(sch_1):m_e_cpu1_sb_cb(5)';
NODE_NAME     U26 BU69
 '@T6G_MB_LIB.T6G(SCH_1):PAGE41_I159@PURE_QUANTA.GENOA_SP5(CHIPS)':
 'MEB_CHECK5': CDS_PINID='MEB_CHECK5';
NODE_NAME     J32 91
 '@T6G_MB_LIB.T6G(SCH_1):PAGE101_I52@PURE_QUANTA.SCONN288_DDR506112002KQ(CHIPS)':
 'CB5_B': CDS_PINID='CB5_B';
NET_NAME
'M_E_CPU1_SB_CB<6>'
 '@T6G_MB_LIB.T6G(SCH_1):M_E_CPU1_SB_CB'<6>:
 C_SIGNAL='@t6g_mb_lib.t6g(sch_1):m_e_cpu1_sb_cb(6)';
NODE_NAME     U26 BU71
 '@T6G_MB_LIB.T6G(SCH_1):PAGE41_I159@PURE_QUANTA.GENOA_SP5(CHIPS)':
 'MEB_CHECK6': CDS_PINID='MEB_CHECK6';
NODE_NAME     J32 234
 '@T6G_MB_LIB.T6G(SCH_1):PAGE101_I52@PURE_QUANTA.SCONN288_DDR506112002KQ(CHIPS)':
 'CB6_B': CDS_PINID='CB6_B';
NET_NAME
'M_E_CPU1_SB_CB<7>'
 '@T6G_MB_LIB.T6G(SCH_1):M_E_CPU1_SB_CB'<7>:
 C_SIGNAL='@t6g_mb_lib.t6g(sch_1):m_e_cpu1_sb_cb(7)';
NODE_NAME     U26 BV69
 '@T6G_MB_LIB.T6G(SCH_1):PAGE41_I159@PURE_QUANTA.GENOA_SP5(CHIPS)':
 'MEB_CHECK7': CDS_PINID='MEB_CHECK7';
NODE_NAME     J32 236
 '@T6G_MB_LIB.T6G(SCH_1):PAGE101_I52@PURE_QUANTA.SCONN288_DDR506112002KQ(CHIPS)':
 'CB7_B': CDS_PINID='CB7_B';
NET_NAME
'M_E_CPU1_SB_CS_N<0>'
 '@T6G_MB_LIB.T6G(SCH_1):M_E_CPU1_SB_CS_N'<0>:
 C_SIGNAL='@t6g_mb_lib.t6g(sch_1):m_e_cpu1_sb_cs_n(0)';
NODE_NAME     U26 BM69
 '@T6G_MB_LIB.T6G(SCH_1):PAGE41_I159@PURE_QUANTA.GENOA_SP5(CHIPS)':
 'MEB0_CS_L0': CDS_PINID='MEB0_CS_L0';
NODE_NAME     J32 84
 '@T6G_MB_LIB.T6G(SCH_1):PAGE101_I52@PURE_QUANTA.SCONN288_DDR506112002KQ(CHIPS)':
 'CS0_B_N': CDS_PINID='CS0_B_N';
NET_NAME
'M_E_CPU1_SB_CS_N<1>'
 '@T6G_MB_LIB.T6G(SCH_1):M_E_CPU1_SB_CS_N'<1>:
 C_SIGNAL='@t6g_mb_lib.t6g(sch_1):m_e_cpu1_sb_cs_n(1)';
NODE_NAME     U26 BN71
 '@T6G_MB_LIB.T6G(SCH_1):PAGE41_I159@PURE_QUANTA.GENOA_SP5(CHIPS)':
 'MEB0_CS_L1': CDS_PINID='MEB0_CS_L1';
NODE_NAME     J32 229
 '@T6G_MB_LIB.T6G(SCH_1):PAGE101_I52@PURE_QUANTA.SCONN288_DDR506112002KQ(CHIPS)':
 'CS1_B_N': CDS_PINID='CS1_B_N';
NET_NAME
'M_E_CPU1_SB_DQ<0>'
 '@T6G_MB_LIB.T6G(SCH_1):M_E_CPU1_SB_DQ'<0>:
 C_SIGNAL='@t6g_mb_lib.t6g(sch_1):m_e_cpu1_sb_dq(0)';
NODE_NAME     U26 CB70
 '@T6G_MB_LIB.T6G(SCH_1):PAGE41_I159@PURE_QUANTA.GENOA_SP5(CHIPS)':
 'MEB_DATA0': CDS_PINID='MEB_DATA0';
NODE_NAME     J32 100
 '@T6G_MB_LIB.T6G(SCH_1):PAGE101_I52@PURE_QUANTA.SCONN288_DDR506112002KQ(CHIPS)':
 'DQ0_B': CDS_PINID='DQ0_B';
NET_NAME
'M_E_CPU1_SB_DQ<10>'
 '@T6G_MB_LIB.T6G(SCH_1):M_E_CPU1_SB_DQ'<10>:
 C_SIGNAL='@t6g_mb_lib.t6g(sch_1):m_e_cpu1_sb_dq(10)';
NODE_NAME     U26 CJ71
 '@T6G_MB_LIB.T6G(SCH_1):PAGE41_I159@PURE_QUANTA.GENOA_SP5(CHIPS)':
 'MEB_DATA10': CDS_PINID='MEB_DATA10';
NODE_NAME     J32 256
 '@T6G_MB_LIB.T6G(SCH_1):PAGE101_I52@PURE_QUANTA.SCONN288_DDR506112002KQ(CHIPS)':
 'DQ10_B': CDS_PINID='DQ10_B';
NET_NAME
'M_E_CPU1_SB_DQ<11>'
 '@T6G_MB_LIB.T6G(SCH_1):M_E_CPU1_SB_DQ'<11>:
 C_SIGNAL='@t6g_mb_lib.t6g(sch_1):m_e_cpu1_sb_dq(11)';
NODE_NAME     U26 CK69
 '@T6G_MB_LIB.T6G(SCH_1):PAGE41_I159@PURE_QUANTA.GENOA_SP5(CHIPS)':
 'MEB_DATA11': CDS_PINID='MEB_DATA11';
NODE_NAME     J32 258
 '@T6G_MB_LIB.T6G(SCH_1):PAGE101_I52@PURE_QUANTA.SCONN288_DDR506112002KQ(CHIPS)':
 'DQ11_B': CDS_PINID='DQ11_B';
NET_NAME
'M_E_CPU1_SB_DQ<12>'
 '@T6G_MB_LIB.T6G(SCH_1):M_E_CPU1_SB_DQ'<12>:
 C_SIGNAL='@t6g_mb_lib.t6g(sch_1):m_e_cpu1_sb_dq(12)';
NODE_NAME     U26 CM70
 '@T6G_MB_LIB.T6G(SCH_1):PAGE41_I159@PURE_QUANTA.GENOA_SP5(CHIPS)':
 'MEB_DATA12': CDS_PINID='MEB_DATA12';
NODE_NAME     J32 118
 '@T6G_MB_LIB.T6G(SCH_1):PAGE101_I52@PURE_QUANTA.SCONN288_DDR506112002KQ(CHIPS)':
 'DQ12_B': CDS_PINID='DQ12_B';
NET_NAME
'M_E_CPU1_SB_DQ<13>'
 '@T6G_MB_LIB.T6G(SCH_1):M_E_CPU1_SB_DQ'<13>:
 C_SIGNAL='@t6g_mb_lib.t6g(sch_1):m_e_cpu1_sb_dq(13)';
NODE_NAME     U26 CN69
 '@T6G_MB_LIB.T6G(SCH_1):PAGE41_I159@PURE_QUANTA.GENOA_SP5(CHIPS)':
 'MEB_DATA13': CDS_PINID='MEB_DATA13';
NODE_NAME     J32 120
 '@T6G_MB_LIB.T6G(SCH_1):PAGE101_I52@PURE_QUANTA.SCONN288_DDR506112002KQ(CHIPS)':
 'DQ13_B': CDS_PINID='DQ13_B';
NET_NAME
'M_E_CPU1_SB_DQ<14>'
 '@T6G_MB_LIB.T6G(SCH_1):M_E_CPU1_SB_DQ'<14>:
 C_SIGNAL='@t6g_mb_lib.t6g(sch_1):m_e_cpu1_sb_dq(14)';
NODE_NAME     U26 CN71
 '@T6G_MB_LIB.T6G(SCH_1):PAGE41_I159@PURE_QUANTA.GENOA_SP5(CHIPS)':
 'MEB_DATA14': CDS_PINID='MEB_DATA14';
NODE_NAME     J32 263
 '@T6G_MB_LIB.T6G(SCH_1):PAGE101_I52@PURE_QUANTA.SCONN288_DDR506112002KQ(CHIPS)':
 'DQ14_B': CDS_PINID='DQ14_B';
NET_NAME
'M_E_CPU1_SB_DQ<15>'
 '@T6G_MB_LIB.T6G(SCH_1):M_E_CPU1_SB_DQ'<15>:
 C_SIGNAL='@t6g_mb_lib.t6g(sch_1):m_e_cpu1_sb_dq(15)';
NODE_NAME     U26 CP69
 '@T6G_MB_LIB.T6G(SCH_1):PAGE41_I159@PURE_QUANTA.GENOA_SP5(CHIPS)':
 'MEB_DATA15': CDS_PINID='MEB_DATA15';
NODE_NAME     J32 265
 '@T6G_MB_LIB.T6G(SCH_1):PAGE101_I52@PURE_QUANTA.SCONN288_DDR506112002KQ(CHIPS)':
 'DQ15_B': CDS_PINID='DQ15_B';
NET_NAME
'M_E_CPU1_SB_DQ<16>'
 '@T6G_MB_LIB.T6G(SCH_1):M_E_CPU1_SB_DQ'<16>:
 C_SIGNAL='@t6g_mb_lib.t6g(sch_1):m_e_cpu1_sb_dq(16)';
NODE_NAME     U26 CP70
 '@T6G_MB_LIB.T6G(SCH_1):PAGE41_I159@PURE_QUANTA.GENOA_SP5(CHIPS)':
 'MEB_DATA16': CDS_PINID='MEB_DATA16';
NODE_NAME     J32 122
 '@T6G_MB_LIB.T6G(SCH_1):PAGE101_I52@PURE_QUANTA.SCONN288_DDR506112002KQ(CHIPS)':
 'DQ16_B': CDS_PINID='DQ16_B';
NET_NAME
'M_E_CPU1_SB_DQ<17>'
 '@T6G_MB_LIB.T6G(SCH_1):M_E_CPU1_SB_DQ'<17>:
 C_SIGNAL='@t6g_mb_lib.t6g(sch_1):m_e_cpu1_sb_dq(17)';
NODE_NAME     U26 CR69
 '@T6G_MB_LIB.T6G(SCH_1):PAGE41_I159@PURE_QUANTA.GENOA_SP5(CHIPS)':
 'MEB_DATA17': CDS_PINID='MEB_DATA17';
NODE_NAME     J32 124
 '@T6G_MB_LIB.T6G(SCH_1):PAGE101_I52@PURE_QUANTA.SCONN288_DDR506112002KQ(CHIPS)':
 'DQ17_B': CDS_PINID='DQ17_B';
NET_NAME
'M_E_CPU1_SB_DQ<18>'
 '@T6G_MB_LIB.T6G(SCH_1):M_E_CPU1_SB_DQ'<18>:
 C_SIGNAL='@t6g_mb_lib.t6g(sch_1):m_e_cpu1_sb_dq(18)';
NODE_NAME     U26 CR71
 '@T6G_MB_LIB.T6G(SCH_1):PAGE41_I159@PURE_QUANTA.GENOA_SP5(CHIPS)':
 'MEB_DATA18': CDS_PINID='MEB_DATA18';
NODE_NAME     J32 267
 '@T6G_MB_LIB.T6G(SCH_1):PAGE101_I52@PURE_QUANTA.SCONN288_DDR506112002KQ(CHIPS)':
 'DQ18_B': CDS_PINID='DQ18_B';
NET_NAME
'M_E_CPU1_SB_DQ<19>'
 '@T6G_MB_LIB.T6G(SCH_1):M_E_CPU1_SB_DQ'<19>:
 C_SIGNAL='@t6g_mb_lib.t6g(sch_1):m_e_cpu1_sb_dq(19)';
NODE_NAME     U26 CT69
 '@T6G_MB_LIB.T6G(SCH_1):PAGE41_I159@PURE_QUANTA.GENOA_SP5(CHIPS)':
 'MEB_DATA19': CDS_PINID='MEB_DATA19';
NODE_NAME     J32 269
 '@T6G_MB_LIB.T6G(SCH_1):PAGE101_I52@PURE_QUANTA.SCONN288_DDR506112002KQ(CHIPS)':
 'DQ19_B': CDS_PINID='DQ19_B';
NET_NAME
'M_E_CPU1_SB_DQ<1>'
 '@T6G_MB_LIB.T6G(SCH_1):M_E_CPU1_SB_DQ'<1>:
 C_SIGNAL='@t6g_mb_lib.t6g(sch_1):m_e_cpu1_sb_dq(1)';
NODE_NAME     U26 CC69
 '@T6G_MB_LIB.T6G(SCH_1):PAGE41_I159@PURE_QUANTA.GENOA_SP5(CHIPS)':
 'MEB_DATA1': CDS_PINID='MEB_DATA1';
NODE_NAME     J32 102
 '@T6G_MB_LIB.T6G(SCH_1):PAGE101_I52@PURE_QUANTA.SCONN288_DDR506112002KQ(CHIPS)':
 'DQ1_B': CDS_PINID='DQ1_B';
NET_NAME
'M_E_CPU1_SB_DQ<20>'
 '@T6G_MB_LIB.T6G(SCH_1):M_E_CPU1_SB_DQ'<20>:
 C_SIGNAL='@t6g_mb_lib.t6g(sch_1):m_e_cpu1_sb_dq(20)';
NODE_NAME     U26 CV70
 '@T6G_MB_LIB.T6G(SCH_1):PAGE41_I159@PURE_QUANTA.GENOA_SP5(CHIPS)':
 'MEB_DATA20': CDS_PINID='MEB_DATA20';
NODE_NAME     J32 129
 '@T6G_MB_LIB.T6G(SCH_1):PAGE101_I52@PURE_QUANTA.SCONN288_DDR506112002KQ(CHIPS)':
 'DQ20_B': CDS_PINID='DQ20_B';
NET_NAME
'M_E_CPU1_SB_DQ<21>'
 '@T6G_MB_LIB.T6G(SCH_1):M_E_CPU1_SB_DQ'<21>:
 C_SIGNAL='@t6g_mb_lib.t6g(sch_1):m_e_cpu1_sb_dq(21)';
NODE_NAME     U26 CW69
 '@T6G_MB_LIB.T6G(SCH_1):PAGE41_I159@PURE_QUANTA.GENOA_SP5(CHIPS)':
 'MEB_DATA21': CDS_PINID='MEB_DATA21';
NODE_NAME     J32 131
 '@T6G_MB_LIB.T6G(SCH_1):PAGE101_I52@PURE_QUANTA.SCONN288_DDR506112002KQ(CHIPS)':
 'DQ21_B': CDS_PINID='DQ21_B';
NET_NAME
'M_E_CPU1_SB_DQ<22>'
 '@T6G_MB_LIB.T6G(SCH_1):M_E_CPU1_SB_DQ'<22>:
 C_SIGNAL='@t6g_mb_lib.t6g(sch_1):m_e_cpu1_sb_dq(22)';
NODE_NAME     U26 CW71
 '@T6G_MB_LIB.T6G(SCH_1):PAGE41_I159@PURE_QUANTA.GENOA_SP5(CHIPS)':
 'MEB_DATA22': CDS_PINID='MEB_DATA22';
NODE_NAME     J32 274
 '@T6G_MB_LIB.T6G(SCH_1):PAGE101_I52@PURE_QUANTA.SCONN288_DDR506112002KQ(CHIPS)':
 'DQ22_B': CDS_PINID='DQ22_B';
NET_NAME
'M_E_CPU1_SB_DQ<23>'
 '@T6G_MB_LIB.T6G(SCH_1):M_E_CPU1_SB_DQ'<23>:
 C_SIGNAL='@t6g_mb_lib.t6g(sch_1):m_e_cpu1_sb_dq(23)';
NODE_NAME     U26 CY69
 '@T6G_MB_LIB.T6G(SCH_1):PAGE41_I159@PURE_QUANTA.GENOA_SP5(CHIPS)':
 'MEB_DATA23': CDS_PINID='MEB_DATA23';
NODE_NAME     J32 276
 '@T6G_MB_LIB.T6G(SCH_1):PAGE101_I52@PURE_QUANTA.SCONN288_DDR506112002KQ(CHIPS)':
 'DQ23_B': CDS_PINID='DQ23_B';
NET_NAME
'M_E_CPU1_SB_DQ<24>'
 '@T6G_MB_LIB.T6G(SCH_1):M_E_CPU1_SB_DQ'<24>:
 C_SIGNAL='@t6g_mb_lib.t6g(sch_1):m_e_cpu1_sb_dq(24)';
NODE_NAME     U26 CY70
 '@T6G_MB_LIB.T6G(SCH_1):PAGE41_I159@PURE_QUANTA.GENOA_SP5(CHIPS)':
 'MEB_DATA24': CDS_PINID='MEB_DATA24';
NODE_NAME     J32 133
 '@T6G_MB_LIB.T6G(SCH_1):PAGE101_I52@PURE_QUANTA.SCONN288_DDR506112002KQ(CHIPS)':
 'DQ24_B': CDS_PINID='DQ24_B';
NET_NAME
'M_E_CPU1_SB_DQ<25>'
 '@T6G_MB_LIB.T6G(SCH_1):M_E_CPU1_SB_DQ'<25>:
 C_SIGNAL='@t6g_mb_lib.t6g(sch_1):m_e_cpu1_sb_dq(25)';
NODE_NAME     U26 DA69
 '@T6G_MB_LIB.T6G(SCH_1):PAGE41_I159@PURE_QUANTA.GENOA_SP5(CHIPS)':
 'MEB_DATA25': CDS_PINID='MEB_DATA25';
NODE_NAME     J32 135
 '@T6G_MB_LIB.T6G(SCH_1):PAGE101_I52@PURE_QUANTA.SCONN288_DDR506112002KQ(CHIPS)':
 'DQ25_B': CDS_PINID='DQ25_B';
NET_NAME
'M_E_CPU1_SB_DQ<26>'
 '@T6G_MB_LIB.T6G(SCH_1):M_E_CPU1_SB_DQ'<26>:
 C_SIGNAL='@t6g_mb_lib.t6g(sch_1):m_e_cpu1_sb_dq(26)';
NODE_NAME     U26 DA71
 '@T6G_MB_LIB.T6G(SCH_1):PAGE41_I159@PURE_QUANTA.GENOA_SP5(CHIPS)':
 'MEB_DATA26': CDS_PINID='MEB_DATA26';
NODE_NAME     J32 278
 '@T6G_MB_LIB.T6G(SCH_1):PAGE101_I52@PURE_QUANTA.SCONN288_DDR506112002KQ(CHIPS)':
 'DQ26_B': CDS_PINID='DQ26_B';
NET_NAME
'M_E_CPU1_SB_DQ<27>'
 '@T6G_MB_LIB.T6G(SCH_1):M_E_CPU1_SB_DQ'<27>:
 C_SIGNAL='@t6g_mb_lib.t6g(sch_1):m_e_cpu1_sb_dq(27)';
NODE_NAME     U26 DB69
 '@T6G_MB_LIB.T6G(SCH_1):PAGE41_I159@PURE_QUANTA.GENOA_SP5(CHIPS)':
 'MEB_DATA27': CDS_PINID='MEB_DATA27';
NODE_NAME     J32 280
 '@T6G_MB_LIB.T6G(SCH_1):PAGE101_I52@PURE_QUANTA.SCONN288_DDR506112002KQ(CHIPS)':
 'DQ27_B': CDS_PINID='DQ27_B';
NET_NAME
'M_E_CPU1_SB_DQ<28>'
 '@T6G_MB_LIB.T6G(SCH_1):M_E_CPU1_SB_DQ'<28>:
 C_SIGNAL='@t6g_mb_lib.t6g(sch_1):m_e_cpu1_sb_dq(28)';
NODE_NAME     U26 DD70
 '@T6G_MB_LIB.T6G(SCH_1):PAGE41_I159@PURE_QUANTA.GENOA_SP5(CHIPS)':
 'MEB_DATA28': CDS_PINID='MEB_DATA28';
NODE_NAME     J32 140
 '@T6G_MB_LIB.T6G(SCH_1):PAGE101_I52@PURE_QUANTA.SCONN288_DDR506112002KQ(CHIPS)':
 'DQ28_B': CDS_PINID='DQ28_B';
NET_NAME
'M_E_CPU1_SB_DQ<29>'
 '@T6G_MB_LIB.T6G(SCH_1):M_E_CPU1_SB_DQ'<29>:
 C_SIGNAL='@t6g_mb_lib.t6g(sch_1):m_e_cpu1_sb_dq(29)';
NODE_NAME     U26 DE69
 '@T6G_MB_LIB.T6G(SCH_1):PAGE41_I159@PURE_QUANTA.GENOA_SP5(CHIPS)':
 'MEB_DATA29': CDS_PINID='MEB_DATA29';
NODE_NAME     J32 142
 '@T6G_MB_LIB.T6G(SCH_1):PAGE101_I52@PURE_QUANTA.SCONN288_DDR506112002KQ(CHIPS)':
 'DQ29_B': CDS_PINID='DQ29_B';
NET_NAME
'M_E_CPU1_SB_DQ<2>'
 '@T6G_MB_LIB.T6G(SCH_1):M_E_CPU1_SB_DQ'<2>:
 C_SIGNAL='@t6g_mb_lib.t6g(sch_1):m_e_cpu1_sb_dq(2)';
NODE_NAME     U26 CC71
 '@T6G_MB_LIB.T6G(SCH_1):PAGE41_I159@PURE_QUANTA.GENOA_SP5(CHIPS)':
 'MEB_DATA2': CDS_PINID='MEB_DATA2';
NODE_NAME     J32 245
 '@T6G_MB_LIB.T6G(SCH_1):PAGE101_I52@PURE_QUANTA.SCONN288_DDR506112002KQ(CHIPS)':
 'DQ2_B': CDS_PINID='DQ2_B';
NET_NAME
'M_E_CPU1_SB_DQ<30>'
 '@T6G_MB_LIB.T6G(SCH_1):M_E_CPU1_SB_DQ'<30>:
 C_SIGNAL='@t6g_mb_lib.t6g(sch_1):m_e_cpu1_sb_dq(30)';
NODE_NAME     U26 DE71
 '@T6G_MB_LIB.T6G(SCH_1):PAGE41_I159@PURE_QUANTA.GENOA_SP5(CHIPS)':
 'MEB_DATA30': CDS_PINID='MEB_DATA30';
NODE_NAME     J32 285
 '@T6G_MB_LIB.T6G(SCH_1):PAGE101_I52@PURE_QUANTA.SCONN288_DDR506112002KQ(CHIPS)':
 'DQ30_B': CDS_PINID='DQ30_B';
NET_NAME
'M_E_CPU1_SB_DQ<31>'
 '@T6G_MB_LIB.T6G(SCH_1):M_E_CPU1_SB_DQ'<31>:
 C_SIGNAL='@t6g_mb_lib.t6g(sch_1):m_e_cpu1_sb_dq(31)';
NODE_NAME     U26 DF69
 '@T6G_MB_LIB.T6G(SCH_1):PAGE41_I159@PURE_QUANTA.GENOA_SP5(CHIPS)':
 'MEB_DATA31': CDS_PINID='MEB_DATA31';
NODE_NAME     J32 287
 '@T6G_MB_LIB.T6G(SCH_1):PAGE101_I52@PURE_QUANTA.SCONN288_DDR506112002KQ(CHIPS)':
 'DQ31_B': CDS_PINID='DQ31_B';
NET_NAME
'M_E_CPU1_SB_DQ<3>'
 '@T6G_MB_LIB.T6G(SCH_1):M_E_CPU1_SB_DQ'<3>:
 C_SIGNAL='@t6g_mb_lib.t6g(sch_1):m_e_cpu1_sb_dq(3)';
NODE_NAME     U26 CD69
 '@T6G_MB_LIB.T6G(SCH_1):PAGE41_I159@PURE_QUANTA.GENOA_SP5(CHIPS)':
 'MEB_DATA3': CDS_PINID='MEB_DATA3';
NODE_NAME     J32 247
 '@T6G_MB_LIB.T6G(SCH_1):PAGE101_I52@PURE_QUANTA.SCONN288_DDR506112002KQ(CHIPS)':
 'DQ3_B': CDS_PINID='DQ3_B';
NET_NAME
'M_E_CPU1_SB_DQ<4>'
 '@T6G_MB_LIB.T6G(SCH_1):M_E_CPU1_SB_DQ'<4>:
 C_SIGNAL='@t6g_mb_lib.t6g(sch_1):m_e_cpu1_sb_dq(4)';
NODE_NAME     U26 CF70
 '@T6G_MB_LIB.T6G(SCH_1):PAGE41_I159@PURE_QUANTA.GENOA_SP5(CHIPS)':
 'MEB_DATA4': CDS_PINID='MEB_DATA4';
NODE_NAME     J32 107
 '@T6G_MB_LIB.T6G(SCH_1):PAGE101_I52@PURE_QUANTA.SCONN288_DDR506112002KQ(CHIPS)':
 'DQ4_B': CDS_PINID='DQ4_B';
NET_NAME
'M_E_CPU1_SB_DQ<5>'
 '@T6G_MB_LIB.T6G(SCH_1):M_E_CPU1_SB_DQ'<5>:
 C_SIGNAL='@t6g_mb_lib.t6g(sch_1):m_e_cpu1_sb_dq(5)';
NODE_NAME     U26 CG69
 '@T6G_MB_LIB.T6G(SCH_1):PAGE41_I159@PURE_QUANTA.GENOA_SP5(CHIPS)':
 'MEB_DATA5': CDS_PINID='MEB_DATA5';
NODE_NAME     J32 109
 '@T6G_MB_LIB.T6G(SCH_1):PAGE101_I52@PURE_QUANTA.SCONN288_DDR506112002KQ(CHIPS)':
 'DQ5_B': CDS_PINID='DQ5_B';
NET_NAME
'M_E_CPU1_SB_DQ<6>'
 '@T6G_MB_LIB.T6G(SCH_1):M_E_CPU1_SB_DQ'<6>:
 C_SIGNAL='@t6g_mb_lib.t6g(sch_1):m_e_cpu1_sb_dq(6)';
NODE_NAME     U26 CG71
 '@T6G_MB_LIB.T6G(SCH_1):PAGE41_I159@PURE_QUANTA.GENOA_SP5(CHIPS)':
 'MEB_DATA6': CDS_PINID='MEB_DATA6';
NODE_NAME     J32 252
 '@T6G_MB_LIB.T6G(SCH_1):PAGE101_I52@PURE_QUANTA.SCONN288_DDR506112002KQ(CHIPS)':
 'DQ6_B': CDS_PINID='DQ6_B';
NET_NAME
'M_E_CPU1_SB_DQ<7>'
 '@T6G_MB_LIB.T6G(SCH_1):M_E_CPU1_SB_DQ'<7>:
 C_SIGNAL='@t6g_mb_lib.t6g(sch_1):m_e_cpu1_sb_dq(7)';
NODE_NAME     U26 CH69
 '@T6G_MB_LIB.T6G(SCH_1):PAGE41_I159@PURE_QUANTA.GENOA_SP5(CHIPS)':
 'MEB_DATA7': CDS_PINID='MEB_DATA7';
NODE_NAME     J32 254
 '@T6G_MB_LIB.T6G(SCH_1):PAGE101_I52@PURE_QUANTA.SCONN288_DDR506112002KQ(CHIPS)':
 'DQ7_B': CDS_PINID='DQ7_B';
NET_NAME
'M_E_CPU1_SB_DQ<8>'
 '@T6G_MB_LIB.T6G(SCH_1):M_E_CPU1_SB_DQ'<8>:
 C_SIGNAL='@t6g_mb_lib.t6g(sch_1):m_e_cpu1_sb_dq(8)';
NODE_NAME     U26 CH70
 '@T6G_MB_LIB.T6G(SCH_1):PAGE41_I159@PURE_QUANTA.GENOA_SP5(CHIPS)':
 'MEB_DATA8': CDS_PINID='MEB_DATA8';
NODE_NAME     J32 111
 '@T6G_MB_LIB.T6G(SCH_1):PAGE101_I52@PURE_QUANTA.SCONN288_DDR506112002KQ(CHIPS)':
 'DQ8_B': CDS_PINID='DQ8_B';
NET_NAME
'M_E_CPU1_SB_DQ<9>'
 '@T6G_MB_LIB.T6G(SCH_1):M_E_CPU1_SB_DQ'<9>:
 C_SIGNAL='@t6g_mb_lib.t6g(sch_1):m_e_cpu1_sb_dq(9)';
NODE_NAME     U26 CJ69
 '@T6G_MB_LIB.T6G(SCH_1):PAGE41_I159@PURE_QUANTA.GENOA_SP5(CHIPS)':
 'MEB_DATA9': CDS_PINID='MEB_DATA9';
NODE_NAME     J32 113
 '@T6G_MB_LIB.T6G(SCH_1):PAGE101_I52@PURE_QUANTA.SCONN288_DDR506112002KQ(CHIPS)':
 'DQ9_B': CDS_PINID='DQ9_B';
NET_NAME
'M_E_CPU1_SB_DQS_DN<0>'
 '@T6G_MB_LIB.T6G(SCH_1):M_E_CPU1_SB_DQS_DN'<0>:
 C_SIGNAL='@t6g_mb_lib.t6g(sch_1):m_e_cpu1_sb_dqs_dn(0)';
NODE_NAME     U26 CE71
 '@T6G_MB_LIB.T6G(SCH_1):PAGE41_I159@PURE_QUANTA.GENOA_SP5(CHIPS)':
 'MEB_DQS_L0': CDS_PINID='MEB_DQS_L0';
NODE_NAME     J32 105
 '@T6G_MB_LIB.T6G(SCH_1):PAGE101_I236@PURE_QUANTA.SCONN288_DDR506112002KQ(CHIPS)':
 'DQS0_B_C': CDS_PINID='DQS0_B_C';
NET_NAME
'M_E_CPU1_SB_DQS_DN<1>'
 '@T6G_MB_LIB.T6G(SCH_1):M_E_CPU1_SB_DQS_DN'<1>:
 C_SIGNAL='@t6g_mb_lib.t6g(sch_1):m_e_cpu1_sb_dqs_dn(1)';
NODE_NAME     U26 CL71
 '@T6G_MB_LIB.T6G(SCH_1):PAGE41_I159@PURE_QUANTA.GENOA_SP5(CHIPS)':
 'MEB_DQS_L1': CDS_PINID='MEB_DQS_L1';
NODE_NAME     J32 116
 '@T6G_MB_LIB.T6G(SCH_1):PAGE101_I236@PURE_QUANTA.SCONN288_DDR506112002KQ(CHIPS)':
 'DQS1_B_C': CDS_PINID='DQS1_B_C';
NET_NAME
'M_E_CPU1_SB_DQS_DN<2>'
 '@T6G_MB_LIB.T6G(SCH_1):M_E_CPU1_SB_DQS_DN'<2>:
 C_SIGNAL='@t6g_mb_lib.t6g(sch_1):m_e_cpu1_sb_dqs_dn(2)';
NODE_NAME     U26 CU71
 '@T6G_MB_LIB.T6G(SCH_1):PAGE41_I159@PURE_QUANTA.GENOA_SP5(CHIPS)':
 'MEB_DQS_L2': CDS_PINID='MEB_DQS_L2';
NODE_NAME     J32 127
 '@T6G_MB_LIB.T6G(SCH_1):PAGE101_I236@PURE_QUANTA.SCONN288_DDR506112002KQ(CHIPS)':
 'DQS2_B_C': CDS_PINID='DQS2_B_C';
NET_NAME
'M_E_CPU1_SB_DQS_DN<3>'
 '@T6G_MB_LIB.T6G(SCH_1):M_E_CPU1_SB_DQS_DN'<3>:
 C_SIGNAL='@t6g_mb_lib.t6g(sch_1):m_e_cpu1_sb_dqs_dn(3)';
NODE_NAME     U26 DC71
 '@T6G_MB_LIB.T6G(SCH_1):PAGE41_I159@PURE_QUANTA.GENOA_SP5(CHIPS)':
 'MEB_DQS_L3': CDS_PINID='MEB_DQS_L3';
NODE_NAME     J32 138
 '@T6G_MB_LIB.T6G(SCH_1):PAGE101_I236@PURE_QUANTA.SCONN288_DDR506112002KQ(CHIPS)':
 'DQS3_B_C': CDS_PINID='DQS3_B_C';
NET_NAME
'M_E_CPU1_SB_DQS_DN<4>'
 '@T6G_MB_LIB.T6G(SCH_1):M_E_CPU1_SB_DQS_DN'<4>:
 C_SIGNAL='@t6g_mb_lib.t6g(sch_1):m_e_cpu1_sb_dqs_dn(4)';
NODE_NAME     U26 BW69
 '@T6G_MB_LIB.T6G(SCH_1):PAGE41_I159@PURE_QUANTA.GENOA_SP5(CHIPS)':
 'MEB_DQS_L4': CDS_PINID='MEB_DQS_L4';
NODE_NAME     J32 238
 '@T6G_MB_LIB.T6G(SCH_1):PAGE101_I236@PURE_QUANTA.SCONN288_DDR506112002KQ(CHIPS)':
 'DQS4_B_C': CDS_PINID='DQS4_B_C';
NET_NAME
'M_E_CPU1_SB_DQS_DN<5>'
 '@T6G_MB_LIB.T6G(SCH_1):M_E_CPU1_SB_DQS_DN'<5>:
 C_SIGNAL='@t6g_mb_lib.t6g(sch_1):m_e_cpu1_sb_dqs_dn(5)';
NODE_NAME     U26 CE69
 '@T6G_MB_LIB.T6G(SCH_1):PAGE41_I159@PURE_QUANTA.GENOA_SP5(CHIPS)':
 'MEB_DQS_L5': CDS_PINID='MEB_DQS_L5';
NODE_NAME     J32 249
 '@T6G_MB_LIB.T6G(SCH_1):PAGE101_I236@PURE_QUANTA.SCONN288_DDR506112002KQ(CHIPS)':
 'DQS5_B_C||TDQS5_B_C': CDS_PINID='\dqs5_b_c||tdqs5_b_c\';
NET_NAME
'M_E_CPU1_SB_DQS_DN<6>'
 '@T6G_MB_LIB.T6G(SCH_1):M_E_CPU1_SB_DQS_DN'<6>:
 C_SIGNAL='@t6g_mb_lib.t6g(sch_1):m_e_cpu1_sb_dqs_dn(6)';
NODE_NAME     U26 CL69
 '@T6G_MB_LIB.T6G(SCH_1):PAGE41_I159@PURE_QUANTA.GENOA_SP5(CHIPS)':
 'MEB_DQS_L6': CDS_PINID='MEB_DQS_L6';
NODE_NAME     J32 260
 '@T6G_MB_LIB.T6G(SCH_1):PAGE101_I236@PURE_QUANTA.SCONN288_DDR506112002KQ(CHIPS)':
 'DQS6_B_C||TDQS6_B_C': CDS_PINID='\dqs6_b_c||tdqs6_b_c\';
NET_NAME
'M_E_CPU1_SB_DQS_DN<7>'
 '@T6G_MB_LIB.T6G(SCH_1):M_E_CPU1_SB_DQS_DN'<7>:
 C_SIGNAL='@t6g_mb_lib.t6g(sch_1):m_e_cpu1_sb_dqs_dn(7)';
NODE_NAME     U26 CU69
 '@T6G_MB_LIB.T6G(SCH_1):PAGE41_I159@PURE_QUANTA.GENOA_SP5(CHIPS)':
 'MEB_DQS_L7': CDS_PINID='MEB_DQS_L7';
NODE_NAME     J32 271
 '@T6G_MB_LIB.T6G(SCH_1):PAGE101_I236@PURE_QUANTA.SCONN288_DDR506112002KQ(CHIPS)':
 'DQS7_B_C||TDQS7_B_C': CDS_PINID='\dqs7_b_c||tdqs7_b_c\';
NET_NAME
'M_E_CPU1_SB_DQS_DN<8>'
 '@T6G_MB_LIB.T6G(SCH_1):M_E_CPU1_SB_DQS_DN'<8>:
 C_SIGNAL='@t6g_mb_lib.t6g(sch_1):m_e_cpu1_sb_dqs_dn(8)';
NODE_NAME     U26 DC69
 '@T6G_MB_LIB.T6G(SCH_1):PAGE41_I159@PURE_QUANTA.GENOA_SP5(CHIPS)':
 'MEB_DQS_L8': CDS_PINID='MEB_DQS_L8';
NODE_NAME     J32 282
 '@T6G_MB_LIB.T6G(SCH_1):PAGE101_I236@PURE_QUANTA.SCONN288_DDR506112002KQ(CHIPS)':
 'DQS8_B_C||TDQS8_B_C': CDS_PINID='\dqs8_b_c||tdqs8_b_c\';
NET_NAME
'M_E_CPU1_SB_DQS_DN<9>'
 '@T6G_MB_LIB.T6G(SCH_1):M_E_CPU1_SB_DQS_DN'<9>:
 C_SIGNAL='@t6g_mb_lib.t6g(sch_1):m_e_cpu1_sb_dqs_dn(9)';
NODE_NAME     U26 BW71
 '@T6G_MB_LIB.T6G(SCH_1):PAGE41_I159@PURE_QUANTA.GENOA_SP5(CHIPS)':
 'MEB_DQS_L9': CDS_PINID='MEB_DQS_L9';
NODE_NAME     J32 94
 '@T6G_MB_LIB.T6G(SCH_1):PAGE101_I236@PURE_QUANTA.SCONN288_DDR506112002KQ(CHIPS)':
 'DQS9_B_C||TDQS9_B_C': CDS_PINID='\dqs9_b_c||tdqs9_b_c\';
NET_NAME
'M_E_CPU1_SB_DQS_DP<0>'
 '@T6G_MB_LIB.T6G(SCH_1):M_E_CPU1_SB_DQS_DP'<0>:
 C_SIGNAL='@t6g_mb_lib.t6g(sch_1):m_e_cpu1_sb_dqs_dp(0)';
NODE_NAME     U26 CD70
 '@T6G_MB_LIB.T6G(SCH_1):PAGE41_I159@PURE_QUANTA.GENOA_SP5(CHIPS)':
 'MEB_DQS_H0': CDS_PINID='MEB_DQS_H0';
NODE_NAME     J32 104
 '@T6G_MB_LIB.T6G(SCH_1):PAGE101_I236@PURE_QUANTA.SCONN288_DDR506112002KQ(CHIPS)':
 'DQS0_B_T': CDS_PINID='DQS0_B_T';
NET_NAME
'M_E_CPU1_SB_DQS_DP<1>'
 '@T6G_MB_LIB.T6G(SCH_1):M_E_CPU1_SB_DQS_DP'<1>:
 C_SIGNAL='@t6g_mb_lib.t6g(sch_1):m_e_cpu1_sb_dqs_dp(1)';
NODE_NAME     U26 CK70
 '@T6G_MB_LIB.T6G(SCH_1):PAGE41_I159@PURE_QUANTA.GENOA_SP5(CHIPS)':
 'MEB_DQS_H1': CDS_PINID='MEB_DQS_H1';
NODE_NAME     J32 115
 '@T6G_MB_LIB.T6G(SCH_1):PAGE101_I236@PURE_QUANTA.SCONN288_DDR506112002KQ(CHIPS)':
 'DQS1_B_T': CDS_PINID='DQS1_B_T';
NET_NAME
'M_E_CPU1_SB_DQS_DP<2>'
 '@T6G_MB_LIB.T6G(SCH_1):M_E_CPU1_SB_DQS_DP'<2>:
 C_SIGNAL='@t6g_mb_lib.t6g(sch_1):m_e_cpu1_sb_dqs_dp(2)';
NODE_NAME     U26 CT70
 '@T6G_MB_LIB.T6G(SCH_1):PAGE41_I159@PURE_QUANTA.GENOA_SP5(CHIPS)':
 'MEB_DQS_H2': CDS_PINID='MEB_DQS_H2';
NODE_NAME     J32 126
 '@T6G_MB_LIB.T6G(SCH_1):PAGE101_I236@PURE_QUANTA.SCONN288_DDR506112002KQ(CHIPS)':
 'DQS2_B_T': CDS_PINID='DQS2_B_T';
NET_NAME
'M_E_CPU1_SB_DQS_DP<3>'
 '@T6G_MB_LIB.T6G(SCH_1):M_E_CPU1_SB_DQS_DP'<3>:
 C_SIGNAL='@t6g_mb_lib.t6g(sch_1):m_e_cpu1_sb_dqs_dp(3)';
NODE_NAME     U26 DB70
 '@T6G_MB_LIB.T6G(SCH_1):PAGE41_I159@PURE_QUANTA.GENOA_SP5(CHIPS)':
 'MEB_DQS_H3': CDS_PINID='MEB_DQS_H3';
NODE_NAME     J32 137
 '@T6G_MB_LIB.T6G(SCH_1):PAGE101_I236@PURE_QUANTA.SCONN288_DDR506112002KQ(CHIPS)':
 'DQS3_B_T': CDS_PINID='DQS3_B_T';
NET_NAME
'M_E_CPU1_SB_DQS_DP<4>'
 '@T6G_MB_LIB.T6G(SCH_1):M_E_CPU1_SB_DQS_DP'<4>:
 C_SIGNAL='@t6g_mb_lib.t6g(sch_1):m_e_cpu1_sb_dqs_dp(4)';
NODE_NAME     U26 BY69
 '@T6G_MB_LIB.T6G(SCH_1):PAGE41_I159@PURE_QUANTA.GENOA_SP5(CHIPS)':
 'MEB_DQS_H4': CDS_PINID='MEB_DQS_H4';
NODE_NAME     J32 239
 '@T6G_MB_LIB.T6G(SCH_1):PAGE101_I236@PURE_QUANTA.SCONN288_DDR506112002KQ(CHIPS)':
 'DQS4_B_T': CDS_PINID='DQS4_B_T';
NET_NAME
'M_E_CPU1_SB_DQS_DP<5>'
 '@T6G_MB_LIB.T6G(SCH_1):M_E_CPU1_SB_DQS_DP'<5>:
 C_SIGNAL='@t6g_mb_lib.t6g(sch_1):m_e_cpu1_sb_dqs_dp(5)';
NODE_NAME     U26 CF69
 '@T6G_MB_LIB.T6G(SCH_1):PAGE41_I159@PURE_QUANTA.GENOA_SP5(CHIPS)':
 'MEB_DQS_H5': CDS_PINID='MEB_DQS_H5';
NODE_NAME     J32 250
 '@T6G_MB_LIB.T6G(SCH_1):PAGE101_I236@PURE_QUANTA.SCONN288_DDR506112002KQ(CHIPS)':
 'DQS5_B_T||TDQS5_B_T': CDS_PINID='\dqs5_b_t||tdqs5_b_t\';
NET_NAME
'M_E_CPU1_SB_DQS_DP<6>'
 '@T6G_MB_LIB.T6G(SCH_1):M_E_CPU1_SB_DQS_DP'<6>:
 C_SIGNAL='@t6g_mb_lib.t6g(sch_1):m_e_cpu1_sb_dqs_dp(6)';
NODE_NAME     U26 CM69
 '@T6G_MB_LIB.T6G(SCH_1):PAGE41_I159@PURE_QUANTA.GENOA_SP5(CHIPS)':
 'MEB_DQS_H6': CDS_PINID='MEB_DQS_H6';
NODE_NAME     J32 261
 '@T6G_MB_LIB.T6G(SCH_1):PAGE101_I236@PURE_QUANTA.SCONN288_DDR506112002KQ(CHIPS)':
 'DQS6_B_T||TDQS6_B_T': CDS_PINID='\dqs6_b_t||tdqs6_b_t\';
NET_NAME
'M_E_CPU1_SB_DQS_DP<7>'
 '@T6G_MB_LIB.T6G(SCH_1):M_E_CPU1_SB_DQS_DP'<7>:
 C_SIGNAL='@t6g_mb_lib.t6g(sch_1):m_e_cpu1_sb_dqs_dp(7)';
NODE_NAME     U26 CV69
 '@T6G_MB_LIB.T6G(SCH_1):PAGE41_I159@PURE_QUANTA.GENOA_SP5(CHIPS)':
 'MEB_DQS_H7': CDS_PINID='MEB_DQS_H7';
NODE_NAME     J32 272
 '@T6G_MB_LIB.T6G(SCH_1):PAGE101_I236@PURE_QUANTA.SCONN288_DDR506112002KQ(CHIPS)':
 'DQS7_B_T||TDQS7_B_T': CDS_PINID='\dqs7_b_t||tdqs7_b_t\';
NET_NAME
'M_E_CPU1_SB_DQS_DP<8>'
 '@T6G_MB_LIB.T6G(SCH_1):M_E_CPU1_SB_DQS_DP'<8>:
 C_SIGNAL='@t6g_mb_lib.t6g(sch_1):m_e_cpu1_sb_dqs_dp(8)';
NODE_NAME     U26 DD69
 '@T6G_MB_LIB.T6G(SCH_1):PAGE41_I159@PURE_QUANTA.GENOA_SP5(CHIPS)':
 'MEB_DQS_H8': CDS_PINID='MEB_DQS_H8';
NODE_NAME     J32 283
 '@T6G_MB_LIB.T6G(SCH_1):PAGE101_I236@PURE_QUANTA.SCONN288_DDR506112002KQ(CHIPS)':
 'DQS8_B_T||TDQS8_B_T': CDS_PINID='\dqs8_b_t||tdqs8_b_t\';
NET_NAME
'M_E_CPU1_SB_DQS_DP<9>'
 '@T6G_MB_LIB.T6G(SCH_1):M_E_CPU1_SB_DQS_DP'<9>:
 C_SIGNAL='@t6g_mb_lib.t6g(sch_1):m_e_cpu1_sb_dqs_dp(9)';
NODE_NAME     U26 BV70
 '@T6G_MB_LIB.T6G(SCH_1):PAGE41_I159@PURE_QUANTA.GENOA_SP5(CHIPS)':
 'MEB_DQS_H9': CDS_PINID='MEB_DQS_H9';
NODE_NAME     J32 93
 '@T6G_MB_LIB.T6G(SCH_1):PAGE101_I236@PURE_QUANTA.SCONN288_DDR506112002KQ(CHIPS)':
 'DQS9_B_T||TDQS9_B_T||DBI4_B_N': CDS_PINID='\dqs9_b_t||tdqs9_b_t||dbi4_b_n\';
NET_NAME
'M_E_CPU1_SB_PAR'
 '@T6G_MB_LIB.T6G(SCH_1):M_E_CPU1_SB_PAR':
 C_SIGNAL='@t6g_mb_lib.t6g(sch_1):m_e_cpu1_sb_par';
NODE_NAME     U26 BL71
 '@T6G_MB_LIB.T6G(SCH_1):PAGE41_I159@PURE_QUANTA.GENOA_SP5(CHIPS)':
 'MEB_PAR': CDS_PINID='MEB_PAR';
NODE_NAME     J32 227
 '@T6G_MB_LIB.T6G(SCH_1):PAGE101_I52@PURE_QUANTA.SCONN288_DDR506112002KQ(CHIPS)':
 'PAR_B': CDS_PINID='PAR_B';
NET_NAME
'M_E_CPU1_SB_RSP<0>'
 '@T6G_MB_LIB.T6G(SCH_1):M_E_CPU1_SB_RSP'<0>:
 C_SIGNAL='@t6g_mb_lib.t6g(sch_1):m_e_cpu1_sb_rsp(0)';
NODE_NAME     U26 BP70
 '@T6G_MB_LIB.T6G(SCH_1):PAGE41_I159@PURE_QUANTA.GENOA_SP5(CHIPS)':
 'MEB0_RSP_L': CDS_PINID='MEB0_RSP_L';
NODE_NAME     J32 87
 '@T6G_MB_LIB.T6G(SCH_1):PAGE101_I52@PURE_QUANTA.SCONN288_DDR506112002KQ(CHIPS)':
 'LBS||RSP_B_N': CDS_PINID='\lbs||rsp_b_n\';
NET_NAME
'M_F_CPU0_ALERT_N'
 '@T6G_MB_LIB.T6G(SCH_1):M_F_CPU0_ALERT_N':
 C_SIGNAL='@t6g_mb_lib.t6g(sch_1):m_f_cpu0_alert_n';
NODE_NAME     R380 1
 '@T6G_MB_LIB.T6G(SCH_1):PAGE15_I314@PURE_QUANTA.Q_RES(CHIPS)':
 'A': CDS_PINID='A';
NODE_NAME     J23 62
 '@T6G_MB_LIB.T6G(SCH_1):PAGE90_I350@PURE_QUANTA.SCONN288_DDR506112002KQ(CHIPS)':
 'ALERT_N': CDS_PINID='ALERT_N';
NET_NAME
'M_F_CPU0_ALERT_R_N'
 '@T6G_MB_LIB.T6G(SCH_1):M_F_CPU0_ALERT_R_N':
 C_SIGNAL='@t6g_mb_lib.t6g(sch_1):m_f_cpu0_alert_r_n';
NODE_NAME     U25 AT65
 '@T6G_MB_LIB.T6G(SCH_1):PAGE15_I159@PURE_QUANTA.GENOA_SP5(CHIPS)':
 'MF_ALERT_L': CDS_PINID='MF_ALERT_L';
NODE_NAME     R380 2
 '@T6G_MB_LIB.T6G(SCH_1):PAGE15_I314@PURE_QUANTA.Q_RES(CHIPS)':
 'B': CDS_PINID='B';
NET_NAME
'M_F_CPU0_CLK_DN<0>'
 '@T6G_MB_LIB.T6G(SCH_1):M_F_CPU0_CLK_DN'<0>:
 C_SIGNAL='@t6g_mb_lib.t6g(sch_1):m_f_cpu0_clk_dn(0)';
NODE_NAME     U25 BD67
 '@T6G_MB_LIB.T6G(SCH_1):PAGE15_I159@PURE_QUANTA.GENOA_SP5(CHIPS)':
 'MF0_CLK_L': CDS_PINID='MF0_CLK_L';
NODE_NAME     J23 218
 '@T6G_MB_LIB.T6G(SCH_1):PAGE90_I350@PURE_QUANTA.SCONN288_DDR506112002KQ(CHIPS)':
 'CK_C': CDS_PINID='CK_C';
NET_NAME
'M_F_CPU0_CLK_DP<0>'
 '@T6G_MB_LIB.T6G(SCH_1):M_F_CPU0_CLK_DP'<0>:
 C_SIGNAL='@t6g_mb_lib.t6g(sch_1):m_f_cpu0_clk_dp(0)';
NODE_NAME     U25 BC67
 '@T6G_MB_LIB.T6G(SCH_1):PAGE15_I159@PURE_QUANTA.GENOA_SP5(CHIPS)':
 'MF0_CLK_H': CDS_PINID='MF0_CLK_H';
NODE_NAME     J23 217
 '@T6G_MB_LIB.T6G(SCH_1):PAGE90_I350@PURE_QUANTA.SCONN288_DDR506112002KQ(CHIPS)':
 'CK_T': CDS_PINID='CK_T';
NET_NAME
'M_F_CPU0_RESET_N'
 '@T6G_MB_LIB.T6G(SCH_1):M_F_CPU0_RESET_N':
 C_SIGNAL='@t6g_mb_lib.t6g(sch_1):m_f_cpu0_reset_n';
NODE_NAME     U25 AU66
 '@T6G_MB_LIB.T6G(SCH_1):PAGE15_I159@PURE_QUANTA.GENOA_SP5(CHIPS)':
 'MF_RESET_L': CDS_PINID='MF_RESET_L';
NODE_NAME     J23 207
 '@T6G_MB_LIB.T6G(SCH_1):PAGE90_I350@PURE_QUANTA.SCONN288_DDR506112002KQ(CHIPS)':
 'RESET_N': CDS_PINID='RESET_N';
NET_NAME
'M_F_CPU0_SA_CA<0>'
 '@T6G_MB_LIB.T6G(SCH_1):M_F_CPU0_SA_CA'<0>:
 C_SIGNAL='@t6g_mb_lib.t6g(sch_1):m_f_cpu0_sa_ca(0)';
NODE_NAME     U25 AW67
 '@T6G_MB_LIB.T6G(SCH_1):PAGE15_I159@PURE_QUANTA.GENOA_SP5(CHIPS)':
 'MFA_CA0': CDS_PINID='MFA_CA0';
NODE_NAME     J23 66
 '@T6G_MB_LIB.T6G(SCH_1):PAGE90_I350@PURE_QUANTA.SCONN288_DDR506112002KQ(CHIPS)':
 'CA0_A': CDS_PINID='CA0_A';
NET_NAME
'M_F_CPU0_SA_CA<1>'
 '@T6G_MB_LIB.T6G(SCH_1):M_F_CPU0_SA_CA'<1>:
 C_SIGNAL='@t6g_mb_lib.t6g(sch_1):m_f_cpu0_sa_ca(1)';
NODE_NAME     U25 AY67
 '@T6G_MB_LIB.T6G(SCH_1):PAGE15_I159@PURE_QUANTA.GENOA_SP5(CHIPS)':
 'MFA_CA1': CDS_PINID='MFA_CA1';
NODE_NAME     J23 211
 '@T6G_MB_LIB.T6G(SCH_1):PAGE90_I350@PURE_QUANTA.SCONN288_DDR506112002KQ(CHIPS)':
 'CA1_A': CDS_PINID='CA1_A';
NET_NAME
'M_F_CPU0_SA_CA<2>'
 '@T6G_MB_LIB.T6G(SCH_1):M_F_CPU0_SA_CA'<2>:
 C_SIGNAL='@t6g_mb_lib.t6g(sch_1):m_f_cpu0_sa_ca(2)';
NODE_NAME     U25 AY65
 '@T6G_MB_LIB.T6G(SCH_1):PAGE15_I159@PURE_QUANTA.GENOA_SP5(CHIPS)':
 'MFA_CA2': CDS_PINID='MFA_CA2';
NODE_NAME     J23 68
 '@T6G_MB_LIB.T6G(SCH_1):PAGE90_I350@PURE_QUANTA.SCONN288_DDR506112002KQ(CHIPS)':
 'CA2_A': CDS_PINID='CA2_A';
NET_NAME
'M_F_CPU0_SA_CA<3>'
 '@T6G_MB_LIB.T6G(SCH_1):M_F_CPU0_SA_CA'<3>:
 C_SIGNAL='@t6g_mb_lib.t6g(sch_1):m_f_cpu0_sa_ca(3)';
NODE_NAME     U25 BA66
 '@T6G_MB_LIB.T6G(SCH_1):PAGE15_I159@PURE_QUANTA.GENOA_SP5(CHIPS)':
 'MFA_CA3': CDS_PINID='MFA_CA3';
NODE_NAME     J23 213
 '@T6G_MB_LIB.T6G(SCH_1):PAGE90_I350@PURE_QUANTA.SCONN288_DDR506112002KQ(CHIPS)':
 'CA3_A': CDS_PINID='CA3_A';
NET_NAME
'M_F_CPU0_SA_CA<4>'
 '@T6G_MB_LIB.T6G(SCH_1):M_F_CPU0_SA_CA'<4>:
 C_SIGNAL='@t6g_mb_lib.t6g(sch_1):m_f_cpu0_sa_ca(4)';
NODE_NAME     U25 BA67
 '@T6G_MB_LIB.T6G(SCH_1):PAGE15_I159@PURE_QUANTA.GENOA_SP5(CHIPS)':
 'MFA_CA4': CDS_PINID='MFA_CA4';
NODE_NAME     J23 70
 '@T6G_MB_LIB.T6G(SCH_1):PAGE90_I350@PURE_QUANTA.SCONN288_DDR506112002KQ(CHIPS)':
 'CA4_A': CDS_PINID='CA4_A';
NET_NAME
'M_F_CPU0_SA_CA<5>'
 '@T6G_MB_LIB.T6G(SCH_1):M_F_CPU0_SA_CA'<5>:
 C_SIGNAL='@t6g_mb_lib.t6g(sch_1):m_f_cpu0_sa_ca(5)';
NODE_NAME     U25 BB67
 '@T6G_MB_LIB.T6G(SCH_1):PAGE15_I159@PURE_QUANTA.GENOA_SP5(CHIPS)':
 'MFA_CA5': CDS_PINID='MFA_CA5';
NODE_NAME     J23 215
 '@T6G_MB_LIB.T6G(SCH_1):PAGE90_I350@PURE_QUANTA.SCONN288_DDR506112002KQ(CHIPS)':
 'CA5_A': CDS_PINID='CA5_A';
NET_NAME
'M_F_CPU0_SA_CA<6>'
 '@T6G_MB_LIB.T6G(SCH_1):M_F_CPU0_SA_CA'<6>:
 C_SIGNAL='@t6g_mb_lib.t6g(sch_1):m_f_cpu0_sa_ca(6)';
NODE_NAME     U25 BB65
 '@T6G_MB_LIB.T6G(SCH_1):PAGE15_I159@PURE_QUANTA.GENOA_SP5(CHIPS)':
 'MFA_CA6': CDS_PINID='MFA_CA6';
NODE_NAME     J23 72
 '@T6G_MB_LIB.T6G(SCH_1):PAGE90_I350@PURE_QUANTA.SCONN288_DDR506112002KQ(CHIPS)':
 'CA6_A': CDS_PINID='CA6_A';
NET_NAME
'M_F_CPU0_SA_CB<0>'
 '@T6G_MB_LIB.T6G(SCH_1):M_F_CPU0_SA_CB'<0>:
 C_SIGNAL='@t6g_mb_lib.t6g(sch_1):m_f_cpu0_sa_cb(0)';
NODE_NAME     U25 AJ67
 '@T6G_MB_LIB.T6G(SCH_1):PAGE15_I159@PURE_QUANTA.GENOA_SP5(CHIPS)':
 'MFA_CHECK0': CDS_PINID='MFA_CHECK0';
NODE_NAME     J23 51
 '@T6G_MB_LIB.T6G(SCH_1):PAGE90_I350@PURE_QUANTA.SCONN288_DDR506112002KQ(CHIPS)':
 'CB0_A': CDS_PINID='CB0_A';
NET_NAME
'M_F_CPU0_SA_CB<1>'
 '@T6G_MB_LIB.T6G(SCH_1):M_F_CPU0_SA_CB'<1>:
 C_SIGNAL='@t6g_mb_lib.t6g(sch_1):m_f_cpu0_sa_cb(1)';
NODE_NAME     U25 AK65
 '@T6G_MB_LIB.T6G(SCH_1):PAGE15_I159@PURE_QUANTA.GENOA_SP5(CHIPS)':
 'MFA_CHECK1': CDS_PINID='MFA_CHECK1';
NODE_NAME     J23 53
 '@T6G_MB_LIB.T6G(SCH_1):PAGE90_I350@PURE_QUANTA.SCONN288_DDR506112002KQ(CHIPS)':
 'CB1_A': CDS_PINID='CB1_A';
NET_NAME
'M_F_CPU0_SA_CB<2>'
 '@T6G_MB_LIB.T6G(SCH_1):M_F_CPU0_SA_CB'<2>:
 C_SIGNAL='@t6g_mb_lib.t6g(sch_1):m_f_cpu0_sa_cb(2)';
NODE_NAME     U25 AK67
 '@T6G_MB_LIB.T6G(SCH_1):PAGE15_I159@PURE_QUANTA.GENOA_SP5(CHIPS)':
 'MFA_CHECK2': CDS_PINID='MFA_CHECK2';
NODE_NAME     J23 196
 '@T6G_MB_LIB.T6G(SCH_1):PAGE90_I350@PURE_QUANTA.SCONN288_DDR506112002KQ(CHIPS)':
 'CB2_A': CDS_PINID='CB2_A';
NET_NAME
'M_F_CPU0_SA_CB<3>'
 '@T6G_MB_LIB.T6G(SCH_1):M_F_CPU0_SA_CB'<3>:
 C_SIGNAL='@t6g_mb_lib.t6g(sch_1):m_f_cpu0_sa_cb(3)';
NODE_NAME     U25 AL66
 '@T6G_MB_LIB.T6G(SCH_1):PAGE15_I159@PURE_QUANTA.GENOA_SP5(CHIPS)':
 'MFA_CHECK3': CDS_PINID='MFA_CHECK3';
NODE_NAME     J23 198
 '@T6G_MB_LIB.T6G(SCH_1):PAGE90_I350@PURE_QUANTA.SCONN288_DDR506112002KQ(CHIPS)':
 'CB3_A': CDS_PINID='CB3_A';
NET_NAME
'M_F_CPU0_SA_CB<4>'
 '@T6G_MB_LIB.T6G(SCH_1):M_F_CPU0_SA_CB'<4>:
 C_SIGNAL='@t6g_mb_lib.t6g(sch_1):m_f_cpu0_sa_cb(4)';
NODE_NAME     U25 AN67
 '@T6G_MB_LIB.T6G(SCH_1):PAGE15_I159@PURE_QUANTA.GENOA_SP5(CHIPS)':
 'MFA_CHECK4': CDS_PINID='MFA_CHECK4';
NODE_NAME     J23 58
 '@T6G_MB_LIB.T6G(SCH_1):PAGE90_I350@PURE_QUANTA.SCONN288_DDR506112002KQ(CHIPS)':
 'CB4_A': CDS_PINID='CB4_A';
NET_NAME
'M_F_CPU0_SA_CB<5>'
 '@T6G_MB_LIB.T6G(SCH_1):M_F_CPU0_SA_CB'<5>:
 C_SIGNAL='@t6g_mb_lib.t6g(sch_1):m_f_cpu0_sa_cb(5)';
NODE_NAME     U25 AP65
 '@T6G_MB_LIB.T6G(SCH_1):PAGE15_I159@PURE_QUANTA.GENOA_SP5(CHIPS)':
 'MFA_CHECK5': CDS_PINID='MFA_CHECK5';
NODE_NAME     J23 60
 '@T6G_MB_LIB.T6G(SCH_1):PAGE90_I350@PURE_QUANTA.SCONN288_DDR506112002KQ(CHIPS)':
 'CB5_A': CDS_PINID='CB5_A';
NET_NAME
'M_F_CPU0_SA_CB<6>'
 '@T6G_MB_LIB.T6G(SCH_1):M_F_CPU0_SA_CB'<6>:
 C_SIGNAL='@t6g_mb_lib.t6g(sch_1):m_f_cpu0_sa_cb(6)';
NODE_NAME     U25 AP67
 '@T6G_MB_LIB.T6G(SCH_1):PAGE15_I159@PURE_QUANTA.GENOA_SP5(CHIPS)':
 'MFA_CHECK6': CDS_PINID='MFA_CHECK6';
NODE_NAME     J23 203
 '@T6G_MB_LIB.T6G(SCH_1):PAGE90_I350@PURE_QUANTA.SCONN288_DDR506112002KQ(CHIPS)':
 'CB6_A': CDS_PINID='CB6_A';
NET_NAME
'M_F_CPU0_SA_CB<7>'
 '@T6G_MB_LIB.T6G(SCH_1):M_F_CPU0_SA_CB'<7>:
 C_SIGNAL='@t6g_mb_lib.t6g(sch_1):m_f_cpu0_sa_cb(7)';
NODE_NAME     U25 AR66
 '@T6G_MB_LIB.T6G(SCH_1):PAGE15_I159@PURE_QUANTA.GENOA_SP5(CHIPS)':
 'MFA_CHECK7': CDS_PINID='MFA_CHECK7';
NODE_NAME     J23 205
 '@T6G_MB_LIB.T6G(SCH_1):PAGE90_I350@PURE_QUANTA.SCONN288_DDR506112002KQ(CHIPS)':
 'CB7_A': CDS_PINID='CB7_A';
NET_NAME
'M_F_CPU0_SA_CS_N<0>'
 '@T6G_MB_LIB.T6G(SCH_1):M_F_CPU0_SA_CS_N'<0>:
 C_SIGNAL='@t6g_mb_lib.t6g(sch_1):m_f_cpu0_sa_cs_n(0)';
NODE_NAME     U25 AV67
 '@T6G_MB_LIB.T6G(SCH_1):PAGE15_I159@PURE_QUANTA.GENOA_SP5(CHIPS)':
 'MFA0_CS_L0': CDS_PINID='MFA0_CS_L0';
NODE_NAME     J23 64
 '@T6G_MB_LIB.T6G(SCH_1):PAGE90_I350@PURE_QUANTA.SCONN288_DDR506112002KQ(CHIPS)':
 'CS0_A_N': CDS_PINID='CS0_A_N';
NET_NAME
'M_F_CPU0_SA_CS_N<1>'
 '@T6G_MB_LIB.T6G(SCH_1):M_F_CPU0_SA_CS_N'<1>:
 C_SIGNAL='@t6g_mb_lib.t6g(sch_1):m_f_cpu0_sa_cs_n(1)';
NODE_NAME     U25 AW66
 '@T6G_MB_LIB.T6G(SCH_1):PAGE15_I159@PURE_QUANTA.GENOA_SP5(CHIPS)':
 'MFA0_CS_L1': CDS_PINID='MFA0_CS_L1';
NODE_NAME     J23 209
 '@T6G_MB_LIB.T6G(SCH_1):PAGE90_I350@PURE_QUANTA.SCONN288_DDR506112002KQ(CHIPS)':
 'CS1_A_N': CDS_PINID='CS1_A_N';
NET_NAME
'M_F_CPU0_SA_DQ<0>'
 '@T6G_MB_LIB.T6G(SCH_1):M_F_CPU0_SA_DQ'<0>:
 C_SIGNAL='@t6g_mb_lib.t6g(sch_1):m_f_cpu0_sa_dq(0)';
NODE_NAME     U25 E67
 '@T6G_MB_LIB.T6G(SCH_1):PAGE15_I159@PURE_QUANTA.GENOA_SP5(CHIPS)':
 'MFA_DATA0': CDS_PINID='MFA_DATA0';
NODE_NAME     J23 7
 '@T6G_MB_LIB.T6G(SCH_1):PAGE90_I350@PURE_QUANTA.SCONN288_DDR506112002KQ(CHIPS)':
 'DQ0_A': CDS_PINID='DQ0_A';
NET_NAME
'M_F_CPU0_SA_DQ<10>'
 '@T6G_MB_LIB.T6G(SCH_1):M_F_CPU0_SA_DQ'<10>:
 C_SIGNAL='@t6g_mb_lib.t6g(sch_1):m_f_cpu0_sa_dq(10)';
NODE_NAME     U25 M67
 '@T6G_MB_LIB.T6G(SCH_1):PAGE15_I159@PURE_QUANTA.GENOA_SP5(CHIPS)':
 'MFA_DATA10': CDS_PINID='MFA_DATA10';
NODE_NAME     J23 163
 '@T6G_MB_LIB.T6G(SCH_1):PAGE90_I350@PURE_QUANTA.SCONN288_DDR506112002KQ(CHIPS)':
 'DQ10_A': CDS_PINID='DQ10_A';
NET_NAME
'M_F_CPU0_SA_DQ<11>'
 '@T6G_MB_LIB.T6G(SCH_1):M_F_CPU0_SA_DQ'<11>:
 C_SIGNAL='@t6g_mb_lib.t6g(sch_1):m_f_cpu0_sa_dq(11)';
NODE_NAME     U25 N66
 '@T6G_MB_LIB.T6G(SCH_1):PAGE15_I159@PURE_QUANTA.GENOA_SP5(CHIPS)':
 'MFA_DATA11': CDS_PINID='MFA_DATA11';
NODE_NAME     J23 165
 '@T6G_MB_LIB.T6G(SCH_1):PAGE90_I350@PURE_QUANTA.SCONN288_DDR506112002KQ(CHIPS)':
 'DQ11_A': CDS_PINID='DQ11_A';
NET_NAME
'M_F_CPU0_SA_DQ<12>'
 '@T6G_MB_LIB.T6G(SCH_1):M_F_CPU0_SA_DQ'<12>:
 C_SIGNAL='@t6g_mb_lib.t6g(sch_1):m_f_cpu0_sa_dq(12)';
NODE_NAME     U25 R67
 '@T6G_MB_LIB.T6G(SCH_1):PAGE15_I159@PURE_QUANTA.GENOA_SP5(CHIPS)':
 'MFA_DATA12': CDS_PINID='MFA_DATA12';
NODE_NAME     J23 25
 '@T6G_MB_LIB.T6G(SCH_1):PAGE90_I350@PURE_QUANTA.SCONN288_DDR506112002KQ(CHIPS)':
 'DQ12_A': CDS_PINID='DQ12_A';
NET_NAME
'M_F_CPU0_SA_DQ<13>'
 '@T6G_MB_LIB.T6G(SCH_1):M_F_CPU0_SA_DQ'<13>:
 C_SIGNAL='@t6g_mb_lib.t6g(sch_1):m_f_cpu0_sa_dq(13)';
NODE_NAME     U25 T65
 '@T6G_MB_LIB.T6G(SCH_1):PAGE15_I159@PURE_QUANTA.GENOA_SP5(CHIPS)':
 'MFA_DATA13': CDS_PINID='MFA_DATA13';
NODE_NAME     J23 27
 '@T6G_MB_LIB.T6G(SCH_1):PAGE90_I350@PURE_QUANTA.SCONN288_DDR506112002KQ(CHIPS)':
 'DQ13_A': CDS_PINID='DQ13_A';
NET_NAME
'M_F_CPU0_SA_DQ<14>'
 '@T6G_MB_LIB.T6G(SCH_1):M_F_CPU0_SA_DQ'<14>:
 C_SIGNAL='@t6g_mb_lib.t6g(sch_1):m_f_cpu0_sa_dq(14)';
NODE_NAME     U25 T67
 '@T6G_MB_LIB.T6G(SCH_1):PAGE15_I159@PURE_QUANTA.GENOA_SP5(CHIPS)':
 'MFA_DATA14': CDS_PINID='MFA_DATA14';
NODE_NAME     J23 170
 '@T6G_MB_LIB.T6G(SCH_1):PAGE90_I350@PURE_QUANTA.SCONN288_DDR506112002KQ(CHIPS)':
 'DQ14_A': CDS_PINID='DQ14_A';
NET_NAME
'M_F_CPU0_SA_DQ<15>'
 '@T6G_MB_LIB.T6G(SCH_1):M_F_CPU0_SA_DQ'<15>:
 C_SIGNAL='@t6g_mb_lib.t6g(sch_1):m_f_cpu0_sa_dq(15)';
NODE_NAME     U25 U66
 '@T6G_MB_LIB.T6G(SCH_1):PAGE15_I159@PURE_QUANTA.GENOA_SP5(CHIPS)':
 'MFA_DATA15': CDS_PINID='MFA_DATA15';
NODE_NAME     J23 172
 '@T6G_MB_LIB.T6G(SCH_1):PAGE90_I350@PURE_QUANTA.SCONN288_DDR506112002KQ(CHIPS)':
 'DQ15_A': CDS_PINID='DQ15_A';
NET_NAME
'M_F_CPU0_SA_DQ<16>'
 '@T6G_MB_LIB.T6G(SCH_1):M_F_CPU0_SA_DQ'<16>:
 C_SIGNAL='@t6g_mb_lib.t6g(sch_1):m_f_cpu0_sa_dq(16)';
NODE_NAME     U25 U67
 '@T6G_MB_LIB.T6G(SCH_1):PAGE15_I159@PURE_QUANTA.GENOA_SP5(CHIPS)':
 'MFA_DATA16': CDS_PINID='MFA_DATA16';
NODE_NAME     J23 29
 '@T6G_MB_LIB.T6G(SCH_1):PAGE90_I350@PURE_QUANTA.SCONN288_DDR506112002KQ(CHIPS)':
 'DQ16_A': CDS_PINID='DQ16_A';
NET_NAME
'M_F_CPU0_SA_DQ<17>'
 '@T6G_MB_LIB.T6G(SCH_1):M_F_CPU0_SA_DQ'<17>:
 C_SIGNAL='@t6g_mb_lib.t6g(sch_1):m_f_cpu0_sa_dq(17)';
NODE_NAME     U25 V65
 '@T6G_MB_LIB.T6G(SCH_1):PAGE15_I159@PURE_QUANTA.GENOA_SP5(CHIPS)':
 'MFA_DATA17': CDS_PINID='MFA_DATA17';
NODE_NAME     J23 31
 '@T6G_MB_LIB.T6G(SCH_1):PAGE90_I350@PURE_QUANTA.SCONN288_DDR506112002KQ(CHIPS)':
 'DQ17_A': CDS_PINID='DQ17_A';
NET_NAME
'M_F_CPU0_SA_DQ<18>'
 '@T6G_MB_LIB.T6G(SCH_1):M_F_CPU0_SA_DQ'<18>:
 C_SIGNAL='@t6g_mb_lib.t6g(sch_1):m_f_cpu0_sa_dq(18)';
NODE_NAME     U25 V67
 '@T6G_MB_LIB.T6G(SCH_1):PAGE15_I159@PURE_QUANTA.GENOA_SP5(CHIPS)':
 'MFA_DATA18': CDS_PINID='MFA_DATA18';
NODE_NAME     J23 174
 '@T6G_MB_LIB.T6G(SCH_1):PAGE90_I350@PURE_QUANTA.SCONN288_DDR506112002KQ(CHIPS)':
 'DQ18_A': CDS_PINID='DQ18_A';
NET_NAME
'M_F_CPU0_SA_DQ<19>'
 '@T6G_MB_LIB.T6G(SCH_1):M_F_CPU0_SA_DQ'<19>:
 C_SIGNAL='@t6g_mb_lib.t6g(sch_1):m_f_cpu0_sa_dq(19)';
NODE_NAME     U25 W66
 '@T6G_MB_LIB.T6G(SCH_1):PAGE15_I159@PURE_QUANTA.GENOA_SP5(CHIPS)':
 'MFA_DATA19': CDS_PINID='MFA_DATA19';
NODE_NAME     J23 176
 '@T6G_MB_LIB.T6G(SCH_1):PAGE90_I350@PURE_QUANTA.SCONN288_DDR506112002KQ(CHIPS)':
 'DQ19_A': CDS_PINID='DQ19_A';
NET_NAME
'M_F_CPU0_SA_DQ<1>'
 '@T6G_MB_LIB.T6G(SCH_1):M_F_CPU0_SA_DQ'<1>:
 C_SIGNAL='@t6g_mb_lib.t6g(sch_1):m_f_cpu0_sa_dq(1)';
NODE_NAME     U25 F65
 '@T6G_MB_LIB.T6G(SCH_1):PAGE15_I159@PURE_QUANTA.GENOA_SP5(CHIPS)':
 'MFA_DATA1': CDS_PINID='MFA_DATA1';
NODE_NAME     J23 9
 '@T6G_MB_LIB.T6G(SCH_1):PAGE90_I350@PURE_QUANTA.SCONN288_DDR506112002KQ(CHIPS)':
 'DQ1_A': CDS_PINID='DQ1_A';
NET_NAME
'M_F_CPU0_SA_DQ<20>'
 '@T6G_MB_LIB.T6G(SCH_1):M_F_CPU0_SA_DQ'<20>:
 C_SIGNAL='@t6g_mb_lib.t6g(sch_1):m_f_cpu0_sa_dq(20)';
NODE_NAME     U25 AA67
 '@T6G_MB_LIB.T6G(SCH_1):PAGE15_I159@PURE_QUANTA.GENOA_SP5(CHIPS)':
 'MFA_DATA20': CDS_PINID='MFA_DATA20';
NODE_NAME     J23 36
 '@T6G_MB_LIB.T6G(SCH_1):PAGE90_I350@PURE_QUANTA.SCONN288_DDR506112002KQ(CHIPS)':
 'DQ20_A': CDS_PINID='DQ20_A';
NET_NAME
'M_F_CPU0_SA_DQ<21>'
 '@T6G_MB_LIB.T6G(SCH_1):M_F_CPU0_SA_DQ'<21>:
 C_SIGNAL='@t6g_mb_lib.t6g(sch_1):m_f_cpu0_sa_dq(21)';
NODE_NAME     U25 AB65
 '@T6G_MB_LIB.T6G(SCH_1):PAGE15_I159@PURE_QUANTA.GENOA_SP5(CHIPS)':
 'MFA_DATA21': CDS_PINID='MFA_DATA21';
NODE_NAME     J23 38
 '@T6G_MB_LIB.T6G(SCH_1):PAGE90_I350@PURE_QUANTA.SCONN288_DDR506112002KQ(CHIPS)':
 'DQ21_A': CDS_PINID='DQ21_A';
NET_NAME
'M_F_CPU0_SA_DQ<22>'
 '@T6G_MB_LIB.T6G(SCH_1):M_F_CPU0_SA_DQ'<22>:
 C_SIGNAL='@t6g_mb_lib.t6g(sch_1):m_f_cpu0_sa_dq(22)';
NODE_NAME     U25 AB67
 '@T6G_MB_LIB.T6G(SCH_1):PAGE15_I159@PURE_QUANTA.GENOA_SP5(CHIPS)':
 'MFA_DATA22': CDS_PINID='MFA_DATA22';
NODE_NAME     J23 181
 '@T6G_MB_LIB.T6G(SCH_1):PAGE90_I350@PURE_QUANTA.SCONN288_DDR506112002KQ(CHIPS)':
 'DQ22_A': CDS_PINID='DQ22_A';
NET_NAME
'M_F_CPU0_SA_DQ<23>'
 '@T6G_MB_LIB.T6G(SCH_1):M_F_CPU0_SA_DQ'<23>:
 C_SIGNAL='@t6g_mb_lib.t6g(sch_1):m_f_cpu0_sa_dq(23)';
NODE_NAME     U25 AC66
 '@T6G_MB_LIB.T6G(SCH_1):PAGE15_I159@PURE_QUANTA.GENOA_SP5(CHIPS)':
 'MFA_DATA23': CDS_PINID='MFA_DATA23';
NODE_NAME     J23 183
 '@T6G_MB_LIB.T6G(SCH_1):PAGE90_I350@PURE_QUANTA.SCONN288_DDR506112002KQ(CHIPS)':
 'DQ23_A': CDS_PINID='DQ23_A';
NET_NAME
'M_F_CPU0_SA_DQ<24>'
 '@T6G_MB_LIB.T6G(SCH_1):M_F_CPU0_SA_DQ'<24>:
 C_SIGNAL='@t6g_mb_lib.t6g(sch_1):m_f_cpu0_sa_dq(24)';
NODE_NAME     U25 AC67
 '@T6G_MB_LIB.T6G(SCH_1):PAGE15_I159@PURE_QUANTA.GENOA_SP5(CHIPS)':
 'MFA_DATA24': CDS_PINID='MFA_DATA24';
NODE_NAME     J23 40
 '@T6G_MB_LIB.T6G(SCH_1):PAGE90_I350@PURE_QUANTA.SCONN288_DDR506112002KQ(CHIPS)':
 'DQ24_A': CDS_PINID='DQ24_A';
NET_NAME
'M_F_CPU0_SA_DQ<25>'
 '@T6G_MB_LIB.T6G(SCH_1):M_F_CPU0_SA_DQ'<25>:
 C_SIGNAL='@t6g_mb_lib.t6g(sch_1):m_f_cpu0_sa_dq(25)';
NODE_NAME     U25 AD65
 '@T6G_MB_LIB.T6G(SCH_1):PAGE15_I159@PURE_QUANTA.GENOA_SP5(CHIPS)':
 'MFA_DATA25': CDS_PINID='MFA_DATA25';
NODE_NAME     J23 42
 '@T6G_MB_LIB.T6G(SCH_1):PAGE90_I350@PURE_QUANTA.SCONN288_DDR506112002KQ(CHIPS)':
 'DQ25_A': CDS_PINID='DQ25_A';
NET_NAME
'M_F_CPU0_SA_DQ<26>'
 '@T6G_MB_LIB.T6G(SCH_1):M_F_CPU0_SA_DQ'<26>:
 C_SIGNAL='@t6g_mb_lib.t6g(sch_1):m_f_cpu0_sa_dq(26)';
NODE_NAME     U25 AD67
 '@T6G_MB_LIB.T6G(SCH_1):PAGE15_I159@PURE_QUANTA.GENOA_SP5(CHIPS)':
 'MFA_DATA26': CDS_PINID='MFA_DATA26';
NODE_NAME     J23 185
 '@T6G_MB_LIB.T6G(SCH_1):PAGE90_I350@PURE_QUANTA.SCONN288_DDR506112002KQ(CHIPS)':
 'DQ26_A': CDS_PINID='DQ26_A';
NET_NAME
'M_F_CPU0_SA_DQ<27>'
 '@T6G_MB_LIB.T6G(SCH_1):M_F_CPU0_SA_DQ'<27>:
 C_SIGNAL='@t6g_mb_lib.t6g(sch_1):m_f_cpu0_sa_dq(27)';
NODE_NAME     U25 AE66
 '@T6G_MB_LIB.T6G(SCH_1):PAGE15_I159@PURE_QUANTA.GENOA_SP5(CHIPS)':
 'MFA_DATA27': CDS_PINID='MFA_DATA27';
NODE_NAME     J23 187
 '@T6G_MB_LIB.T6G(SCH_1):PAGE90_I350@PURE_QUANTA.SCONN288_DDR506112002KQ(CHIPS)':
 'DQ27_A': CDS_PINID='DQ27_A';
NET_NAME
'M_F_CPU0_SA_DQ<28>'
 '@T6G_MB_LIB.T6G(SCH_1):M_F_CPU0_SA_DQ'<28>:
 C_SIGNAL='@t6g_mb_lib.t6g(sch_1):m_f_cpu0_sa_dq(28)';
NODE_NAME     U25 AG67
 '@T6G_MB_LIB.T6G(SCH_1):PAGE15_I159@PURE_QUANTA.GENOA_SP5(CHIPS)':
 'MFA_DATA28': CDS_PINID='MFA_DATA28';
NODE_NAME     J23 47
 '@T6G_MB_LIB.T6G(SCH_1):PAGE90_I350@PURE_QUANTA.SCONN288_DDR506112002KQ(CHIPS)':
 'DQ28_A': CDS_PINID='DQ28_A';
NET_NAME
'M_F_CPU0_SA_DQ<29>'
 '@T6G_MB_LIB.T6G(SCH_1):M_F_CPU0_SA_DQ'<29>:
 C_SIGNAL='@t6g_mb_lib.t6g(sch_1):m_f_cpu0_sa_dq(29)';
NODE_NAME     U25 AH65
 '@T6G_MB_LIB.T6G(SCH_1):PAGE15_I159@PURE_QUANTA.GENOA_SP5(CHIPS)':
 'MFA_DATA29': CDS_PINID='MFA_DATA29';
NODE_NAME     J23 49
 '@T6G_MB_LIB.T6G(SCH_1):PAGE90_I350@PURE_QUANTA.SCONN288_DDR506112002KQ(CHIPS)':
 'DQ29_A': CDS_PINID='DQ29_A';
NET_NAME
'M_F_CPU0_SA_DQ<2>'
 '@T6G_MB_LIB.T6G(SCH_1):M_F_CPU0_SA_DQ'<2>:
 C_SIGNAL='@t6g_mb_lib.t6g(sch_1):m_f_cpu0_sa_dq(2)';
NODE_NAME     U25 F67
 '@T6G_MB_LIB.T6G(SCH_1):PAGE15_I159@PURE_QUANTA.GENOA_SP5(CHIPS)':
 'MFA_DATA2': CDS_PINID='MFA_DATA2';
NODE_NAME     J23 152
 '@T6G_MB_LIB.T6G(SCH_1):PAGE90_I350@PURE_QUANTA.SCONN288_DDR506112002KQ(CHIPS)':
 'DQ2_A': CDS_PINID='DQ2_A';
NET_NAME
'M_F_CPU0_SA_DQ<30>'
 '@T6G_MB_LIB.T6G(SCH_1):M_F_CPU0_SA_DQ'<30>:
 C_SIGNAL='@t6g_mb_lib.t6g(sch_1):m_f_cpu0_sa_dq(30)';
NODE_NAME     U25 AH67
 '@T6G_MB_LIB.T6G(SCH_1):PAGE15_I159@PURE_QUANTA.GENOA_SP5(CHIPS)':
 'MFA_DATA30': CDS_PINID='MFA_DATA30';
NODE_NAME     J23 192
 '@T6G_MB_LIB.T6G(SCH_1):PAGE90_I350@PURE_QUANTA.SCONN288_DDR506112002KQ(CHIPS)':
 'DQ30_A': CDS_PINID='DQ30_A';
NET_NAME
'M_F_CPU0_SA_DQ<31>'
 '@T6G_MB_LIB.T6G(SCH_1):M_F_CPU0_SA_DQ'<31>:
 C_SIGNAL='@t6g_mb_lib.t6g(sch_1):m_f_cpu0_sa_dq(31)';
NODE_NAME     U25 AJ66
 '@T6G_MB_LIB.T6G(SCH_1):PAGE15_I159@PURE_QUANTA.GENOA_SP5(CHIPS)':
 'MFA_DATA31': CDS_PINID='MFA_DATA31';
NODE_NAME     J23 194
 '@T6G_MB_LIB.T6G(SCH_1):PAGE90_I350@PURE_QUANTA.SCONN288_DDR506112002KQ(CHIPS)':
 'DQ31_A': CDS_PINID='DQ31_A';
NET_NAME
'M_F_CPU0_SA_DQ<3>'
 '@T6G_MB_LIB.T6G(SCH_1):M_F_CPU0_SA_DQ'<3>:
 C_SIGNAL='@t6g_mb_lib.t6g(sch_1):m_f_cpu0_sa_dq(3)';
NODE_NAME     U25 G66
 '@T6G_MB_LIB.T6G(SCH_1):PAGE15_I159@PURE_QUANTA.GENOA_SP5(CHIPS)':
 'MFA_DATA3': CDS_PINID='MFA_DATA3';
NODE_NAME     J23 154
 '@T6G_MB_LIB.T6G(SCH_1):PAGE90_I350@PURE_QUANTA.SCONN288_DDR506112002KQ(CHIPS)':
 'DQ3_A': CDS_PINID='DQ3_A';
NET_NAME
'M_F_CPU0_SA_DQ<4>'
 '@T6G_MB_LIB.T6G(SCH_1):M_F_CPU0_SA_DQ'<4>:
 C_SIGNAL='@t6g_mb_lib.t6g(sch_1):m_f_cpu0_sa_dq(4)';
NODE_NAME     U25 J67
 '@T6G_MB_LIB.T6G(SCH_1):PAGE15_I159@PURE_QUANTA.GENOA_SP5(CHIPS)':
 'MFA_DATA4': CDS_PINID='MFA_DATA4';
NODE_NAME     J23 14
 '@T6G_MB_LIB.T6G(SCH_1):PAGE90_I350@PURE_QUANTA.SCONN288_DDR506112002KQ(CHIPS)':
 'DQ4_A': CDS_PINID='DQ4_A';
NET_NAME
'M_F_CPU0_SA_DQ<5>'
 '@T6G_MB_LIB.T6G(SCH_1):M_F_CPU0_SA_DQ'<5>:
 C_SIGNAL='@t6g_mb_lib.t6g(sch_1):m_f_cpu0_sa_dq(5)';
NODE_NAME     U25 K65
 '@T6G_MB_LIB.T6G(SCH_1):PAGE15_I159@PURE_QUANTA.GENOA_SP5(CHIPS)':
 'MFA_DATA5': CDS_PINID='MFA_DATA5';
NODE_NAME     J23 16
 '@T6G_MB_LIB.T6G(SCH_1):PAGE90_I350@PURE_QUANTA.SCONN288_DDR506112002KQ(CHIPS)':
 'DQ5_A': CDS_PINID='DQ5_A';
NET_NAME
'M_F_CPU0_SA_DQ<6>'
 '@T6G_MB_LIB.T6G(SCH_1):M_F_CPU0_SA_DQ'<6>:
 C_SIGNAL='@t6g_mb_lib.t6g(sch_1):m_f_cpu0_sa_dq(6)';
NODE_NAME     U25 K67
 '@T6G_MB_LIB.T6G(SCH_1):PAGE15_I159@PURE_QUANTA.GENOA_SP5(CHIPS)':
 'MFA_DATA6': CDS_PINID='MFA_DATA6';
NODE_NAME     J23 159
 '@T6G_MB_LIB.T6G(SCH_1):PAGE90_I350@PURE_QUANTA.SCONN288_DDR506112002KQ(CHIPS)':
 'DQ6_A': CDS_PINID='DQ6_A';
NET_NAME
'M_F_CPU0_SA_DQ<7>'
 '@T6G_MB_LIB.T6G(SCH_1):M_F_CPU0_SA_DQ'<7>:
 C_SIGNAL='@t6g_mb_lib.t6g(sch_1):m_f_cpu0_sa_dq(7)';
NODE_NAME     U25 L66
 '@T6G_MB_LIB.T6G(SCH_1):PAGE15_I159@PURE_QUANTA.GENOA_SP5(CHIPS)':
 'MFA_DATA7': CDS_PINID='MFA_DATA7';
NODE_NAME     J23 161
 '@T6G_MB_LIB.T6G(SCH_1):PAGE90_I350@PURE_QUANTA.SCONN288_DDR506112002KQ(CHIPS)':
 'DQ7_A': CDS_PINID='DQ7_A';
NET_NAME
'M_F_CPU0_SA_DQ<8>'
 '@T6G_MB_LIB.T6G(SCH_1):M_F_CPU0_SA_DQ'<8>:
 C_SIGNAL='@t6g_mb_lib.t6g(sch_1):m_f_cpu0_sa_dq(8)';
NODE_NAME     U25 L67
 '@T6G_MB_LIB.T6G(SCH_1):PAGE15_I159@PURE_QUANTA.GENOA_SP5(CHIPS)':
 'MFA_DATA8': CDS_PINID='MFA_DATA8';
NODE_NAME     J23 18
 '@T6G_MB_LIB.T6G(SCH_1):PAGE90_I350@PURE_QUANTA.SCONN288_DDR506112002KQ(CHIPS)':
 'DQ8_A': CDS_PINID='DQ8_A';
NET_NAME
'M_F_CPU0_SA_DQ<9>'
 '@T6G_MB_LIB.T6G(SCH_1):M_F_CPU0_SA_DQ'<9>:
 C_SIGNAL='@t6g_mb_lib.t6g(sch_1):m_f_cpu0_sa_dq(9)';
NODE_NAME     U25 M65
 '@T6G_MB_LIB.T6G(SCH_1):PAGE15_I159@PURE_QUANTA.GENOA_SP5(CHIPS)':
 'MFA_DATA9': CDS_PINID='MFA_DATA9';
NODE_NAME     J23 20
 '@T6G_MB_LIB.T6G(SCH_1):PAGE90_I350@PURE_QUANTA.SCONN288_DDR506112002KQ(CHIPS)':
 'DQ9_A': CDS_PINID='DQ9_A';
NET_NAME
'M_F_CPU0_SA_DQS_DN<0>'
 '@T6G_MB_LIB.T6G(SCH_1):M_F_CPU0_SA_DQS_DN'<0>:
 C_SIGNAL='@t6g_mb_lib.t6g(sch_1):m_f_cpu0_sa_dqs_dn(0)';
NODE_NAME     U25 H67
 '@T6G_MB_LIB.T6G(SCH_1):PAGE15_I159@PURE_QUANTA.GENOA_SP5(CHIPS)':
 'MFA_DQS_L0': CDS_PINID='MFA_DQS_L0';
NODE_NAME     J23 12
 '@T6G_MB_LIB.T6G(SCH_1):PAGE90_I412@PURE_QUANTA.SCONN288_DDR506112002KQ(CHIPS)':
 'DQS0_A_C': CDS_PINID='DQS0_A_C';
NET_NAME
'M_F_CPU0_SA_DQS_DN<1>'
 '@T6G_MB_LIB.T6G(SCH_1):M_F_CPU0_SA_DQS_DN'<1>:
 C_SIGNAL='@t6g_mb_lib.t6g(sch_1):m_f_cpu0_sa_dqs_dn(1)';
NODE_NAME     U25 P67
 '@T6G_MB_LIB.T6G(SCH_1):PAGE15_I159@PURE_QUANTA.GENOA_SP5(CHIPS)':
 'MFA_DQS_L1': CDS_PINID='MFA_DQS_L1';
NODE_NAME     J23 23
 '@T6G_MB_LIB.T6G(SCH_1):PAGE90_I412@PURE_QUANTA.SCONN288_DDR506112002KQ(CHIPS)':
 'DQS1_A_C': CDS_PINID='DQS1_A_C';
NET_NAME
'M_F_CPU0_SA_DQS_DN<2>'
 '@T6G_MB_LIB.T6G(SCH_1):M_F_CPU0_SA_DQS_DN'<2>:
 C_SIGNAL='@t6g_mb_lib.t6g(sch_1):m_f_cpu0_sa_dqs_dn(2)';
NODE_NAME     U25 Y67
 '@T6G_MB_LIB.T6G(SCH_1):PAGE15_I159@PURE_QUANTA.GENOA_SP5(CHIPS)':
 'MFA_DQS_L2': CDS_PINID='MFA_DQS_L2';
NODE_NAME     J23 34
 '@T6G_MB_LIB.T6G(SCH_1):PAGE90_I412@PURE_QUANTA.SCONN288_DDR506112002KQ(CHIPS)':
 'DQS2_A_C': CDS_PINID='DQS2_A_C';
NET_NAME
'M_F_CPU0_SA_DQS_DN<3>'
 '@T6G_MB_LIB.T6G(SCH_1):M_F_CPU0_SA_DQS_DN'<3>:
 C_SIGNAL='@t6g_mb_lib.t6g(sch_1):m_f_cpu0_sa_dqs_dn(3)';
NODE_NAME     U25 AF67
 '@T6G_MB_LIB.T6G(SCH_1):PAGE15_I159@PURE_QUANTA.GENOA_SP5(CHIPS)':
 'MFA_DQS_L3': CDS_PINID='MFA_DQS_L3';
NODE_NAME     J23 45
 '@T6G_MB_LIB.T6G(SCH_1):PAGE90_I412@PURE_QUANTA.SCONN288_DDR506112002KQ(CHIPS)':
 'DQS3_A_C': CDS_PINID='DQS3_A_C';
NET_NAME
'M_F_CPU0_SA_DQS_DN<4>'
 '@T6G_MB_LIB.T6G(SCH_1):M_F_CPU0_SA_DQS_DN'<4>:
 C_SIGNAL='@t6g_mb_lib.t6g(sch_1):m_f_cpu0_sa_dqs_dn(4)';
NODE_NAME     U25 AM67
 '@T6G_MB_LIB.T6G(SCH_1):PAGE15_I159@PURE_QUANTA.GENOA_SP5(CHIPS)':
 'MFA_DQS_L4': CDS_PINID='MFA_DQS_L4';
NODE_NAME     J23 56
 '@T6G_MB_LIB.T6G(SCH_1):PAGE90_I412@PURE_QUANTA.SCONN288_DDR506112002KQ(CHIPS)':
 'DQS4_A_C': CDS_PINID='DQS4_A_C';
NET_NAME
'M_F_CPU0_SA_DQS_DN<5>'
 '@T6G_MB_LIB.T6G(SCH_1):M_F_CPU0_SA_DQS_DN'<5>:
 C_SIGNAL='@t6g_mb_lib.t6g(sch_1):m_f_cpu0_sa_dqs_dn(5)';
NODE_NAME     U25 H65
 '@T6G_MB_LIB.T6G(SCH_1):PAGE15_I159@PURE_QUANTA.GENOA_SP5(CHIPS)':
 'MFA_DQS_L5': CDS_PINID='MFA_DQS_L5';
NODE_NAME     J23 156
 '@T6G_MB_LIB.T6G(SCH_1):PAGE90_I412@PURE_QUANTA.SCONN288_DDR506112002KQ(CHIPS)':
 'DQS5_A_C||TDQS5_A_C||DQS5_A_T||TDQS5_A_T': CDS_PINID='\dqs5_a_c||tdqs5_a_c||dqs5_a_t||tdqs5_a_t\';
NET_NAME
'M_F_CPU0_SA_DQS_DN<6>'
 '@T6G_MB_LIB.T6G(SCH_1):M_F_CPU0_SA_DQS_DN'<6>:
 C_SIGNAL='@t6g_mb_lib.t6g(sch_1):m_f_cpu0_sa_dqs_dn(6)';
NODE_NAME     U25 P65
 '@T6G_MB_LIB.T6G(SCH_1):PAGE15_I159@PURE_QUANTA.GENOA_SP5(CHIPS)':
 'MFA_DQS_L6': CDS_PINID='MFA_DQS_L6';
NODE_NAME     J23 167
 '@T6G_MB_LIB.T6G(SCH_1):PAGE90_I412@PURE_QUANTA.SCONN288_DDR506112002KQ(CHIPS)':
 'DQS6_A_C||TDQS6_A_C||DQS6_A_T||TDQS6_A_T': CDS_PINID='\dqs6_a_c||tdqs6_a_c||dqs6_a_t||tdqs6_a_t\';
NET_NAME
'M_F_CPU0_SA_DQS_DN<7>'
 '@T6G_MB_LIB.T6G(SCH_1):M_F_CPU0_SA_DQS_DN'<7>:
 C_SIGNAL='@t6g_mb_lib.t6g(sch_1):m_f_cpu0_sa_dqs_dn(7)';
NODE_NAME     U25 Y65
 '@T6G_MB_LIB.T6G(SCH_1):PAGE15_I159@PURE_QUANTA.GENOA_SP5(CHIPS)':
 'MFA_DQS_L7': CDS_PINID='MFA_DQS_L7';
NODE_NAME     J23 178
 '@T6G_MB_LIB.T6G(SCH_1):PAGE90_I412@PURE_QUANTA.SCONN288_DDR506112002KQ(CHIPS)':
 'DQS7_A_C||TDQS7_A_C': CDS_PINID='\dqs7_a_c||tdqs7_a_c\';
NET_NAME
'M_F_CPU0_SA_DQS_DN<8>'
 '@T6G_MB_LIB.T6G(SCH_1):M_F_CPU0_SA_DQS_DN'<8>:
 C_SIGNAL='@t6g_mb_lib.t6g(sch_1):m_f_cpu0_sa_dqs_dn(8)';
NODE_NAME     U25 AF65
 '@T6G_MB_LIB.T6G(SCH_1):PAGE15_I159@PURE_QUANTA.GENOA_SP5(CHIPS)':
 'MFA_DQS_L8': CDS_PINID='MFA_DQS_L8';
NODE_NAME     J23 189
 '@T6G_MB_LIB.T6G(SCH_1):PAGE90_I412@PURE_QUANTA.SCONN288_DDR506112002KQ(CHIPS)':
 'DQS8_A_C||TDQS8_A_C': CDS_PINID='\dqs8_a_c||tdqs8_a_c\';
NET_NAME
'M_F_CPU0_SA_DQS_DN<9>'
 '@T6G_MB_LIB.T6G(SCH_1):M_F_CPU0_SA_DQS_DN'<9>:
 C_SIGNAL='@t6g_mb_lib.t6g(sch_1):m_f_cpu0_sa_dqs_dn(9)';
NODE_NAME     U25 AM65
 '@T6G_MB_LIB.T6G(SCH_1):PAGE15_I159@PURE_QUANTA.GENOA_SP5(CHIPS)':
 'MFA_DQS_L9': CDS_PINID='MFA_DQS_L9';
NODE_NAME     J23 200
 '@T6G_MB_LIB.T6G(SCH_1):PAGE90_I412@PURE_QUANTA.SCONN288_DDR506112002KQ(CHIPS)':
 'DQS9_A_C||TDQS9_A_C': CDS_PINID='\dqs9_a_c||tdqs9_a_c\';
NET_NAME
'M_F_CPU0_SA_DQS_DP<0>'
 '@T6G_MB_LIB.T6G(SCH_1):M_F_CPU0_SA_DQS_DP'<0>:
 C_SIGNAL='@t6g_mb_lib.t6g(sch_1):m_f_cpu0_sa_dqs_dp(0)';
NODE_NAME     U25 G67
 '@T6G_MB_LIB.T6G(SCH_1):PAGE15_I159@PURE_QUANTA.GENOA_SP5(CHIPS)':
 'MFA_DQS_H0': CDS_PINID='MFA_DQS_H0';
NODE_NAME     J23 11
 '@T6G_MB_LIB.T6G(SCH_1):PAGE90_I412@PURE_QUANTA.SCONN288_DDR506112002KQ(CHIPS)':
 'DQS0_A_T': CDS_PINID='DQS0_A_T';
NET_NAME
'M_F_CPU0_SA_DQS_DP<1>'
 '@T6G_MB_LIB.T6G(SCH_1):M_F_CPU0_SA_DQS_DP'<1>:
 C_SIGNAL='@t6g_mb_lib.t6g(sch_1):m_f_cpu0_sa_dqs_dp(1)';
NODE_NAME     U25 N67
 '@T6G_MB_LIB.T6G(SCH_1):PAGE15_I159@PURE_QUANTA.GENOA_SP5(CHIPS)':
 'MFA_DQS_H1': CDS_PINID='MFA_DQS_H1';
NODE_NAME     J23 22
 '@T6G_MB_LIB.T6G(SCH_1):PAGE90_I412@PURE_QUANTA.SCONN288_DDR506112002KQ(CHIPS)':
 'DQS1_A_T': CDS_PINID='DQS1_A_T';
NET_NAME
'M_F_CPU0_SA_DQS_DP<2>'
 '@T6G_MB_LIB.T6G(SCH_1):M_F_CPU0_SA_DQS_DP'<2>:
 C_SIGNAL='@t6g_mb_lib.t6g(sch_1):m_f_cpu0_sa_dqs_dp(2)';
NODE_NAME     U25 W67
 '@T6G_MB_LIB.T6G(SCH_1):PAGE15_I159@PURE_QUANTA.GENOA_SP5(CHIPS)':
 'MFA_DQS_H2': CDS_PINID='MFA_DQS_H2';
NODE_NAME     J23 33
 '@T6G_MB_LIB.T6G(SCH_1):PAGE90_I412@PURE_QUANTA.SCONN288_DDR506112002KQ(CHIPS)':
 'DQS2_A_T': CDS_PINID='DQS2_A_T';
NET_NAME
'M_F_CPU0_SA_DQS_DP<3>'
 '@T6G_MB_LIB.T6G(SCH_1):M_F_CPU0_SA_DQS_DP'<3>:
 C_SIGNAL='@t6g_mb_lib.t6g(sch_1):m_f_cpu0_sa_dqs_dp(3)';
NODE_NAME     U25 AE67
 '@T6G_MB_LIB.T6G(SCH_1):PAGE15_I159@PURE_QUANTA.GENOA_SP5(CHIPS)':
 'MFA_DQS_H3': CDS_PINID='MFA_DQS_H3';
NODE_NAME     J23 44
 '@T6G_MB_LIB.T6G(SCH_1):PAGE90_I412@PURE_QUANTA.SCONN288_DDR506112002KQ(CHIPS)':
 'DQS3_A_T': CDS_PINID='DQS3_A_T';
NET_NAME
'M_F_CPU0_SA_DQS_DP<4>'
 '@T6G_MB_LIB.T6G(SCH_1):M_F_CPU0_SA_DQS_DP'<4>:
 C_SIGNAL='@t6g_mb_lib.t6g(sch_1):m_f_cpu0_sa_dqs_dp(4)';
NODE_NAME     U25 AL67
 '@T6G_MB_LIB.T6G(SCH_1):PAGE15_I159@PURE_QUANTA.GENOA_SP5(CHIPS)':
 'MFA_DQS_H4': CDS_PINID='MFA_DQS_H4';
NODE_NAME     J23 55
 '@T6G_MB_LIB.T6G(SCH_1):PAGE90_I412@PURE_QUANTA.SCONN288_DDR506112002KQ(CHIPS)':
 'DQS4_A_T': CDS_PINID='DQS4_A_T';
NET_NAME
'M_F_CPU0_SA_DQS_DP<5>'
 '@T6G_MB_LIB.T6G(SCH_1):M_F_CPU0_SA_DQS_DP'<5>:
 C_SIGNAL='@t6g_mb_lib.t6g(sch_1):m_f_cpu0_sa_dqs_dp(5)';
NODE_NAME     U25 J66
 '@T6G_MB_LIB.T6G(SCH_1):PAGE15_I159@PURE_QUANTA.GENOA_SP5(CHIPS)':
 'MFA_DQS_H5': CDS_PINID='MFA_DQS_H5';
NODE_NAME     J23 157
 '@T6G_MB_LIB.T6G(SCH_1):PAGE90_I412@PURE_QUANTA.SCONN288_DDR506112002KQ(CHIPS)':
 'DQS5_A_T||TDQS5_A_T': CDS_PINID='\dqs5_a_t||tdqs5_a_t\';
NET_NAME
'M_F_CPU0_SA_DQS_DP<6>'
 '@T6G_MB_LIB.T6G(SCH_1):M_F_CPU0_SA_DQS_DP'<6>:
 C_SIGNAL='@t6g_mb_lib.t6g(sch_1):m_f_cpu0_sa_dqs_dp(6)';
NODE_NAME     U25 R66
 '@T6G_MB_LIB.T6G(SCH_1):PAGE15_I159@PURE_QUANTA.GENOA_SP5(CHIPS)':
 'MFA_DQS_H6': CDS_PINID='MFA_DQS_H6';
NODE_NAME     J23 168
 '@T6G_MB_LIB.T6G(SCH_1):PAGE90_I412@PURE_QUANTA.SCONN288_DDR506112002KQ(CHIPS)':
 'DQS6_A_T||TDQS6_A_T': CDS_PINID='\dqs6_a_t||tdqs6_a_t\';
NET_NAME
'M_F_CPU0_SA_DQS_DP<7>'
 '@T6G_MB_LIB.T6G(SCH_1):M_F_CPU0_SA_DQS_DP'<7>:
 C_SIGNAL='@t6g_mb_lib.t6g(sch_1):m_f_cpu0_sa_dqs_dp(7)';
NODE_NAME     U25 AA66
 '@T6G_MB_LIB.T6G(SCH_1):PAGE15_I159@PURE_QUANTA.GENOA_SP5(CHIPS)':
 'MFA_DQS_H7': CDS_PINID='MFA_DQS_H7';
NODE_NAME     J23 179
 '@T6G_MB_LIB.T6G(SCH_1):PAGE90_I412@PURE_QUANTA.SCONN288_DDR506112002KQ(CHIPS)':
 'DQS7_A_T||TDQS7_A_T': CDS_PINID='\dqs7_a_t||tdqs7_a_t\';
NET_NAME
'M_F_CPU0_SA_DQS_DP<8>'
 '@T6G_MB_LIB.T6G(SCH_1):M_F_CPU0_SA_DQS_DP'<8>:
 C_SIGNAL='@t6g_mb_lib.t6g(sch_1):m_f_cpu0_sa_dqs_dp(8)';
NODE_NAME     U25 AG66
 '@T6G_MB_LIB.T6G(SCH_1):PAGE15_I159@PURE_QUANTA.GENOA_SP5(CHIPS)':
 'MFA_DQS_H8': CDS_PINID='MFA_DQS_H8';
NODE_NAME     J23 190
 '@T6G_MB_LIB.T6G(SCH_1):PAGE90_I412@PURE_QUANTA.SCONN288_DDR506112002KQ(CHIPS)':
 'DQS8_A_T||TDQS8_A_T': CDS_PINID='\dqs8_a_t||tdqs8_a_t\';
NET_NAME
'M_F_CPU0_SA_DQS_DP<9>'
 '@T6G_MB_LIB.T6G(SCH_1):M_F_CPU0_SA_DQS_DP'<9>:
 C_SIGNAL='@t6g_mb_lib.t6g(sch_1):m_f_cpu0_sa_dqs_dp(9)';
NODE_NAME     U25 AN66
 '@T6G_MB_LIB.T6G(SCH_1):PAGE15_I159@PURE_QUANTA.GENOA_SP5(CHIPS)':
 'MFA_DQS_H9': CDS_PINID='MFA_DQS_H9';
NODE_NAME     J23 201
 '@T6G_MB_LIB.T6G(SCH_1):PAGE90_I412@PURE_QUANTA.SCONN288_DDR506112002KQ(CHIPS)':
 'DQS9_A_T||TDQS9_A_T': CDS_PINID='\dqs9_a_t||tdqs9_a_t\';
NET_NAME
'M_F_CPU0_SA_PAR'
 '@T6G_MB_LIB.T6G(SCH_1):M_F_CPU0_SA_PAR':
 C_SIGNAL='@t6g_mb_lib.t6g(sch_1):m_f_cpu0_sa_par';
NODE_NAME     U25 BC66
 '@T6G_MB_LIB.T6G(SCH_1):PAGE15_I159@PURE_QUANTA.GENOA_SP5(CHIPS)':
 'MFA_PAR': CDS_PINID='MFA_PAR';
NODE_NAME     J23 74
 '@T6G_MB_LIB.T6G(SCH_1):PAGE90_I350@PURE_QUANTA.SCONN288_DDR506112002KQ(CHIPS)':
 'PAR_A': CDS_PINID='PAR_A';
NET_NAME
'M_F_CPU0_SA_RSP<0>'
 '@T6G_MB_LIB.T6G(SCH_1):M_F_CPU0_SA_RSP'<0>:
 C_SIGNAL='@t6g_mb_lib.t6g(sch_1):m_f_cpu0_sa_rsp(0)';
NODE_NAME     U25 BN66
 '@T6G_MB_LIB.T6G(SCH_1):PAGE15_I159@PURE_QUANTA.GENOA_SP5(CHIPS)':
 'MFA0_RSP_L': CDS_PINID='MFA0_RSP_L';
NODE_NAME     J23 86
 '@T6G_MB_LIB.T6G(SCH_1):PAGE90_I350@PURE_QUANTA.SCONN288_DDR506112002KQ(CHIPS)':
 'LBD||RSP_A_N': CDS_PINID='\lbd||rsp_a_n\';
NET_NAME
'M_F_CPU0_SB_CA<0>'
 '@T6G_MB_LIB.T6G(SCH_1):M_F_CPU0_SB_CA'<0>:
 C_SIGNAL='@t6g_mb_lib.t6g(sch_1):m_f_cpu0_sb_ca(0)';
NODE_NAME     U25 BG66
 '@T6G_MB_LIB.T6G(SCH_1):PAGE15_I159@PURE_QUANTA.GENOA_SP5(CHIPS)':
 'MFB_CA0': CDS_PINID='MFB_CA0';
NODE_NAME     J23 76
 '@T6G_MB_LIB.T6G(SCH_1):PAGE90_I350@PURE_QUANTA.SCONN288_DDR506112002KQ(CHIPS)':
 'CA0_B': CDS_PINID='CA0_B';
NET_NAME
'M_F_CPU0_SB_CA<1>'
 '@T6G_MB_LIB.T6G(SCH_1):M_F_CPU0_SB_CA'<1>:
 C_SIGNAL='@t6g_mb_lib.t6g(sch_1):m_f_cpu0_sb_ca(1)';
NODE_NAME     U25 BH65
 '@T6G_MB_LIB.T6G(SCH_1):PAGE15_I159@PURE_QUANTA.GENOA_SP5(CHIPS)':
 'MFB_CA1': CDS_PINID='MFB_CA1';
NODE_NAME     J23 221
 '@T6G_MB_LIB.T6G(SCH_1):PAGE90_I350@PURE_QUANTA.SCONN288_DDR506112002KQ(CHIPS)':
 'CA1_B': CDS_PINID='CA1_B';
NET_NAME
'M_F_CPU0_SB_CA<2>'
 '@T6G_MB_LIB.T6G(SCH_1):M_F_CPU0_SB_CA'<2>:
 C_SIGNAL='@t6g_mb_lib.t6g(sch_1):m_f_cpu0_sb_ca(2)';
NODE_NAME     U25 BH67
 '@T6G_MB_LIB.T6G(SCH_1):PAGE15_I159@PURE_QUANTA.GENOA_SP5(CHIPS)':
 'MFB_CA2': CDS_PINID='MFB_CA2';
NODE_NAME     J23 78
 '@T6G_MB_LIB.T6G(SCH_1):PAGE90_I350@PURE_QUANTA.SCONN288_DDR506112002KQ(CHIPS)':
 'CA2_B': CDS_PINID='CA2_B';
NET_NAME
'M_F_CPU0_SB_CA<3>'
 '@T6G_MB_LIB.T6G(SCH_1):M_F_CPU0_SB_CA'<3>:
 C_SIGNAL='@t6g_mb_lib.t6g(sch_1):m_f_cpu0_sb_ca(3)';
NODE_NAME     U25 BJ67
 '@T6G_MB_LIB.T6G(SCH_1):PAGE15_I159@PURE_QUANTA.GENOA_SP5(CHIPS)':
 'MFB_CA3': CDS_PINID='MFB_CA3';
NODE_NAME     J23 223
 '@T6G_MB_LIB.T6G(SCH_1):PAGE90_I350@PURE_QUANTA.SCONN288_DDR506112002KQ(CHIPS)':
 'CA3_B': CDS_PINID='CA3_B';
NET_NAME
'M_F_CPU0_SB_CA<4>'
 '@T6G_MB_LIB.T6G(SCH_1):M_F_CPU0_SB_CA'<4>:
 C_SIGNAL='@t6g_mb_lib.t6g(sch_1):m_f_cpu0_sb_ca(4)';
NODE_NAME     U25 BJ66
 '@T6G_MB_LIB.T6G(SCH_1):PAGE15_I159@PURE_QUANTA.GENOA_SP5(CHIPS)':
 'MFB_CA4': CDS_PINID='MFB_CA4';
NODE_NAME     J23 80
 '@T6G_MB_LIB.T6G(SCH_1):PAGE90_I350@PURE_QUANTA.SCONN288_DDR506112002KQ(CHIPS)':
 'CA4_B': CDS_PINID='CA4_B';
NET_NAME
'M_F_CPU0_SB_CA<5>'
 '@T6G_MB_LIB.T6G(SCH_1):M_F_CPU0_SB_CA'<5>:
 C_SIGNAL='@t6g_mb_lib.t6g(sch_1):m_f_cpu0_sb_ca(5)';
NODE_NAME     U25 BK65
 '@T6G_MB_LIB.T6G(SCH_1):PAGE15_I159@PURE_QUANTA.GENOA_SP5(CHIPS)':
 'MFB_CA5': CDS_PINID='MFB_CA5';
NODE_NAME     J23 225
 '@T6G_MB_LIB.T6G(SCH_1):PAGE90_I350@PURE_QUANTA.SCONN288_DDR506112002KQ(CHIPS)':
 'CA5_B': CDS_PINID='CA5_B';
NET_NAME
'M_F_CPU0_SB_CA<6>'
 '@T6G_MB_LIB.T6G(SCH_1):M_F_CPU0_SB_CA'<6>:
 C_SIGNAL='@t6g_mb_lib.t6g(sch_1):m_f_cpu0_sb_ca(6)';
NODE_NAME     U25 BK67
 '@T6G_MB_LIB.T6G(SCH_1):PAGE15_I159@PURE_QUANTA.GENOA_SP5(CHIPS)':
 'MFB_CA6': CDS_PINID='MFB_CA6';
NODE_NAME     J23 82
 '@T6G_MB_LIB.T6G(SCH_1):PAGE90_I350@PURE_QUANTA.SCONN288_DDR506112002KQ(CHIPS)':
 'CA6_B': CDS_PINID='CA6_B';
NET_NAME
'M_F_CPU0_SB_CB<0>'
 '@T6G_MB_LIB.T6G(SCH_1):M_F_CPU0_SB_CB'<0>:
 C_SIGNAL='@t6g_mb_lib.t6g(sch_1):m_f_cpu0_sb_cb(0)';
NODE_NAME     U25 BY67
 '@T6G_MB_LIB.T6G(SCH_1):PAGE15_I159@PURE_QUANTA.GENOA_SP5(CHIPS)':
 'MFB_CHECK0': CDS_PINID='MFB_CHECK0';
NODE_NAME     J23 96
 '@T6G_MB_LIB.T6G(SCH_1):PAGE90_I350@PURE_QUANTA.SCONN288_DDR506112002KQ(CHIPS)':
 'CB0_B': CDS_PINID='CB0_B';
NET_NAME
'M_F_CPU0_SB_CB<1>'
 '@T6G_MB_LIB.T6G(SCH_1):M_F_CPU0_SB_CB'<1>:
 C_SIGNAL='@t6g_mb_lib.t6g(sch_1):m_f_cpu0_sb_cb(1)';
NODE_NAME     U25 CA66
 '@T6G_MB_LIB.T6G(SCH_1):PAGE15_I159@PURE_QUANTA.GENOA_SP5(CHIPS)':
 'MFB_CHECK1': CDS_PINID='MFB_CHECK1';
NODE_NAME     J23 98
 '@T6G_MB_LIB.T6G(SCH_1):PAGE90_I350@PURE_QUANTA.SCONN288_DDR506112002KQ(CHIPS)':
 'CB1_B': CDS_PINID='CB1_B';
NET_NAME
'M_F_CPU0_SB_CB<2>'
 '@T6G_MB_LIB.T6G(SCH_1):M_F_CPU0_SB_CB'<2>:
 C_SIGNAL='@t6g_mb_lib.t6g(sch_1):m_f_cpu0_sb_cb(2)';
NODE_NAME     U25 CA67
 '@T6G_MB_LIB.T6G(SCH_1):PAGE15_I159@PURE_QUANTA.GENOA_SP5(CHIPS)':
 'MFB_CHECK2': CDS_PINID='MFB_CHECK2';
NODE_NAME     J23 241
 '@T6G_MB_LIB.T6G(SCH_1):PAGE90_I350@PURE_QUANTA.SCONN288_DDR506112002KQ(CHIPS)':
 'CB2_B': CDS_PINID='CB2_B';
NET_NAME
'M_F_CPU0_SB_CB<3>'
 '@T6G_MB_LIB.T6G(SCH_1):M_F_CPU0_SB_CB'<3>:
 C_SIGNAL='@t6g_mb_lib.t6g(sch_1):m_f_cpu0_sb_cb(3)';
NODE_NAME     U25 CB65
 '@T6G_MB_LIB.T6G(SCH_1):PAGE15_I159@PURE_QUANTA.GENOA_SP5(CHIPS)':
 'MFB_CHECK3': CDS_PINID='MFB_CHECK3';
NODE_NAME     J23 243
 '@T6G_MB_LIB.T6G(SCH_1):PAGE90_I350@PURE_QUANTA.SCONN288_DDR506112002KQ(CHIPS)':
 'CB3_B': CDS_PINID='CB3_B';
NET_NAME
'M_F_CPU0_SB_CB<4>'
 '@T6G_MB_LIB.T6G(SCH_1):M_F_CPU0_SB_CB'<4>:
 C_SIGNAL='@t6g_mb_lib.t6g(sch_1):m_f_cpu0_sb_cb(4)';
NODE_NAME     U25 BT67
 '@T6G_MB_LIB.T6G(SCH_1):PAGE15_I159@PURE_QUANTA.GENOA_SP5(CHIPS)':
 'MFB_CHECK4': CDS_PINID='MFB_CHECK4';
NODE_NAME     J23 89
 '@T6G_MB_LIB.T6G(SCH_1):PAGE90_I350@PURE_QUANTA.SCONN288_DDR506112002KQ(CHIPS)':
 'CB4_B': CDS_PINID='CB4_B';
NET_NAME
'M_F_CPU0_SB_CB<5>'
 '@T6G_MB_LIB.T6G(SCH_1):M_F_CPU0_SB_CB'<5>:
 C_SIGNAL='@t6g_mb_lib.t6g(sch_1):m_f_cpu0_sb_cb(5)';
NODE_NAME     U25 BU66
 '@T6G_MB_LIB.T6G(SCH_1):PAGE15_I159@PURE_QUANTA.GENOA_SP5(CHIPS)':
 'MFB_CHECK5': CDS_PINID='MFB_CHECK5';
NODE_NAME     J23 91
 '@T6G_MB_LIB.T6G(SCH_1):PAGE90_I350@PURE_QUANTA.SCONN288_DDR506112002KQ(CHIPS)':
 'CB5_B': CDS_PINID='CB5_B';
NET_NAME
'M_F_CPU0_SB_CB<6>'
 '@T6G_MB_LIB.T6G(SCH_1):M_F_CPU0_SB_CB'<6>:
 C_SIGNAL='@t6g_mb_lib.t6g(sch_1):m_f_cpu0_sb_cb(6)';
NODE_NAME     U25 BU67
 '@T6G_MB_LIB.T6G(SCH_1):PAGE15_I159@PURE_QUANTA.GENOA_SP5(CHIPS)':
 'MFB_CHECK6': CDS_PINID='MFB_CHECK6';
NODE_NAME     J23 234
 '@T6G_MB_LIB.T6G(SCH_1):PAGE90_I350@PURE_QUANTA.SCONN288_DDR506112002KQ(CHIPS)':
 'CB6_B': CDS_PINID='CB6_B';
NET_NAME
'M_F_CPU0_SB_CB<7>'
 '@T6G_MB_LIB.T6G(SCH_1):M_F_CPU0_SB_CB'<7>:
 C_SIGNAL='@t6g_mb_lib.t6g(sch_1):m_f_cpu0_sb_cb(7)';
NODE_NAME     U25 BV65
 '@T6G_MB_LIB.T6G(SCH_1):PAGE15_I159@PURE_QUANTA.GENOA_SP5(CHIPS)':
 'MFB_CHECK7': CDS_PINID='MFB_CHECK7';
NODE_NAME     J23 236
 '@T6G_MB_LIB.T6G(SCH_1):PAGE90_I350@PURE_QUANTA.SCONN288_DDR506112002KQ(CHIPS)':
 'CB7_B': CDS_PINID='CB7_B';
NET_NAME
'M_F_CPU0_SB_CS_N<0>'
 '@T6G_MB_LIB.T6G(SCH_1):M_F_CPU0_SB_CS_N'<0>:
 C_SIGNAL='@t6g_mb_lib.t6g(sch_1):m_f_cpu0_sb_cs_n(0)';
NODE_NAME     U25 BM65
 '@T6G_MB_LIB.T6G(SCH_1):PAGE15_I159@PURE_QUANTA.GENOA_SP5(CHIPS)':
 'MFB0_CS_L0': CDS_PINID='MFB0_CS_L0';
NODE_NAME     J23 84
 '@T6G_MB_LIB.T6G(SCH_1):PAGE90_I350@PURE_QUANTA.SCONN288_DDR506112002KQ(CHIPS)':
 'CS0_B_N': CDS_PINID='CS0_B_N';
NET_NAME
'M_F_CPU0_SB_CS_N<1>'
 '@T6G_MB_LIB.T6G(SCH_1):M_F_CPU0_SB_CS_N'<1>:
 C_SIGNAL='@t6g_mb_lib.t6g(sch_1):m_f_cpu0_sb_cs_n(1)';
NODE_NAME     U25 BN67
 '@T6G_MB_LIB.T6G(SCH_1):PAGE15_I159@PURE_QUANTA.GENOA_SP5(CHIPS)':
 'MFB0_CS_L1': CDS_PINID='MFB0_CS_L1';
NODE_NAME     J23 229
 '@T6G_MB_LIB.T6G(SCH_1):PAGE90_I350@PURE_QUANTA.SCONN288_DDR506112002KQ(CHIPS)':
 'CS1_B_N': CDS_PINID='CS1_B_N';
NET_NAME
'M_F_CPU0_SB_DQ<0>'
 '@T6G_MB_LIB.T6G(SCH_1):M_F_CPU0_SB_DQ'<0>:
 C_SIGNAL='@t6g_mb_lib.t6g(sch_1):m_f_cpu0_sb_dq(0)';
NODE_NAME     U25 CB67
 '@T6G_MB_LIB.T6G(SCH_1):PAGE15_I159@PURE_QUANTA.GENOA_SP5(CHIPS)':
 'MFB_DATA0': CDS_PINID='MFB_DATA0';
NODE_NAME     J23 100
 '@T6G_MB_LIB.T6G(SCH_1):PAGE90_I350@PURE_QUANTA.SCONN288_DDR506112002KQ(CHIPS)':
 'DQ0_B': CDS_PINID='DQ0_B';
NET_NAME
'M_F_CPU0_SB_DQ<10>'
 '@T6G_MB_LIB.T6G(SCH_1):M_F_CPU0_SB_DQ'<10>:
 C_SIGNAL='@t6g_mb_lib.t6g(sch_1):m_f_cpu0_sb_dq(10)';
NODE_NAME     U25 CJ67
 '@T6G_MB_LIB.T6G(SCH_1):PAGE15_I159@PURE_QUANTA.GENOA_SP5(CHIPS)':
 'MFB_DATA10': CDS_PINID='MFB_DATA10';
NODE_NAME     J23 256
 '@T6G_MB_LIB.T6G(SCH_1):PAGE90_I350@PURE_QUANTA.SCONN288_DDR506112002KQ(CHIPS)':
 'DQ10_B': CDS_PINID='DQ10_B';
NET_NAME
'M_F_CPU0_SB_DQ<11>'
 '@T6G_MB_LIB.T6G(SCH_1):M_F_CPU0_SB_DQ'<11>:
 C_SIGNAL='@t6g_mb_lib.t6g(sch_1):m_f_cpu0_sb_dq(11)';
NODE_NAME     U25 CK65
 '@T6G_MB_LIB.T6G(SCH_1):PAGE15_I159@PURE_QUANTA.GENOA_SP5(CHIPS)':
 'MFB_DATA11': CDS_PINID='MFB_DATA11';
NODE_NAME     J23 258
 '@T6G_MB_LIB.T6G(SCH_1):PAGE90_I350@PURE_QUANTA.SCONN288_DDR506112002KQ(CHIPS)':
 'DQ11_B': CDS_PINID='DQ11_B';
NET_NAME
'M_F_CPU0_SB_DQ<12>'
 '@T6G_MB_LIB.T6G(SCH_1):M_F_CPU0_SB_DQ'<12>:
 C_SIGNAL='@t6g_mb_lib.t6g(sch_1):m_f_cpu0_sb_dq(12)';
NODE_NAME     U25 CM67
 '@T6G_MB_LIB.T6G(SCH_1):PAGE15_I159@PURE_QUANTA.GENOA_SP5(CHIPS)':
 'MFB_DATA12': CDS_PINID='MFB_DATA12';
NODE_NAME     J23 118
 '@T6G_MB_LIB.T6G(SCH_1):PAGE90_I350@PURE_QUANTA.SCONN288_DDR506112002KQ(CHIPS)':
 'DQ12_B': CDS_PINID='DQ12_B';
NET_NAME
'M_F_CPU0_SB_DQ<13>'
 '@T6G_MB_LIB.T6G(SCH_1):M_F_CPU0_SB_DQ'<13>:
 C_SIGNAL='@t6g_mb_lib.t6g(sch_1):m_f_cpu0_sb_dq(13)';
NODE_NAME     U25 CN66
 '@T6G_MB_LIB.T6G(SCH_1):PAGE15_I159@PURE_QUANTA.GENOA_SP5(CHIPS)':
 'MFB_DATA13': CDS_PINID='MFB_DATA13';
NODE_NAME     J23 120
 '@T6G_MB_LIB.T6G(SCH_1):PAGE90_I350@PURE_QUANTA.SCONN288_DDR506112002KQ(CHIPS)':
 'DQ13_B': CDS_PINID='DQ13_B';
NET_NAME
'M_F_CPU0_SB_DQ<14>'
 '@T6G_MB_LIB.T6G(SCH_1):M_F_CPU0_SB_DQ'<14>:
 C_SIGNAL='@t6g_mb_lib.t6g(sch_1):m_f_cpu0_sb_dq(14)';
NODE_NAME     U25 CN67
 '@T6G_MB_LIB.T6G(SCH_1):PAGE15_I159@PURE_QUANTA.GENOA_SP5(CHIPS)':
 'MFB_DATA14': CDS_PINID='MFB_DATA14';
NODE_NAME     J23 263
 '@T6G_MB_LIB.T6G(SCH_1):PAGE90_I350@PURE_QUANTA.SCONN288_DDR506112002KQ(CHIPS)':
 'DQ14_B': CDS_PINID='DQ14_B';
NET_NAME
'M_F_CPU0_SB_DQ<15>'
 '@T6G_MB_LIB.T6G(SCH_1):M_F_CPU0_SB_DQ'<15>:
 C_SIGNAL='@t6g_mb_lib.t6g(sch_1):m_f_cpu0_sb_dq(15)';
NODE_NAME     U25 CP65
 '@T6G_MB_LIB.T6G(SCH_1):PAGE15_I159@PURE_QUANTA.GENOA_SP5(CHIPS)':
 'MFB_DATA15': CDS_PINID='MFB_DATA15';
NODE_NAME     J23 265
 '@T6G_MB_LIB.T6G(SCH_1):PAGE90_I350@PURE_QUANTA.SCONN288_DDR506112002KQ(CHIPS)':
 'DQ15_B': CDS_PINID='DQ15_B';
NET_NAME
'M_F_CPU0_SB_DQ<16>'
 '@T6G_MB_LIB.T6G(SCH_1):M_F_CPU0_SB_DQ'<16>:
 C_SIGNAL='@t6g_mb_lib.t6g(sch_1):m_f_cpu0_sb_dq(16)';
NODE_NAME     U25 CP67
 '@T6G_MB_LIB.T6G(SCH_1):PAGE15_I159@PURE_QUANTA.GENOA_SP5(CHIPS)':
 'MFB_DATA16': CDS_PINID='MFB_DATA16';
NODE_NAME     J23 122
 '@T6G_MB_LIB.T6G(SCH_1):PAGE90_I350@PURE_QUANTA.SCONN288_DDR506112002KQ(CHIPS)':
 'DQ16_B': CDS_PINID='DQ16_B';
NET_NAME
'M_F_CPU0_SB_DQ<17>'
 '@T6G_MB_LIB.T6G(SCH_1):M_F_CPU0_SB_DQ'<17>:
 C_SIGNAL='@t6g_mb_lib.t6g(sch_1):m_f_cpu0_sb_dq(17)';
NODE_NAME     U25 CR66
 '@T6G_MB_LIB.T6G(SCH_1):PAGE15_I159@PURE_QUANTA.GENOA_SP5(CHIPS)':
 'MFB_DATA17': CDS_PINID='MFB_DATA17';
NODE_NAME     J23 124
 '@T6G_MB_LIB.T6G(SCH_1):PAGE90_I350@PURE_QUANTA.SCONN288_DDR506112002KQ(CHIPS)':
 'DQ17_B': CDS_PINID='DQ17_B';
NET_NAME
'M_F_CPU0_SB_DQ<18>'
 '@T6G_MB_LIB.T6G(SCH_1):M_F_CPU0_SB_DQ'<18>:
 C_SIGNAL='@t6g_mb_lib.t6g(sch_1):m_f_cpu0_sb_dq(18)';
NODE_NAME     U25 CR67
 '@T6G_MB_LIB.T6G(SCH_1):PAGE15_I159@PURE_QUANTA.GENOA_SP5(CHIPS)':
 'MFB_DATA18': CDS_PINID='MFB_DATA18';
NODE_NAME     J23 267
 '@T6G_MB_LIB.T6G(SCH_1):PAGE90_I350@PURE_QUANTA.SCONN288_DDR506112002KQ(CHIPS)':
 'DQ18_B': CDS_PINID='DQ18_B';
NET_NAME
'M_F_CPU0_SB_DQ<19>'
 '@T6G_MB_LIB.T6G(SCH_1):M_F_CPU0_SB_DQ'<19>:
 C_SIGNAL='@t6g_mb_lib.t6g(sch_1):m_f_cpu0_sb_dq(19)';
NODE_NAME     U25 CT65
 '@T6G_MB_LIB.T6G(SCH_1):PAGE15_I159@PURE_QUANTA.GENOA_SP5(CHIPS)':
 'MFB_DATA19': CDS_PINID='MFB_DATA19';
NODE_NAME     J23 269
 '@T6G_MB_LIB.T6G(SCH_1):PAGE90_I350@PURE_QUANTA.SCONN288_DDR506112002KQ(CHIPS)':
 'DQ19_B': CDS_PINID='DQ19_B';
NET_NAME
'M_F_CPU0_SB_DQ<1>'
 '@T6G_MB_LIB.T6G(SCH_1):M_F_CPU0_SB_DQ'<1>:
 C_SIGNAL='@t6g_mb_lib.t6g(sch_1):m_f_cpu0_sb_dq(1)';
NODE_NAME     U25 CC66
 '@T6G_MB_LIB.T6G(SCH_1):PAGE15_I159@PURE_QUANTA.GENOA_SP5(CHIPS)':
 'MFB_DATA1': CDS_PINID='MFB_DATA1';
NODE_NAME     J23 102
 '@T6G_MB_LIB.T6G(SCH_1):PAGE90_I350@PURE_QUANTA.SCONN288_DDR506112002KQ(CHIPS)':
 'DQ1_B': CDS_PINID='DQ1_B';
NET_NAME
'M_F_CPU0_SB_DQ<20>'
 '@T6G_MB_LIB.T6G(SCH_1):M_F_CPU0_SB_DQ'<20>:
 C_SIGNAL='@t6g_mb_lib.t6g(sch_1):m_f_cpu0_sb_dq(20)';
NODE_NAME     U25 CV67
 '@T6G_MB_LIB.T6G(SCH_1):PAGE15_I159@PURE_QUANTA.GENOA_SP5(CHIPS)':
 'MFB_DATA20': CDS_PINID='MFB_DATA20';
NODE_NAME     J23 129
 '@T6G_MB_LIB.T6G(SCH_1):PAGE90_I350@PURE_QUANTA.SCONN288_DDR506112002KQ(CHIPS)':
 'DQ20_B': CDS_PINID='DQ20_B';
NET_NAME
'M_F_CPU0_SB_DQ<21>'
 '@T6G_MB_LIB.T6G(SCH_1):M_F_CPU0_SB_DQ'<21>:
 C_SIGNAL='@t6g_mb_lib.t6g(sch_1):m_f_cpu0_sb_dq(21)';
NODE_NAME     U25 CW66
 '@T6G_MB_LIB.T6G(SCH_1):PAGE15_I159@PURE_QUANTA.GENOA_SP5(CHIPS)':
 'MFB_DATA21': CDS_PINID='MFB_DATA21';
NODE_NAME     J23 131
 '@T6G_MB_LIB.T6G(SCH_1):PAGE90_I350@PURE_QUANTA.SCONN288_DDR506112002KQ(CHIPS)':
 'DQ21_B': CDS_PINID='DQ21_B';
NET_NAME
'M_F_CPU0_SB_DQ<22>'
 '@T6G_MB_LIB.T6G(SCH_1):M_F_CPU0_SB_DQ'<22>:
 C_SIGNAL='@t6g_mb_lib.t6g(sch_1):m_f_cpu0_sb_dq(22)';
NODE_NAME     U25 CW67
 '@T6G_MB_LIB.T6G(SCH_1):PAGE15_I159@PURE_QUANTA.GENOA_SP5(CHIPS)':
 'MFB_DATA22': CDS_PINID='MFB_DATA22';
NODE_NAME     J23 274
 '@T6G_MB_LIB.T6G(SCH_1):PAGE90_I350@PURE_QUANTA.SCONN288_DDR506112002KQ(CHIPS)':
 'DQ22_B': CDS_PINID='DQ22_B';
NET_NAME
'M_F_CPU0_SB_DQ<23>'
 '@T6G_MB_LIB.T6G(SCH_1):M_F_CPU0_SB_DQ'<23>:
 C_SIGNAL='@t6g_mb_lib.t6g(sch_1):m_f_cpu0_sb_dq(23)';
NODE_NAME     U25 CY65
 '@T6G_MB_LIB.T6G(SCH_1):PAGE15_I159@PURE_QUANTA.GENOA_SP5(CHIPS)':
 'MFB_DATA23': CDS_PINID='MFB_DATA23';
NODE_NAME     J23 276
 '@T6G_MB_LIB.T6G(SCH_1):PAGE90_I350@PURE_QUANTA.SCONN288_DDR506112002KQ(CHIPS)':
 'DQ23_B': CDS_PINID='DQ23_B';
NET_NAME
'M_F_CPU0_SB_DQ<24>'
 '@T6G_MB_LIB.T6G(SCH_1):M_F_CPU0_SB_DQ'<24>:
 C_SIGNAL='@t6g_mb_lib.t6g(sch_1):m_f_cpu0_sb_dq(24)';
NODE_NAME     U25 CY67
 '@T6G_MB_LIB.T6G(SCH_1):PAGE15_I159@PURE_QUANTA.GENOA_SP5(CHIPS)':
 'MFB_DATA24': CDS_PINID='MFB_DATA24';
NODE_NAME     J23 133
 '@T6G_MB_LIB.T6G(SCH_1):PAGE90_I350@PURE_QUANTA.SCONN288_DDR506112002KQ(CHIPS)':
 'DQ24_B': CDS_PINID='DQ24_B';
NET_NAME
'M_F_CPU0_SB_DQ<25>'
 '@T6G_MB_LIB.T6G(SCH_1):M_F_CPU0_SB_DQ'<25>:
 C_SIGNAL='@t6g_mb_lib.t6g(sch_1):m_f_cpu0_sb_dq(25)';
NODE_NAME     U25 DA66
 '@T6G_MB_LIB.T6G(SCH_1):PAGE15_I159@PURE_QUANTA.GENOA_SP5(CHIPS)':
 'MFB_DATA25': CDS_PINID='MFB_DATA25';
NODE_NAME     J23 135
 '@T6G_MB_LIB.T6G(SCH_1):PAGE90_I350@PURE_QUANTA.SCONN288_DDR506112002KQ(CHIPS)':
 'DQ25_B': CDS_PINID='DQ25_B';
NET_NAME
'M_F_CPU0_SB_DQ<26>'
 '@T6G_MB_LIB.T6G(SCH_1):M_F_CPU0_SB_DQ'<26>:
 C_SIGNAL='@t6g_mb_lib.t6g(sch_1):m_f_cpu0_sb_dq(26)';
NODE_NAME     U25 DA67
 '@T6G_MB_LIB.T6G(SCH_1):PAGE15_I159@PURE_QUANTA.GENOA_SP5(CHIPS)':
 'MFB_DATA26': CDS_PINID='MFB_DATA26';
NODE_NAME     J23 278
 '@T6G_MB_LIB.T6G(SCH_1):PAGE90_I350@PURE_QUANTA.SCONN288_DDR506112002KQ(CHIPS)':
 'DQ26_B': CDS_PINID='DQ26_B';
NET_NAME
'M_F_CPU0_SB_DQ<27>'
 '@T6G_MB_LIB.T6G(SCH_1):M_F_CPU0_SB_DQ'<27>:
 C_SIGNAL='@t6g_mb_lib.t6g(sch_1):m_f_cpu0_sb_dq(27)';
NODE_NAME     U25 DB65
 '@T6G_MB_LIB.T6G(SCH_1):PAGE15_I159@PURE_QUANTA.GENOA_SP5(CHIPS)':
 'MFB_DATA27': CDS_PINID='MFB_DATA27';
NODE_NAME     J23 280
 '@T6G_MB_LIB.T6G(SCH_1):PAGE90_I350@PURE_QUANTA.SCONN288_DDR506112002KQ(CHIPS)':
 'DQ27_B': CDS_PINID='DQ27_B';
NET_NAME
'M_F_CPU0_SB_DQ<28>'
 '@T6G_MB_LIB.T6G(SCH_1):M_F_CPU0_SB_DQ'<28>:
 C_SIGNAL='@t6g_mb_lib.t6g(sch_1):m_f_cpu0_sb_dq(28)';
NODE_NAME     U25 DD67
 '@T6G_MB_LIB.T6G(SCH_1):PAGE15_I159@PURE_QUANTA.GENOA_SP5(CHIPS)':
 'MFB_DATA28': CDS_PINID='MFB_DATA28';
NODE_NAME     J23 140
 '@T6G_MB_LIB.T6G(SCH_1):PAGE90_I350@PURE_QUANTA.SCONN288_DDR506112002KQ(CHIPS)':
 'DQ28_B': CDS_PINID='DQ28_B';
NET_NAME
'M_F_CPU0_SB_DQ<29>'
 '@T6G_MB_LIB.T6G(SCH_1):M_F_CPU0_SB_DQ'<29>:
 C_SIGNAL='@t6g_mb_lib.t6g(sch_1):m_f_cpu0_sb_dq(29)';
NODE_NAME     U25 DE66
 '@T6G_MB_LIB.T6G(SCH_1):PAGE15_I159@PURE_QUANTA.GENOA_SP5(CHIPS)':
 'MFB_DATA29': CDS_PINID='MFB_DATA29';
NODE_NAME     J23 142
 '@T6G_MB_LIB.T6G(SCH_1):PAGE90_I350@PURE_QUANTA.SCONN288_DDR506112002KQ(CHIPS)':
 'DQ29_B': CDS_PINID='DQ29_B';
NET_NAME
'M_F_CPU0_SB_DQ<2>'
 '@T6G_MB_LIB.T6G(SCH_1):M_F_CPU0_SB_DQ'<2>:
 C_SIGNAL='@t6g_mb_lib.t6g(sch_1):m_f_cpu0_sb_dq(2)';
NODE_NAME     U25 CC67
 '@T6G_MB_LIB.T6G(SCH_1):PAGE15_I159@PURE_QUANTA.GENOA_SP5(CHIPS)':
 'MFB_DATA2': CDS_PINID='MFB_DATA2';
NODE_NAME     J23 245
 '@T6G_MB_LIB.T6G(SCH_1):PAGE90_I350@PURE_QUANTA.SCONN288_DDR506112002KQ(CHIPS)':
 'DQ2_B': CDS_PINID='DQ2_B';
NET_NAME
'M_F_CPU0_SB_DQ<30>'
 '@T6G_MB_LIB.T6G(SCH_1):M_F_CPU0_SB_DQ'<30>:
 C_SIGNAL='@t6g_mb_lib.t6g(sch_1):m_f_cpu0_sb_dq(30)';
NODE_NAME     U25 DE67
 '@T6G_MB_LIB.T6G(SCH_1):PAGE15_I159@PURE_QUANTA.GENOA_SP5(CHIPS)':
 'MFB_DATA30': CDS_PINID='MFB_DATA30';
NODE_NAME     J23 285
 '@T6G_MB_LIB.T6G(SCH_1):PAGE90_I350@PURE_QUANTA.SCONN288_DDR506112002KQ(CHIPS)':
 'DQ30_B': CDS_PINID='DQ30_B';
NET_NAME
'M_F_CPU0_SB_DQ<31>'
 '@T6G_MB_LIB.T6G(SCH_1):M_F_CPU0_SB_DQ'<31>:
 C_SIGNAL='@t6g_mb_lib.t6g(sch_1):m_f_cpu0_sb_dq(31)';
NODE_NAME     U25 DF67
 '@T6G_MB_LIB.T6G(SCH_1):PAGE15_I159@PURE_QUANTA.GENOA_SP5(CHIPS)':
 'MFB_DATA31': CDS_PINID='MFB_DATA31';
NODE_NAME     J23 287
 '@T6G_MB_LIB.T6G(SCH_1):PAGE90_I350@PURE_QUANTA.SCONN288_DDR506112002KQ(CHIPS)':
 'DQ31_B': CDS_PINID='DQ31_B';
NET_NAME
'M_F_CPU0_SB_DQ<3>'
 '@T6G_MB_LIB.T6G(SCH_1):M_F_CPU0_SB_DQ'<3>:
 C_SIGNAL='@t6g_mb_lib.t6g(sch_1):m_f_cpu0_sb_dq(3)';
NODE_NAME     U25 CD65
 '@T6G_MB_LIB.T6G(SCH_1):PAGE15_I159@PURE_QUANTA.GENOA_SP5(CHIPS)':
 'MFB_DATA3': CDS_PINID='MFB_DATA3';
NODE_NAME     J23 247
 '@T6G_MB_LIB.T6G(SCH_1):PAGE90_I350@PURE_QUANTA.SCONN288_DDR506112002KQ(CHIPS)':
 'DQ3_B': CDS_PINID='DQ3_B';
NET_NAME
'M_F_CPU0_SB_DQ<4>'
 '@T6G_MB_LIB.T6G(SCH_1):M_F_CPU0_SB_DQ'<4>:
 C_SIGNAL='@t6g_mb_lib.t6g(sch_1):m_f_cpu0_sb_dq(4)';
NODE_NAME     U25 CF67
 '@T6G_MB_LIB.T6G(SCH_1):PAGE15_I159@PURE_QUANTA.GENOA_SP5(CHIPS)':
 'MFB_DATA4': CDS_PINID='MFB_DATA4';
NODE_NAME     J23 107
 '@T6G_MB_LIB.T6G(SCH_1):PAGE90_I350@PURE_QUANTA.SCONN288_DDR506112002KQ(CHIPS)':
 'DQ4_B': CDS_PINID='DQ4_B';
NET_NAME
'M_F_CPU0_SB_DQ<5>'
 '@T6G_MB_LIB.T6G(SCH_1):M_F_CPU0_SB_DQ'<5>:
 C_SIGNAL='@t6g_mb_lib.t6g(sch_1):m_f_cpu0_sb_dq(5)';
NODE_NAME     U25 CG66
 '@T6G_MB_LIB.T6G(SCH_1):PAGE15_I159@PURE_QUANTA.GENOA_SP5(CHIPS)':
 'MFB_DATA5': CDS_PINID='MFB_DATA5';
NODE_NAME     J23 109
 '@T6G_MB_LIB.T6G(SCH_1):PAGE90_I350@PURE_QUANTA.SCONN288_DDR506112002KQ(CHIPS)':
 'DQ5_B': CDS_PINID='DQ5_B';
NET_NAME
'M_F_CPU0_SB_DQ<6>'
 '@T6G_MB_LIB.T6G(SCH_1):M_F_CPU0_SB_DQ'<6>:
 C_SIGNAL='@t6g_mb_lib.t6g(sch_1):m_f_cpu0_sb_dq(6)';
NODE_NAME     U25 CG67
 '@T6G_MB_LIB.T6G(SCH_1):PAGE15_I159@PURE_QUANTA.GENOA_SP5(CHIPS)':
 'MFB_DATA6': CDS_PINID='MFB_DATA6';
NODE_NAME     J23 252
 '@T6G_MB_LIB.T6G(SCH_1):PAGE90_I350@PURE_QUANTA.SCONN288_DDR506112002KQ(CHIPS)':
 'DQ6_B': CDS_PINID='DQ6_B';
NET_NAME
'M_F_CPU0_SB_DQ<7>'
 '@T6G_MB_LIB.T6G(SCH_1):M_F_CPU0_SB_DQ'<7>:
 C_SIGNAL='@t6g_mb_lib.t6g(sch_1):m_f_cpu0_sb_dq(7)';
NODE_NAME     U25 CH65
 '@T6G_MB_LIB.T6G(SCH_1):PAGE15_I159@PURE_QUANTA.GENOA_SP5(CHIPS)':
 'MFB_DATA7': CDS_PINID='MFB_DATA7';
NODE_NAME     J23 254
 '@T6G_MB_LIB.T6G(SCH_1):PAGE90_I350@PURE_QUANTA.SCONN288_DDR506112002KQ(CHIPS)':
 'DQ7_B': CDS_PINID='DQ7_B';
NET_NAME
'M_F_CPU0_SB_DQ<8>'
 '@T6G_MB_LIB.T6G(SCH_1):M_F_CPU0_SB_DQ'<8>:
 C_SIGNAL='@t6g_mb_lib.t6g(sch_1):m_f_cpu0_sb_dq(8)';
NODE_NAME     U25 CH67
 '@T6G_MB_LIB.T6G(SCH_1):PAGE15_I159@PURE_QUANTA.GENOA_SP5(CHIPS)':
 'MFB_DATA8': CDS_PINID='MFB_DATA8';
NODE_NAME     J23 111
 '@T6G_MB_LIB.T6G(SCH_1):PAGE90_I350@PURE_QUANTA.SCONN288_DDR506112002KQ(CHIPS)':
 'DQ8_B': CDS_PINID='DQ8_B';
NET_NAME
'M_F_CPU0_SB_DQ<9>'
 '@T6G_MB_LIB.T6G(SCH_1):M_F_CPU0_SB_DQ'<9>:
 C_SIGNAL='@t6g_mb_lib.t6g(sch_1):m_f_cpu0_sb_dq(9)';
NODE_NAME     U25 CJ66
 '@T6G_MB_LIB.T6G(SCH_1):PAGE15_I159@PURE_QUANTA.GENOA_SP5(CHIPS)':
 'MFB_DATA9': CDS_PINID='MFB_DATA9';
NODE_NAME     J23 113
 '@T6G_MB_LIB.T6G(SCH_1):PAGE90_I350@PURE_QUANTA.SCONN288_DDR506112002KQ(CHIPS)':
 'DQ9_B': CDS_PINID='DQ9_B';
NET_NAME
'M_F_CPU0_SB_DQS_DN<0>'
 '@T6G_MB_LIB.T6G(SCH_1):M_F_CPU0_SB_DQS_DN'<0>:
 C_SIGNAL='@t6g_mb_lib.t6g(sch_1):m_f_cpu0_sb_dqs_dn(0)';
NODE_NAME     U25 CE67
 '@T6G_MB_LIB.T6G(SCH_1):PAGE15_I159@PURE_QUANTA.GENOA_SP5(CHIPS)':
 'MFB_DQS_L0': CDS_PINID='MFB_DQS_L0';
NODE_NAME     J23 105
 '@T6G_MB_LIB.T6G(SCH_1):PAGE90_I412@PURE_QUANTA.SCONN288_DDR506112002KQ(CHIPS)':
 'DQS0_B_C': CDS_PINID='DQS0_B_C';
NET_NAME
'M_F_CPU0_SB_DQS_DN<1>'
 '@T6G_MB_LIB.T6G(SCH_1):M_F_CPU0_SB_DQS_DN'<1>:
 C_SIGNAL='@t6g_mb_lib.t6g(sch_1):m_f_cpu0_sb_dqs_dn(1)';
NODE_NAME     U25 CL67
 '@T6G_MB_LIB.T6G(SCH_1):PAGE15_I159@PURE_QUANTA.GENOA_SP5(CHIPS)':
 'MFB_DQS_L1': CDS_PINID='MFB_DQS_L1';
NODE_NAME     J23 116
 '@T6G_MB_LIB.T6G(SCH_1):PAGE90_I412@PURE_QUANTA.SCONN288_DDR506112002KQ(CHIPS)':
 'DQS1_B_C': CDS_PINID='DQS1_B_C';
NET_NAME
'M_F_CPU0_SB_DQS_DN<2>'
 '@T6G_MB_LIB.T6G(SCH_1):M_F_CPU0_SB_DQS_DN'<2>:
 C_SIGNAL='@t6g_mb_lib.t6g(sch_1):m_f_cpu0_sb_dqs_dn(2)';
NODE_NAME     U25 CU67
 '@T6G_MB_LIB.T6G(SCH_1):PAGE15_I159@PURE_QUANTA.GENOA_SP5(CHIPS)':
 'MFB_DQS_L2': CDS_PINID='MFB_DQS_L2';
NODE_NAME     J23 127
 '@T6G_MB_LIB.T6G(SCH_1):PAGE90_I412@PURE_QUANTA.SCONN288_DDR506112002KQ(CHIPS)':
 'DQS2_B_C': CDS_PINID='DQS2_B_C';
NET_NAME
'M_F_CPU0_SB_DQS_DN<3>'
 '@T6G_MB_LIB.T6G(SCH_1):M_F_CPU0_SB_DQS_DN'<3>:
 C_SIGNAL='@t6g_mb_lib.t6g(sch_1):m_f_cpu0_sb_dqs_dn(3)';
NODE_NAME     U25 DC67
 '@T6G_MB_LIB.T6G(SCH_1):PAGE15_I159@PURE_QUANTA.GENOA_SP5(CHIPS)':
 'MFB_DQS_L3': CDS_PINID='MFB_DQS_L3';
NODE_NAME     J23 138
 '@T6G_MB_LIB.T6G(SCH_1):PAGE90_I412@PURE_QUANTA.SCONN288_DDR506112002KQ(CHIPS)':
 'DQS3_B_C': CDS_PINID='DQS3_B_C';
NET_NAME
'M_F_CPU0_SB_DQS_DN<4>'
 '@T6G_MB_LIB.T6G(SCH_1):M_F_CPU0_SB_DQS_DN'<4>:
 C_SIGNAL='@t6g_mb_lib.t6g(sch_1):m_f_cpu0_sb_dqs_dn(4)';
NODE_NAME     U25 BW66
 '@T6G_MB_LIB.T6G(SCH_1):PAGE15_I159@PURE_QUANTA.GENOA_SP5(CHIPS)':
 'MFB_DQS_L4': CDS_PINID='MFB_DQS_L4';
NODE_NAME     J23 238
 '@T6G_MB_LIB.T6G(SCH_1):PAGE90_I412@PURE_QUANTA.SCONN288_DDR506112002KQ(CHIPS)':
 'DQS4_B_C': CDS_PINID='DQS4_B_C';
NET_NAME
'M_F_CPU0_SB_DQS_DN<5>'
 '@T6G_MB_LIB.T6G(SCH_1):M_F_CPU0_SB_DQS_DN'<5>:
 C_SIGNAL='@t6g_mb_lib.t6g(sch_1):m_f_cpu0_sb_dqs_dn(5)';
NODE_NAME     U25 CE66
 '@T6G_MB_LIB.T6G(SCH_1):PAGE15_I159@PURE_QUANTA.GENOA_SP5(CHIPS)':
 'MFB_DQS_L5': CDS_PINID='MFB_DQS_L5';
NODE_NAME     J23 249
 '@T6G_MB_LIB.T6G(SCH_1):PAGE90_I412@PURE_QUANTA.SCONN288_DDR506112002KQ(CHIPS)':
 'DQS5_B_C||TDQS5_B_C': CDS_PINID='\dqs5_b_c||tdqs5_b_c\';
NET_NAME
'M_F_CPU0_SB_DQS_DN<6>'
 '@T6G_MB_LIB.T6G(SCH_1):M_F_CPU0_SB_DQS_DN'<6>:
 C_SIGNAL='@t6g_mb_lib.t6g(sch_1):m_f_cpu0_sb_dqs_dn(6)';
NODE_NAME     U25 CL66
 '@T6G_MB_LIB.T6G(SCH_1):PAGE15_I159@PURE_QUANTA.GENOA_SP5(CHIPS)':
 'MFB_DQS_L6': CDS_PINID='MFB_DQS_L6';
NODE_NAME     J23 260
 '@T6G_MB_LIB.T6G(SCH_1):PAGE90_I412@PURE_QUANTA.SCONN288_DDR506112002KQ(CHIPS)':
 'DQS6_B_C||TDQS6_B_C': CDS_PINID='\dqs6_b_c||tdqs6_b_c\';
NET_NAME
'M_F_CPU0_SB_DQS_DN<7>'
 '@T6G_MB_LIB.T6G(SCH_1):M_F_CPU0_SB_DQS_DN'<7>:
 C_SIGNAL='@t6g_mb_lib.t6g(sch_1):m_f_cpu0_sb_dqs_dn(7)';
NODE_NAME     U25 CU66
 '@T6G_MB_LIB.T6G(SCH_1):PAGE15_I159@PURE_QUANTA.GENOA_SP5(CHIPS)':
 'MFB_DQS_L7': CDS_PINID='MFB_DQS_L7';
NODE_NAME     J23 271
 '@T6G_MB_LIB.T6G(SCH_1):PAGE90_I412@PURE_QUANTA.SCONN288_DDR506112002KQ(CHIPS)':
 'DQS7_B_C||TDQS7_B_C': CDS_PINID='\dqs7_b_c||tdqs7_b_c\';
NET_NAME
'M_F_CPU0_SB_DQS_DN<8>'
 '@T6G_MB_LIB.T6G(SCH_1):M_F_CPU0_SB_DQS_DN'<8>:
 C_SIGNAL='@t6g_mb_lib.t6g(sch_1):m_f_cpu0_sb_dqs_dn(8)';
NODE_NAME     U25 DC66
 '@T6G_MB_LIB.T6G(SCH_1):PAGE15_I159@PURE_QUANTA.GENOA_SP5(CHIPS)':
 'MFB_DQS_L8': CDS_PINID='MFB_DQS_L8';
NODE_NAME     J23 282
 '@T6G_MB_LIB.T6G(SCH_1):PAGE90_I412@PURE_QUANTA.SCONN288_DDR506112002KQ(CHIPS)':
 'DQS8_B_C||TDQS8_B_C': CDS_PINID='\dqs8_b_c||tdqs8_b_c\';
NET_NAME
'M_F_CPU0_SB_DQS_DN<9>'
 '@T6G_MB_LIB.T6G(SCH_1):M_F_CPU0_SB_DQS_DN'<9>:
 C_SIGNAL='@t6g_mb_lib.t6g(sch_1):m_f_cpu0_sb_dqs_dn(9)';
NODE_NAME     U25 BW67
 '@T6G_MB_LIB.T6G(SCH_1):PAGE15_I159@PURE_QUANTA.GENOA_SP5(CHIPS)':
 'MFB_DQS_L9': CDS_PINID='MFB_DQS_L9';
NODE_NAME     J23 94
 '@T6G_MB_LIB.T6G(SCH_1):PAGE90_I412@PURE_QUANTA.SCONN288_DDR506112002KQ(CHIPS)':
 'DQS9_B_C||TDQS9_B_C': CDS_PINID='\dqs9_b_c||tdqs9_b_c\';
NET_NAME
'M_F_CPU0_SB_DQS_DP<0>'
 '@T6G_MB_LIB.T6G(SCH_1):M_F_CPU0_SB_DQS_DP'<0>:
 C_SIGNAL='@t6g_mb_lib.t6g(sch_1):m_f_cpu0_sb_dqs_dp(0)';
NODE_NAME     U25 CD67
 '@T6G_MB_LIB.T6G(SCH_1):PAGE15_I159@PURE_QUANTA.GENOA_SP5(CHIPS)':
 'MFB_DQS_H0': CDS_PINID='MFB_DQS_H0';
NODE_NAME     J23 104
 '@T6G_MB_LIB.T6G(SCH_1):PAGE90_I412@PURE_QUANTA.SCONN288_DDR506112002KQ(CHIPS)':
 'DQS0_B_T': CDS_PINID='DQS0_B_T';
NET_NAME
'M_F_CPU0_SB_DQS_DP<1>'
 '@T6G_MB_LIB.T6G(SCH_1):M_F_CPU0_SB_DQS_DP'<1>:
 C_SIGNAL='@t6g_mb_lib.t6g(sch_1):m_f_cpu0_sb_dqs_dp(1)';
NODE_NAME     U25 CK67
 '@T6G_MB_LIB.T6G(SCH_1):PAGE15_I159@PURE_QUANTA.GENOA_SP5(CHIPS)':
 'MFB_DQS_H1': CDS_PINID='MFB_DQS_H1';
NODE_NAME     J23 115
 '@T6G_MB_LIB.T6G(SCH_1):PAGE90_I412@PURE_QUANTA.SCONN288_DDR506112002KQ(CHIPS)':
 'DQS1_B_T': CDS_PINID='DQS1_B_T';
NET_NAME
'M_F_CPU0_SB_DQS_DP<2>'
 '@T6G_MB_LIB.T6G(SCH_1):M_F_CPU0_SB_DQS_DP'<2>:
 C_SIGNAL='@t6g_mb_lib.t6g(sch_1):m_f_cpu0_sb_dqs_dp(2)';
NODE_NAME     U25 CT67
 '@T6G_MB_LIB.T6G(SCH_1):PAGE15_I159@PURE_QUANTA.GENOA_SP5(CHIPS)':
 'MFB_DQS_H2': CDS_PINID='MFB_DQS_H2';
NODE_NAME     J23 126
 '@T6G_MB_LIB.T6G(SCH_1):PAGE90_I412@PURE_QUANTA.SCONN288_DDR506112002KQ(CHIPS)':
 'DQS2_B_T': CDS_PINID='DQS2_B_T';
NET_NAME
'M_F_CPU0_SB_DQS_DP<3>'
 '@T6G_MB_LIB.T6G(SCH_1):M_F_CPU0_SB_DQS_DP'<3>:
 C_SIGNAL='@t6g_mb_lib.t6g(sch_1):m_f_cpu0_sb_dqs_dp(3)';
NODE_NAME     U25 DB67
 '@T6G_MB_LIB.T6G(SCH_1):PAGE15_I159@PURE_QUANTA.GENOA_SP5(CHIPS)':
 'MFB_DQS_H3': CDS_PINID='MFB_DQS_H3';
NODE_NAME     J23 137
 '@T6G_MB_LIB.T6G(SCH_1):PAGE90_I412@PURE_QUANTA.SCONN288_DDR506112002KQ(CHIPS)':
 'DQS3_B_T': CDS_PINID='DQS3_B_T';
NET_NAME
'M_F_CPU0_SB_DQS_DP<4>'
 '@T6G_MB_LIB.T6G(SCH_1):M_F_CPU0_SB_DQS_DP'<4>:
 C_SIGNAL='@t6g_mb_lib.t6g(sch_1):m_f_cpu0_sb_dqs_dp(4)';
NODE_NAME     U25 BY65
 '@T6G_MB_LIB.T6G(SCH_1):PAGE15_I159@PURE_QUANTA.GENOA_SP5(CHIPS)':
 'MFB_DQS_H4': CDS_PINID='MFB_DQS_H4';
NODE_NAME     J23 239
 '@T6G_MB_LIB.T6G(SCH_1):PAGE90_I412@PURE_QUANTA.SCONN288_DDR506112002KQ(CHIPS)':
 'DQS4_B_T': CDS_PINID='DQS4_B_T';
NET_NAME
'M_F_CPU0_SB_DQS_DP<5>'
 '@T6G_MB_LIB.T6G(SCH_1):M_F_CPU0_SB_DQS_DP'<5>:
 C_SIGNAL='@t6g_mb_lib.t6g(sch_1):m_f_cpu0_sb_dqs_dp(5)';
NODE_NAME     U25 CF65
 '@T6G_MB_LIB.T6G(SCH_1):PAGE15_I159@PURE_QUANTA.GENOA_SP5(CHIPS)':
 'MFB_DQS_H5': CDS_PINID='MFB_DQS_H5';
NODE_NAME     J23 250
 '@T6G_MB_LIB.T6G(SCH_1):PAGE90_I412@PURE_QUANTA.SCONN288_DDR506112002KQ(CHIPS)':
 'DQS5_B_T||TDQS5_B_T': CDS_PINID='\dqs5_b_t||tdqs5_b_t\';
NET_NAME
'M_F_CPU0_SB_DQS_DP<6>'
 '@T6G_MB_LIB.T6G(SCH_1):M_F_CPU0_SB_DQS_DP'<6>:
 C_SIGNAL='@t6g_mb_lib.t6g(sch_1):m_f_cpu0_sb_dqs_dp(6)';
NODE_NAME     U25 CM65
 '@T6G_MB_LIB.T6G(SCH_1):PAGE15_I159@PURE_QUANTA.GENOA_SP5(CHIPS)':
 'MFB_DQS_H6': CDS_PINID='MFB_DQS_H6';
NODE_NAME     J23 261
 '@T6G_MB_LIB.T6G(SCH_1):PAGE90_I412@PURE_QUANTA.SCONN288_DDR506112002KQ(CHIPS)':
 'DQS6_B_T||TDQS6_B_T': CDS_PINID='\dqs6_b_t||tdqs6_b_t\';
NET_NAME
'M_F_CPU0_SB_DQS_DP<7>'
 '@T6G_MB_LIB.T6G(SCH_1):M_F_CPU0_SB_DQS_DP'<7>:
 C_SIGNAL='@t6g_mb_lib.t6g(sch_1):m_f_cpu0_sb_dqs_dp(7)';
NODE_NAME     U25 CV65
 '@T6G_MB_LIB.T6G(SCH_1):PAGE15_I159@PURE_QUANTA.GENOA_SP5(CHIPS)':
 'MFB_DQS_H7': CDS_PINID='MFB_DQS_H7';
NODE_NAME     J23 272
 '@T6G_MB_LIB.T6G(SCH_1):PAGE90_I412@PURE_QUANTA.SCONN288_DDR506112002KQ(CHIPS)':
 'DQS7_B_T||TDQS7_B_T': CDS_PINID='\dqs7_b_t||tdqs7_b_t\';
NET_NAME
'M_F_CPU0_SB_DQS_DP<8>'
 '@T6G_MB_LIB.T6G(SCH_1):M_F_CPU0_SB_DQS_DP'<8>:
 C_SIGNAL='@t6g_mb_lib.t6g(sch_1):m_f_cpu0_sb_dqs_dp(8)';
NODE_NAME     U25 DD65
 '@T6G_MB_LIB.T6G(SCH_1):PAGE15_I159@PURE_QUANTA.GENOA_SP5(CHIPS)':
 'MFB_DQS_H8': CDS_PINID='MFB_DQS_H8';
NODE_NAME     J23 283
 '@T6G_MB_LIB.T6G(SCH_1):PAGE90_I412@PURE_QUANTA.SCONN288_DDR506112002KQ(CHIPS)':
 'DQS8_B_T||TDQS8_B_T': CDS_PINID='\dqs8_b_t||tdqs8_b_t\';
NET_NAME
'M_F_CPU0_SB_DQS_DP<9>'
 '@T6G_MB_LIB.T6G(SCH_1):M_F_CPU0_SB_DQS_DP'<9>:
 C_SIGNAL='@t6g_mb_lib.t6g(sch_1):m_f_cpu0_sb_dqs_dp(9)';
NODE_NAME     U25 BV67
 '@T6G_MB_LIB.T6G(SCH_1):PAGE15_I159@PURE_QUANTA.GENOA_SP5(CHIPS)':
 'MFB_DQS_H9': CDS_PINID='MFB_DQS_H9';
NODE_NAME     J23 93
 '@T6G_MB_LIB.T6G(SCH_1):PAGE90_I412@PURE_QUANTA.SCONN288_DDR506112002KQ(CHIPS)':
 'DQS9_B_T||TDQS9_B_T||DBI4_B_N': CDS_PINID='\dqs9_b_t||tdqs9_b_t||dbi4_b_n\';
NET_NAME
'M_F_CPU0_SB_PAR'
 '@T6G_MB_LIB.T6G(SCH_1):M_F_CPU0_SB_PAR':
 C_SIGNAL='@t6g_mb_lib.t6g(sch_1):m_f_cpu0_sb_par';
NODE_NAME     U25 BL67
 '@T6G_MB_LIB.T6G(SCH_1):PAGE15_I159@PURE_QUANTA.GENOA_SP5(CHIPS)':
 'MFB_PAR': CDS_PINID='MFB_PAR';
NODE_NAME     J23 227
 '@T6G_MB_LIB.T6G(SCH_1):PAGE90_I350@PURE_QUANTA.SCONN288_DDR506112002KQ(CHIPS)':
 'PAR_B': CDS_PINID='PAR_B';
NET_NAME
'M_F_CPU0_SB_RSP<0>'
 '@T6G_MB_LIB.T6G(SCH_1):M_F_CPU0_SB_RSP'<0>:
 C_SIGNAL='@t6g_mb_lib.t6g(sch_1):m_f_cpu0_sb_rsp(0)';
NODE_NAME     U25 BP67
 '@T6G_MB_LIB.T6G(SCH_1):PAGE15_I159@PURE_QUANTA.GENOA_SP5(CHIPS)':
 'MFB0_RSP_L': CDS_PINID='MFB0_RSP_L';
NODE_NAME     J23 87
 '@T6G_MB_LIB.T6G(SCH_1):PAGE90_I350@PURE_QUANTA.SCONN288_DDR506112002KQ(CHIPS)':
 'LBS||RSP_B_N': CDS_PINID='\lbs||rsp_b_n\';
NET_NAME
'M_F_CPU1_ALERT_N'
 '@T6G_MB_LIB.T6G(SCH_1):M_F_CPU1_ALERT_N':
 C_SIGNAL='@t6g_mb_lib.t6g(sch_1):m_f_cpu1_alert_n';
NODE_NAME     R505 1
 '@T6G_MB_LIB.T6G(SCH_1):PAGE42_I314@PURE_QUANTA.Q_RES(CHIPS)':
 'A': CDS_PINID='A';
NODE_NAME     J33 62
 '@T6G_MB_LIB.T6G(SCH_1):PAGE102_I22@PURE_QUANTA.SCONN288_DDR506112002KQ(CHIPS)':
 'ALERT_N': CDS_PINID='ALERT_N';
NET_NAME
'M_F_CPU1_ALERT_R_N'
 '@T6G_MB_LIB.T6G(SCH_1):M_F_CPU1_ALERT_R_N':
 C_SIGNAL='@t6g_mb_lib.t6g(sch_1):m_f_cpu1_alert_r_n';
NODE_NAME     U26 AT65
 '@T6G_MB_LIB.T6G(SCH_1):PAGE42_I159@PURE_QUANTA.GENOA_SP5(CHIPS)':
 'MF_ALERT_L': CDS_PINID='MF_ALERT_L';
NODE_NAME     R505 2
 '@T6G_MB_LIB.T6G(SCH_1):PAGE42_I314@PURE_QUANTA.Q_RES(CHIPS)':
 'B': CDS_PINID='B';
NET_NAME
'M_F_CPU1_CLK_DN<0>'
 '@T6G_MB_LIB.T6G(SCH_1):M_F_CPU1_CLK_DN'<0>:
 C_SIGNAL='@t6g_mb_lib.t6g(sch_1):m_f_cpu1_clk_dn(0)';
NODE_NAME     U26 BD67
 '@T6G_MB_LIB.T6G(SCH_1):PAGE42_I159@PURE_QUANTA.GENOA_SP5(CHIPS)':
 'MF0_CLK_L': CDS_PINID='MF0_CLK_L';
NODE_NAME     J33 218
 '@T6G_MB_LIB.T6G(SCH_1):PAGE102_I22@PURE_QUANTA.SCONN288_DDR506112002KQ(CHIPS)':
 'CK_C': CDS_PINID='CK_C';
NET_NAME
'M_F_CPU1_CLK_DP<0>'
 '@T6G_MB_LIB.T6G(SCH_1):M_F_CPU1_CLK_DP'<0>:
 C_SIGNAL='@t6g_mb_lib.t6g(sch_1):m_f_cpu1_clk_dp(0)';
NODE_NAME     U26 BC67
 '@T6G_MB_LIB.T6G(SCH_1):PAGE42_I159@PURE_QUANTA.GENOA_SP5(CHIPS)':
 'MF0_CLK_H': CDS_PINID='MF0_CLK_H';
NODE_NAME     J33 217
 '@T6G_MB_LIB.T6G(SCH_1):PAGE102_I22@PURE_QUANTA.SCONN288_DDR506112002KQ(CHIPS)':
 'CK_T': CDS_PINID='CK_T';
NET_NAME
'M_F_CPU1_RESET_N'
 '@T6G_MB_LIB.T6G(SCH_1):M_F_CPU1_RESET_N':
 C_SIGNAL='@t6g_mb_lib.t6g(sch_1):m_f_cpu1_reset_n';
NODE_NAME     U26 AU66
 '@T6G_MB_LIB.T6G(SCH_1):PAGE42_I159@PURE_QUANTA.GENOA_SP5(CHIPS)':
 'MF_RESET_L': CDS_PINID='MF_RESET_L';
NODE_NAME     J33 207
 '@T6G_MB_LIB.T6G(SCH_1):PAGE102_I22@PURE_QUANTA.SCONN288_DDR506112002KQ(CHIPS)':
 'RESET_N': CDS_PINID='RESET_N';
NET_NAME
'M_F_CPU1_SA_CA<0>'
 '@T6G_MB_LIB.T6G(SCH_1):M_F_CPU1_SA_CA'<0>:
 C_SIGNAL='@t6g_mb_lib.t6g(sch_1):m_f_cpu1_sa_ca(0)';
NODE_NAME     U26 AW67
 '@T6G_MB_LIB.T6G(SCH_1):PAGE42_I159@PURE_QUANTA.GENOA_SP5(CHIPS)':
 'MFA_CA0': CDS_PINID='MFA_CA0';
NODE_NAME     J33 66
 '@T6G_MB_LIB.T6G(SCH_1):PAGE102_I22@PURE_QUANTA.SCONN288_DDR506112002KQ(CHIPS)':
 'CA0_A': CDS_PINID='CA0_A';
NET_NAME
'M_F_CPU1_SA_CA<1>'
 '@T6G_MB_LIB.T6G(SCH_1):M_F_CPU1_SA_CA'<1>:
 C_SIGNAL='@t6g_mb_lib.t6g(sch_1):m_f_cpu1_sa_ca(1)';
NODE_NAME     U26 AY67
 '@T6G_MB_LIB.T6G(SCH_1):PAGE42_I159@PURE_QUANTA.GENOA_SP5(CHIPS)':
 'MFA_CA1': CDS_PINID='MFA_CA1';
NODE_NAME     J33 211
 '@T6G_MB_LIB.T6G(SCH_1):PAGE102_I22@PURE_QUANTA.SCONN288_DDR506112002KQ(CHIPS)':
 'CA1_A': CDS_PINID='CA1_A';
NET_NAME
'M_F_CPU1_SA_CA<2>'
 '@T6G_MB_LIB.T6G(SCH_1):M_F_CPU1_SA_CA'<2>:
 C_SIGNAL='@t6g_mb_lib.t6g(sch_1):m_f_cpu1_sa_ca(2)';
NODE_NAME     U26 AY65
 '@T6G_MB_LIB.T6G(SCH_1):PAGE42_I159@PURE_QUANTA.GENOA_SP5(CHIPS)':
 'MFA_CA2': CDS_PINID='MFA_CA2';
NODE_NAME     J33 68
 '@T6G_MB_LIB.T6G(SCH_1):PAGE102_I22@PURE_QUANTA.SCONN288_DDR506112002KQ(CHIPS)':
 'CA2_A': CDS_PINID='CA2_A';
NET_NAME
'M_F_CPU1_SA_CA<3>'
 '@T6G_MB_LIB.T6G(SCH_1):M_F_CPU1_SA_CA'<3>:
 C_SIGNAL='@t6g_mb_lib.t6g(sch_1):m_f_cpu1_sa_ca(3)';
NODE_NAME     U26 BA66
 '@T6G_MB_LIB.T6G(SCH_1):PAGE42_I159@PURE_QUANTA.GENOA_SP5(CHIPS)':
 'MFA_CA3': CDS_PINID='MFA_CA3';
NODE_NAME     J33 213
 '@T6G_MB_LIB.T6G(SCH_1):PAGE102_I22@PURE_QUANTA.SCONN288_DDR506112002KQ(CHIPS)':
 'CA3_A': CDS_PINID='CA3_A';
NET_NAME
'M_F_CPU1_SA_CA<4>'
 '@T6G_MB_LIB.T6G(SCH_1):M_F_CPU1_SA_CA'<4>:
 C_SIGNAL='@t6g_mb_lib.t6g(sch_1):m_f_cpu1_sa_ca(4)';
NODE_NAME     U26 BA67
 '@T6G_MB_LIB.T6G(SCH_1):PAGE42_I159@PURE_QUANTA.GENOA_SP5(CHIPS)':
 'MFA_CA4': CDS_PINID='MFA_CA4';
NODE_NAME     J33 70
 '@T6G_MB_LIB.T6G(SCH_1):PAGE102_I22@PURE_QUANTA.SCONN288_DDR506112002KQ(CHIPS)':
 'CA4_A': CDS_PINID='CA4_A';
NET_NAME
'M_F_CPU1_SA_CA<5>'
 '@T6G_MB_LIB.T6G(SCH_1):M_F_CPU1_SA_CA'<5>:
 C_SIGNAL='@t6g_mb_lib.t6g(sch_1):m_f_cpu1_sa_ca(5)';
NODE_NAME     U26 BB67
 '@T6G_MB_LIB.T6G(SCH_1):PAGE42_I159@PURE_QUANTA.GENOA_SP5(CHIPS)':
 'MFA_CA5': CDS_PINID='MFA_CA5';
NODE_NAME     J33 215
 '@T6G_MB_LIB.T6G(SCH_1):PAGE102_I22@PURE_QUANTA.SCONN288_DDR506112002KQ(CHIPS)':
 'CA5_A': CDS_PINID='CA5_A';
NET_NAME
'M_F_CPU1_SA_CA<6>'
 '@T6G_MB_LIB.T6G(SCH_1):M_F_CPU1_SA_CA'<6>:
 C_SIGNAL='@t6g_mb_lib.t6g(sch_1):m_f_cpu1_sa_ca(6)';
NODE_NAME     U26 BB65
 '@T6G_MB_LIB.T6G(SCH_1):PAGE42_I159@PURE_QUANTA.GENOA_SP5(CHIPS)':
 'MFA_CA6': CDS_PINID='MFA_CA6';
NODE_NAME     J33 72
 '@T6G_MB_LIB.T6G(SCH_1):PAGE102_I22@PURE_QUANTA.SCONN288_DDR506112002KQ(CHIPS)':
 'CA6_A': CDS_PINID='CA6_A';
NET_NAME
'M_F_CPU1_SA_CB<0>'
 '@T6G_MB_LIB.T6G(SCH_1):M_F_CPU1_SA_CB'<0>:
 C_SIGNAL='@t6g_mb_lib.t6g(sch_1):m_f_cpu1_sa_cb(0)';
NODE_NAME     U26 AJ67
 '@T6G_MB_LIB.T6G(SCH_1):PAGE42_I159@PURE_QUANTA.GENOA_SP5(CHIPS)':
 'MFA_CHECK0': CDS_PINID='MFA_CHECK0';
NODE_NAME     J33 51
 '@T6G_MB_LIB.T6G(SCH_1):PAGE102_I22@PURE_QUANTA.SCONN288_DDR506112002KQ(CHIPS)':
 'CB0_A': CDS_PINID='CB0_A';
NET_NAME
'M_F_CPU1_SA_CB<1>'
 '@T6G_MB_LIB.T6G(SCH_1):M_F_CPU1_SA_CB'<1>:
 C_SIGNAL='@t6g_mb_lib.t6g(sch_1):m_f_cpu1_sa_cb(1)';
NODE_NAME     U26 AK65
 '@T6G_MB_LIB.T6G(SCH_1):PAGE42_I159@PURE_QUANTA.GENOA_SP5(CHIPS)':
 'MFA_CHECK1': CDS_PINID='MFA_CHECK1';
NODE_NAME     J33 53
 '@T6G_MB_LIB.T6G(SCH_1):PAGE102_I22@PURE_QUANTA.SCONN288_DDR506112002KQ(CHIPS)':
 'CB1_A': CDS_PINID='CB1_A';
NET_NAME
'M_F_CPU1_SA_CB<2>'
 '@T6G_MB_LIB.T6G(SCH_1):M_F_CPU1_SA_CB'<2>:
 C_SIGNAL='@t6g_mb_lib.t6g(sch_1):m_f_cpu1_sa_cb(2)';
NODE_NAME     U26 AK67
 '@T6G_MB_LIB.T6G(SCH_1):PAGE42_I159@PURE_QUANTA.GENOA_SP5(CHIPS)':
 'MFA_CHECK2': CDS_PINID='MFA_CHECK2';
NODE_NAME     J33 196
 '@T6G_MB_LIB.T6G(SCH_1):PAGE102_I22@PURE_QUANTA.SCONN288_DDR506112002KQ(CHIPS)':
 'CB2_A': CDS_PINID='CB2_A';
NET_NAME
'M_F_CPU1_SA_CB<3>'
 '@T6G_MB_LIB.T6G(SCH_1):M_F_CPU1_SA_CB'<3>:
 C_SIGNAL='@t6g_mb_lib.t6g(sch_1):m_f_cpu1_sa_cb(3)';
NODE_NAME     U26 AL66
 '@T6G_MB_LIB.T6G(SCH_1):PAGE42_I159@PURE_QUANTA.GENOA_SP5(CHIPS)':
 'MFA_CHECK3': CDS_PINID='MFA_CHECK3';
NODE_NAME     J33 198
 '@T6G_MB_LIB.T6G(SCH_1):PAGE102_I22@PURE_QUANTA.SCONN288_DDR506112002KQ(CHIPS)':
 'CB3_A': CDS_PINID='CB3_A';
NET_NAME
'M_F_CPU1_SA_CB<4>'
 '@T6G_MB_LIB.T6G(SCH_1):M_F_CPU1_SA_CB'<4>:
 C_SIGNAL='@t6g_mb_lib.t6g(sch_1):m_f_cpu1_sa_cb(4)';
NODE_NAME     U26 AN67
 '@T6G_MB_LIB.T6G(SCH_1):PAGE42_I159@PURE_QUANTA.GENOA_SP5(CHIPS)':
 'MFA_CHECK4': CDS_PINID='MFA_CHECK4';
NODE_NAME     J33 58
 '@T6G_MB_LIB.T6G(SCH_1):PAGE102_I22@PURE_QUANTA.SCONN288_DDR506112002KQ(CHIPS)':
 'CB4_A': CDS_PINID='CB4_A';
NET_NAME
'M_F_CPU1_SA_CB<5>'
 '@T6G_MB_LIB.T6G(SCH_1):M_F_CPU1_SA_CB'<5>:
 C_SIGNAL='@t6g_mb_lib.t6g(sch_1):m_f_cpu1_sa_cb(5)';
NODE_NAME     U26 AP65
 '@T6G_MB_LIB.T6G(SCH_1):PAGE42_I159@PURE_QUANTA.GENOA_SP5(CHIPS)':
 'MFA_CHECK5': CDS_PINID='MFA_CHECK5';
NODE_NAME     J33 60
 '@T6G_MB_LIB.T6G(SCH_1):PAGE102_I22@PURE_QUANTA.SCONN288_DDR506112002KQ(CHIPS)':
 'CB5_A': CDS_PINID='CB5_A';
NET_NAME
'M_F_CPU1_SA_CB<6>'
 '@T6G_MB_LIB.T6G(SCH_1):M_F_CPU1_SA_CB'<6>:
 C_SIGNAL='@t6g_mb_lib.t6g(sch_1):m_f_cpu1_sa_cb(6)';
NODE_NAME     U26 AP67
 '@T6G_MB_LIB.T6G(SCH_1):PAGE42_I159@PURE_QUANTA.GENOA_SP5(CHIPS)':
 'MFA_CHECK6': CDS_PINID='MFA_CHECK6';
NODE_NAME     J33 203
 '@T6G_MB_LIB.T6G(SCH_1):PAGE102_I22@PURE_QUANTA.SCONN288_DDR506112002KQ(CHIPS)':
 'CB6_A': CDS_PINID='CB6_A';
NET_NAME
'M_F_CPU1_SA_CB<7>'
 '@T6G_MB_LIB.T6G(SCH_1):M_F_CPU1_SA_CB'<7>:
 C_SIGNAL='@t6g_mb_lib.t6g(sch_1):m_f_cpu1_sa_cb(7)';
NODE_NAME     U26 AR66
 '@T6G_MB_LIB.T6G(SCH_1):PAGE42_I159@PURE_QUANTA.GENOA_SP5(CHIPS)':
 'MFA_CHECK7': CDS_PINID='MFA_CHECK7';
NODE_NAME     J33 205
 '@T6G_MB_LIB.T6G(SCH_1):PAGE102_I22@PURE_QUANTA.SCONN288_DDR506112002KQ(CHIPS)':
 'CB7_A': CDS_PINID='CB7_A';
NET_NAME
'M_F_CPU1_SA_CS_N<0>'
 '@T6G_MB_LIB.T6G(SCH_1):M_F_CPU1_SA_CS_N'<0>:
 C_SIGNAL='@t6g_mb_lib.t6g(sch_1):m_f_cpu1_sa_cs_n(0)';
NODE_NAME     U26 AV67
 '@T6G_MB_LIB.T6G(SCH_1):PAGE42_I159@PURE_QUANTA.GENOA_SP5(CHIPS)':
 'MFA0_CS_L0': CDS_PINID='MFA0_CS_L0';
NODE_NAME     J33 64
 '@T6G_MB_LIB.T6G(SCH_1):PAGE102_I22@PURE_QUANTA.SCONN288_DDR506112002KQ(CHIPS)':
 'CS0_A_N': CDS_PINID='CS0_A_N';
NET_NAME
'M_F_CPU1_SA_CS_N<1>'
 '@T6G_MB_LIB.T6G(SCH_1):M_F_CPU1_SA_CS_N'<1>:
 C_SIGNAL='@t6g_mb_lib.t6g(sch_1):m_f_cpu1_sa_cs_n(1)';
NODE_NAME     U26 AW66
 '@T6G_MB_LIB.T6G(SCH_1):PAGE42_I159@PURE_QUANTA.GENOA_SP5(CHIPS)':
 'MFA0_CS_L1': CDS_PINID='MFA0_CS_L1';
NODE_NAME     J33 209
 '@T6G_MB_LIB.T6G(SCH_1):PAGE102_I22@PURE_QUANTA.SCONN288_DDR506112002KQ(CHIPS)':
 'CS1_A_N': CDS_PINID='CS1_A_N';
NET_NAME
'M_F_CPU1_SA_DQ<0>'
 '@T6G_MB_LIB.T6G(SCH_1):M_F_CPU1_SA_DQ'<0>:
 C_SIGNAL='@t6g_mb_lib.t6g(sch_1):m_f_cpu1_sa_dq(0)';
NODE_NAME     U26 E67
 '@T6G_MB_LIB.T6G(SCH_1):PAGE42_I159@PURE_QUANTA.GENOA_SP5(CHIPS)':
 'MFA_DATA0': CDS_PINID='MFA_DATA0';
NODE_NAME     J33 7
 '@T6G_MB_LIB.T6G(SCH_1):PAGE102_I22@PURE_QUANTA.SCONN288_DDR506112002KQ(CHIPS)':
 'DQ0_A': CDS_PINID='DQ0_A';
NET_NAME
'M_F_CPU1_SA_DQ<10>'
 '@T6G_MB_LIB.T6G(SCH_1):M_F_CPU1_SA_DQ'<10>:
 C_SIGNAL='@t6g_mb_lib.t6g(sch_1):m_f_cpu1_sa_dq(10)';
NODE_NAME     U26 M67
 '@T6G_MB_LIB.T6G(SCH_1):PAGE42_I159@PURE_QUANTA.GENOA_SP5(CHIPS)':
 'MFA_DATA10': CDS_PINID='MFA_DATA10';
NODE_NAME     J33 163
 '@T6G_MB_LIB.T6G(SCH_1):PAGE102_I22@PURE_QUANTA.SCONN288_DDR506112002KQ(CHIPS)':
 'DQ10_A': CDS_PINID='DQ10_A';
NET_NAME
'M_F_CPU1_SA_DQ<11>'
 '@T6G_MB_LIB.T6G(SCH_1):M_F_CPU1_SA_DQ'<11>:
 C_SIGNAL='@t6g_mb_lib.t6g(sch_1):m_f_cpu1_sa_dq(11)';
NODE_NAME     U26 N66
 '@T6G_MB_LIB.T6G(SCH_1):PAGE42_I159@PURE_QUANTA.GENOA_SP5(CHIPS)':
 'MFA_DATA11': CDS_PINID='MFA_DATA11';
NODE_NAME     J33 165
 '@T6G_MB_LIB.T6G(SCH_1):PAGE102_I22@PURE_QUANTA.SCONN288_DDR506112002KQ(CHIPS)':
 'DQ11_A': CDS_PINID='DQ11_A';
NET_NAME
'M_F_CPU1_SA_DQ<12>'
 '@T6G_MB_LIB.T6G(SCH_1):M_F_CPU1_SA_DQ'<12>:
 C_SIGNAL='@t6g_mb_lib.t6g(sch_1):m_f_cpu1_sa_dq(12)';
NODE_NAME     U26 R67
 '@T6G_MB_LIB.T6G(SCH_1):PAGE42_I159@PURE_QUANTA.GENOA_SP5(CHIPS)':
 'MFA_DATA12': CDS_PINID='MFA_DATA12';
NODE_NAME     J33 25
 '@T6G_MB_LIB.T6G(SCH_1):PAGE102_I22@PURE_QUANTA.SCONN288_DDR506112002KQ(CHIPS)':
 'DQ12_A': CDS_PINID='DQ12_A';
NET_NAME
'M_F_CPU1_SA_DQ<13>'
 '@T6G_MB_LIB.T6G(SCH_1):M_F_CPU1_SA_DQ'<13>:
 C_SIGNAL='@t6g_mb_lib.t6g(sch_1):m_f_cpu1_sa_dq(13)';
NODE_NAME     U26 T65
 '@T6G_MB_LIB.T6G(SCH_1):PAGE42_I159@PURE_QUANTA.GENOA_SP5(CHIPS)':
 'MFA_DATA13': CDS_PINID='MFA_DATA13';
NODE_NAME     J33 27
 '@T6G_MB_LIB.T6G(SCH_1):PAGE102_I22@PURE_QUANTA.SCONN288_DDR506112002KQ(CHIPS)':
 'DQ13_A': CDS_PINID='DQ13_A';
NET_NAME
'M_F_CPU1_SA_DQ<14>'
 '@T6G_MB_LIB.T6G(SCH_1):M_F_CPU1_SA_DQ'<14>:
 C_SIGNAL='@t6g_mb_lib.t6g(sch_1):m_f_cpu1_sa_dq(14)';
NODE_NAME     U26 T67
 '@T6G_MB_LIB.T6G(SCH_1):PAGE42_I159@PURE_QUANTA.GENOA_SP5(CHIPS)':
 'MFA_DATA14': CDS_PINID='MFA_DATA14';
NODE_NAME     J33 170
 '@T6G_MB_LIB.T6G(SCH_1):PAGE102_I22@PURE_QUANTA.SCONN288_DDR506112002KQ(CHIPS)':
 'DQ14_A': CDS_PINID='DQ14_A';
NET_NAME
'M_F_CPU1_SA_DQ<15>'
 '@T6G_MB_LIB.T6G(SCH_1):M_F_CPU1_SA_DQ'<15>:
 C_SIGNAL='@t6g_mb_lib.t6g(sch_1):m_f_cpu1_sa_dq(15)';
NODE_NAME     U26 U66
 '@T6G_MB_LIB.T6G(SCH_1):PAGE42_I159@PURE_QUANTA.GENOA_SP5(CHIPS)':
 'MFA_DATA15': CDS_PINID='MFA_DATA15';
NODE_NAME     J33 172
 '@T6G_MB_LIB.T6G(SCH_1):PAGE102_I22@PURE_QUANTA.SCONN288_DDR506112002KQ(CHIPS)':
 'DQ15_A': CDS_PINID='DQ15_A';
NET_NAME
'M_F_CPU1_SA_DQ<16>'
 '@T6G_MB_LIB.T6G(SCH_1):M_F_CPU1_SA_DQ'<16>:
 C_SIGNAL='@t6g_mb_lib.t6g(sch_1):m_f_cpu1_sa_dq(16)';
NODE_NAME     U26 U67
 '@T6G_MB_LIB.T6G(SCH_1):PAGE42_I159@PURE_QUANTA.GENOA_SP5(CHIPS)':
 'MFA_DATA16': CDS_PINID='MFA_DATA16';
NODE_NAME     J33 29
 '@T6G_MB_LIB.T6G(SCH_1):PAGE102_I22@PURE_QUANTA.SCONN288_DDR506112002KQ(CHIPS)':
 'DQ16_A': CDS_PINID='DQ16_A';
NET_NAME
'M_F_CPU1_SA_DQ<17>'
 '@T6G_MB_LIB.T6G(SCH_1):M_F_CPU1_SA_DQ'<17>:
 C_SIGNAL='@t6g_mb_lib.t6g(sch_1):m_f_cpu1_sa_dq(17)';
NODE_NAME     U26 V65
 '@T6G_MB_LIB.T6G(SCH_1):PAGE42_I159@PURE_QUANTA.GENOA_SP5(CHIPS)':
 'MFA_DATA17': CDS_PINID='MFA_DATA17';
NODE_NAME     J33 31
 '@T6G_MB_LIB.T6G(SCH_1):PAGE102_I22@PURE_QUANTA.SCONN288_DDR506112002KQ(CHIPS)':
 'DQ17_A': CDS_PINID='DQ17_A';
NET_NAME
'M_F_CPU1_SA_DQ<18>'
 '@T6G_MB_LIB.T6G(SCH_1):M_F_CPU1_SA_DQ'<18>:
 C_SIGNAL='@t6g_mb_lib.t6g(sch_1):m_f_cpu1_sa_dq(18)';
NODE_NAME     U26 V67
 '@T6G_MB_LIB.T6G(SCH_1):PAGE42_I159@PURE_QUANTA.GENOA_SP5(CHIPS)':
 'MFA_DATA18': CDS_PINID='MFA_DATA18';
NODE_NAME     J33 174
 '@T6G_MB_LIB.T6G(SCH_1):PAGE102_I22@PURE_QUANTA.SCONN288_DDR506112002KQ(CHIPS)':
 'DQ18_A': CDS_PINID='DQ18_A';
NET_NAME
'M_F_CPU1_SA_DQ<19>'
 '@T6G_MB_LIB.T6G(SCH_1):M_F_CPU1_SA_DQ'<19>:
 C_SIGNAL='@t6g_mb_lib.t6g(sch_1):m_f_cpu1_sa_dq(19)';
NODE_NAME     U26 W66
 '@T6G_MB_LIB.T6G(SCH_1):PAGE42_I159@PURE_QUANTA.GENOA_SP5(CHIPS)':
 'MFA_DATA19': CDS_PINID='MFA_DATA19';
NODE_NAME     J33 176
 '@T6G_MB_LIB.T6G(SCH_1):PAGE102_I22@PURE_QUANTA.SCONN288_DDR506112002KQ(CHIPS)':
 'DQ19_A': CDS_PINID='DQ19_A';
NET_NAME
'M_F_CPU1_SA_DQ<1>'
 '@T6G_MB_LIB.T6G(SCH_1):M_F_CPU1_SA_DQ'<1>:
 C_SIGNAL='@t6g_mb_lib.t6g(sch_1):m_f_cpu1_sa_dq(1)';
NODE_NAME     U26 F65
 '@T6G_MB_LIB.T6G(SCH_1):PAGE42_I159@PURE_QUANTA.GENOA_SP5(CHIPS)':
 'MFA_DATA1': CDS_PINID='MFA_DATA1';
NODE_NAME     J33 9
 '@T6G_MB_LIB.T6G(SCH_1):PAGE102_I22@PURE_QUANTA.SCONN288_DDR506112002KQ(CHIPS)':
 'DQ1_A': CDS_PINID='DQ1_A';
NET_NAME
'M_F_CPU1_SA_DQ<20>'
 '@T6G_MB_LIB.T6G(SCH_1):M_F_CPU1_SA_DQ'<20>:
 C_SIGNAL='@t6g_mb_lib.t6g(sch_1):m_f_cpu1_sa_dq(20)';
NODE_NAME     U26 AA67
 '@T6G_MB_LIB.T6G(SCH_1):PAGE42_I159@PURE_QUANTA.GENOA_SP5(CHIPS)':
 'MFA_DATA20': CDS_PINID='MFA_DATA20';
NODE_NAME     J33 36
 '@T6G_MB_LIB.T6G(SCH_1):PAGE102_I22@PURE_QUANTA.SCONN288_DDR506112002KQ(CHIPS)':
 'DQ20_A': CDS_PINID='DQ20_A';
NET_NAME
'M_F_CPU1_SA_DQ<21>'
 '@T6G_MB_LIB.T6G(SCH_1):M_F_CPU1_SA_DQ'<21>:
 C_SIGNAL='@t6g_mb_lib.t6g(sch_1):m_f_cpu1_sa_dq(21)';
NODE_NAME     U26 AB65
 '@T6G_MB_LIB.T6G(SCH_1):PAGE42_I159@PURE_QUANTA.GENOA_SP5(CHIPS)':
 'MFA_DATA21': CDS_PINID='MFA_DATA21';
NODE_NAME     J33 38
 '@T6G_MB_LIB.T6G(SCH_1):PAGE102_I22@PURE_QUANTA.SCONN288_DDR506112002KQ(CHIPS)':
 'DQ21_A': CDS_PINID='DQ21_A';
NET_NAME
'M_F_CPU1_SA_DQ<22>'
 '@T6G_MB_LIB.T6G(SCH_1):M_F_CPU1_SA_DQ'<22>:
 C_SIGNAL='@t6g_mb_lib.t6g(sch_1):m_f_cpu1_sa_dq(22)';
NODE_NAME     U26 AB67
 '@T6G_MB_LIB.T6G(SCH_1):PAGE42_I159@PURE_QUANTA.GENOA_SP5(CHIPS)':
 'MFA_DATA22': CDS_PINID='MFA_DATA22';
NODE_NAME     J33 181
 '@T6G_MB_LIB.T6G(SCH_1):PAGE102_I22@PURE_QUANTA.SCONN288_DDR506112002KQ(CHIPS)':
 'DQ22_A': CDS_PINID='DQ22_A';
NET_NAME
'M_F_CPU1_SA_DQ<23>'
 '@T6G_MB_LIB.T6G(SCH_1):M_F_CPU1_SA_DQ'<23>:
 C_SIGNAL='@t6g_mb_lib.t6g(sch_1):m_f_cpu1_sa_dq(23)';
NODE_NAME     U26 AC66
 '@T6G_MB_LIB.T6G(SCH_1):PAGE42_I159@PURE_QUANTA.GENOA_SP5(CHIPS)':
 'MFA_DATA23': CDS_PINID='MFA_DATA23';
NODE_NAME     J33 183
 '@T6G_MB_LIB.T6G(SCH_1):PAGE102_I22@PURE_QUANTA.SCONN288_DDR506112002KQ(CHIPS)':
 'DQ23_A': CDS_PINID='DQ23_A';
NET_NAME
'M_F_CPU1_SA_DQ<24>'
 '@T6G_MB_LIB.T6G(SCH_1):M_F_CPU1_SA_DQ'<24>:
 C_SIGNAL='@t6g_mb_lib.t6g(sch_1):m_f_cpu1_sa_dq(24)';
NODE_NAME     U26 AC67
 '@T6G_MB_LIB.T6G(SCH_1):PAGE42_I159@PURE_QUANTA.GENOA_SP5(CHIPS)':
 'MFA_DATA24': CDS_PINID='MFA_DATA24';
NODE_NAME     J33 40
 '@T6G_MB_LIB.T6G(SCH_1):PAGE102_I22@PURE_QUANTA.SCONN288_DDR506112002KQ(CHIPS)':
 'DQ24_A': CDS_PINID='DQ24_A';
NET_NAME
'M_F_CPU1_SA_DQ<25>'
 '@T6G_MB_LIB.T6G(SCH_1):M_F_CPU1_SA_DQ'<25>:
 C_SIGNAL='@t6g_mb_lib.t6g(sch_1):m_f_cpu1_sa_dq(25)';
NODE_NAME     U26 AD65
 '@T6G_MB_LIB.T6G(SCH_1):PAGE42_I159@PURE_QUANTA.GENOA_SP5(CHIPS)':
 'MFA_DATA25': CDS_PINID='MFA_DATA25';
NODE_NAME     J33 42
 '@T6G_MB_LIB.T6G(SCH_1):PAGE102_I22@PURE_QUANTA.SCONN288_DDR506112002KQ(CHIPS)':
 'DQ25_A': CDS_PINID='DQ25_A';
NET_NAME
'M_F_CPU1_SA_DQ<26>'
 '@T6G_MB_LIB.T6G(SCH_1):M_F_CPU1_SA_DQ'<26>:
 C_SIGNAL='@t6g_mb_lib.t6g(sch_1):m_f_cpu1_sa_dq(26)';
NODE_NAME     U26 AD67
 '@T6G_MB_LIB.T6G(SCH_1):PAGE42_I159@PURE_QUANTA.GENOA_SP5(CHIPS)':
 'MFA_DATA26': CDS_PINID='MFA_DATA26';
NODE_NAME     J33 185
 '@T6G_MB_LIB.T6G(SCH_1):PAGE102_I22@PURE_QUANTA.SCONN288_DDR506112002KQ(CHIPS)':
 'DQ26_A': CDS_PINID='DQ26_A';
NET_NAME
'M_F_CPU1_SA_DQ<27>'
 '@T6G_MB_LIB.T6G(SCH_1):M_F_CPU1_SA_DQ'<27>:
 C_SIGNAL='@t6g_mb_lib.t6g(sch_1):m_f_cpu1_sa_dq(27)';
NODE_NAME     U26 AE66
 '@T6G_MB_LIB.T6G(SCH_1):PAGE42_I159@PURE_QUANTA.GENOA_SP5(CHIPS)':
 'MFA_DATA27': CDS_PINID='MFA_DATA27';
NODE_NAME     J33 187
 '@T6G_MB_LIB.T6G(SCH_1):PAGE102_I22@PURE_QUANTA.SCONN288_DDR506112002KQ(CHIPS)':
 'DQ27_A': CDS_PINID='DQ27_A';
NET_NAME
'M_F_CPU1_SA_DQ<28>'
 '@T6G_MB_LIB.T6G(SCH_1):M_F_CPU1_SA_DQ'<28>:
 C_SIGNAL='@t6g_mb_lib.t6g(sch_1):m_f_cpu1_sa_dq(28)';
NODE_NAME     U26 AG67
 '@T6G_MB_LIB.T6G(SCH_1):PAGE42_I159@PURE_QUANTA.GENOA_SP5(CHIPS)':
 'MFA_DATA28': CDS_PINID='MFA_DATA28';
NODE_NAME     J33 47
 '@T6G_MB_LIB.T6G(SCH_1):PAGE102_I22@PURE_QUANTA.SCONN288_DDR506112002KQ(CHIPS)':
 'DQ28_A': CDS_PINID='DQ28_A';
NET_NAME
'M_F_CPU1_SA_DQ<29>'
 '@T6G_MB_LIB.T6G(SCH_1):M_F_CPU1_SA_DQ'<29>:
 C_SIGNAL='@t6g_mb_lib.t6g(sch_1):m_f_cpu1_sa_dq(29)';
NODE_NAME     U26 AH65
 '@T6G_MB_LIB.T6G(SCH_1):PAGE42_I159@PURE_QUANTA.GENOA_SP5(CHIPS)':
 'MFA_DATA29': CDS_PINID='MFA_DATA29';
NODE_NAME     J33 49
 '@T6G_MB_LIB.T6G(SCH_1):PAGE102_I22@PURE_QUANTA.SCONN288_DDR506112002KQ(CHIPS)':
 'DQ29_A': CDS_PINID='DQ29_A';
NET_NAME
'M_F_CPU1_SA_DQ<2>'
 '@T6G_MB_LIB.T6G(SCH_1):M_F_CPU1_SA_DQ'<2>:
 C_SIGNAL='@t6g_mb_lib.t6g(sch_1):m_f_cpu1_sa_dq(2)';
NODE_NAME     U26 F67
 '@T6G_MB_LIB.T6G(SCH_1):PAGE42_I159@PURE_QUANTA.GENOA_SP5(CHIPS)':
 'MFA_DATA2': CDS_PINID='MFA_DATA2';
NODE_NAME     J33 152
 '@T6G_MB_LIB.T6G(SCH_1):PAGE102_I22@PURE_QUANTA.SCONN288_DDR506112002KQ(CHIPS)':
 'DQ2_A': CDS_PINID='DQ2_A';
NET_NAME
'M_F_CPU1_SA_DQ<30>'
 '@T6G_MB_LIB.T6G(SCH_1):M_F_CPU1_SA_DQ'<30>:
 C_SIGNAL='@t6g_mb_lib.t6g(sch_1):m_f_cpu1_sa_dq(30)';
NODE_NAME     U26 AH67
 '@T6G_MB_LIB.T6G(SCH_1):PAGE42_I159@PURE_QUANTA.GENOA_SP5(CHIPS)':
 'MFA_DATA30': CDS_PINID='MFA_DATA30';
NODE_NAME     J33 192
 '@T6G_MB_LIB.T6G(SCH_1):PAGE102_I22@PURE_QUANTA.SCONN288_DDR506112002KQ(CHIPS)':
 'DQ30_A': CDS_PINID='DQ30_A';
NET_NAME
'M_F_CPU1_SA_DQ<31>'
 '@T6G_MB_LIB.T6G(SCH_1):M_F_CPU1_SA_DQ'<31>:
 C_SIGNAL='@t6g_mb_lib.t6g(sch_1):m_f_cpu1_sa_dq(31)';
NODE_NAME     U26 AJ66
 '@T6G_MB_LIB.T6G(SCH_1):PAGE42_I159@PURE_QUANTA.GENOA_SP5(CHIPS)':
 'MFA_DATA31': CDS_PINID='MFA_DATA31';
NODE_NAME     J33 194
 '@T6G_MB_LIB.T6G(SCH_1):PAGE102_I22@PURE_QUANTA.SCONN288_DDR506112002KQ(CHIPS)':
 'DQ31_A': CDS_PINID='DQ31_A';
NET_NAME
'M_F_CPU1_SA_DQ<3>'
 '@T6G_MB_LIB.T6G(SCH_1):M_F_CPU1_SA_DQ'<3>:
 C_SIGNAL='@t6g_mb_lib.t6g(sch_1):m_f_cpu1_sa_dq(3)';
NODE_NAME     U26 G66
 '@T6G_MB_LIB.T6G(SCH_1):PAGE42_I159@PURE_QUANTA.GENOA_SP5(CHIPS)':
 'MFA_DATA3': CDS_PINID='MFA_DATA3';
NODE_NAME     J33 154
 '@T6G_MB_LIB.T6G(SCH_1):PAGE102_I22@PURE_QUANTA.SCONN288_DDR506112002KQ(CHIPS)':
 'DQ3_A': CDS_PINID='DQ3_A';
NET_NAME
'M_F_CPU1_SA_DQ<4>'
 '@T6G_MB_LIB.T6G(SCH_1):M_F_CPU1_SA_DQ'<4>:
 C_SIGNAL='@t6g_mb_lib.t6g(sch_1):m_f_cpu1_sa_dq(4)';
NODE_NAME     U26 J67
 '@T6G_MB_LIB.T6G(SCH_1):PAGE42_I159@PURE_QUANTA.GENOA_SP5(CHIPS)':
 'MFA_DATA4': CDS_PINID='MFA_DATA4';
NODE_NAME     J33 14
 '@T6G_MB_LIB.T6G(SCH_1):PAGE102_I22@PURE_QUANTA.SCONN288_DDR506112002KQ(CHIPS)':
 'DQ4_A': CDS_PINID='DQ4_A';
NET_NAME
'M_F_CPU1_SA_DQ<5>'
 '@T6G_MB_LIB.T6G(SCH_1):M_F_CPU1_SA_DQ'<5>:
 C_SIGNAL='@t6g_mb_lib.t6g(sch_1):m_f_cpu1_sa_dq(5)';
NODE_NAME     U26 K65
 '@T6G_MB_LIB.T6G(SCH_1):PAGE42_I159@PURE_QUANTA.GENOA_SP5(CHIPS)':
 'MFA_DATA5': CDS_PINID='MFA_DATA5';
NODE_NAME     J33 16
 '@T6G_MB_LIB.T6G(SCH_1):PAGE102_I22@PURE_QUANTA.SCONN288_DDR506112002KQ(CHIPS)':
 'DQ5_A': CDS_PINID='DQ5_A';
NET_NAME
'M_F_CPU1_SA_DQ<6>'
 '@T6G_MB_LIB.T6G(SCH_1):M_F_CPU1_SA_DQ'<6>:
 C_SIGNAL='@t6g_mb_lib.t6g(sch_1):m_f_cpu1_sa_dq(6)';
NODE_NAME     U26 K67
 '@T6G_MB_LIB.T6G(SCH_1):PAGE42_I159@PURE_QUANTA.GENOA_SP5(CHIPS)':
 'MFA_DATA6': CDS_PINID='MFA_DATA6';
NODE_NAME     J33 159
 '@T6G_MB_LIB.T6G(SCH_1):PAGE102_I22@PURE_QUANTA.SCONN288_DDR506112002KQ(CHIPS)':
 'DQ6_A': CDS_PINID='DQ6_A';
NET_NAME
'M_F_CPU1_SA_DQ<7>'
 '@T6G_MB_LIB.T6G(SCH_1):M_F_CPU1_SA_DQ'<7>:
 C_SIGNAL='@t6g_mb_lib.t6g(sch_1):m_f_cpu1_sa_dq(7)';
NODE_NAME     U26 L66
 '@T6G_MB_LIB.T6G(SCH_1):PAGE42_I159@PURE_QUANTA.GENOA_SP5(CHIPS)':
 'MFA_DATA7': CDS_PINID='MFA_DATA7';
NODE_NAME     J33 161
 '@T6G_MB_LIB.T6G(SCH_1):PAGE102_I22@PURE_QUANTA.SCONN288_DDR506112002KQ(CHIPS)':
 'DQ7_A': CDS_PINID='DQ7_A';
NET_NAME
'M_F_CPU1_SA_DQ<8>'
 '@T6G_MB_LIB.T6G(SCH_1):M_F_CPU1_SA_DQ'<8>:
 C_SIGNAL='@t6g_mb_lib.t6g(sch_1):m_f_cpu1_sa_dq(8)';
NODE_NAME     U26 L67
 '@T6G_MB_LIB.T6G(SCH_1):PAGE42_I159@PURE_QUANTA.GENOA_SP5(CHIPS)':
 'MFA_DATA8': CDS_PINID='MFA_DATA8';
NODE_NAME     J33 18
 '@T6G_MB_LIB.T6G(SCH_1):PAGE102_I22@PURE_QUANTA.SCONN288_DDR506112002KQ(CHIPS)':
 'DQ8_A': CDS_PINID='DQ8_A';
NET_NAME
'M_F_CPU1_SA_DQ<9>'
 '@T6G_MB_LIB.T6G(SCH_1):M_F_CPU1_SA_DQ'<9>:
 C_SIGNAL='@t6g_mb_lib.t6g(sch_1):m_f_cpu1_sa_dq(9)';
NODE_NAME     U26 M65
 '@T6G_MB_LIB.T6G(SCH_1):PAGE42_I159@PURE_QUANTA.GENOA_SP5(CHIPS)':
 'MFA_DATA9': CDS_PINID='MFA_DATA9';
NODE_NAME     J33 20
 '@T6G_MB_LIB.T6G(SCH_1):PAGE102_I22@PURE_QUANTA.SCONN288_DDR506112002KQ(CHIPS)':
 'DQ9_A': CDS_PINID='DQ9_A';
NET_NAME
'M_F_CPU1_SA_DQS_DN<0>'
 '@T6G_MB_LIB.T6G(SCH_1):M_F_CPU1_SA_DQS_DN'<0>:
 C_SIGNAL='@t6g_mb_lib.t6g(sch_1):m_f_cpu1_sa_dqs_dn(0)';
NODE_NAME     U26 H67
 '@T6G_MB_LIB.T6G(SCH_1):PAGE42_I159@PURE_QUANTA.GENOA_SP5(CHIPS)':
 'MFA_DQS_L0': CDS_PINID='MFA_DQS_L0';
NODE_NAME     J33 12
 '@T6G_MB_LIB.T6G(SCH_1):PAGE102_I236@PURE_QUANTA.SCONN288_DDR506112002KQ(CHIPS)':
 'DQS0_A_C': CDS_PINID='DQS0_A_C';
NET_NAME
'M_F_CPU1_SA_DQS_DN<1>'
 '@T6G_MB_LIB.T6G(SCH_1):M_F_CPU1_SA_DQS_DN'<1>:
 C_SIGNAL='@t6g_mb_lib.t6g(sch_1):m_f_cpu1_sa_dqs_dn(1)';
NODE_NAME     U26 P67
 '@T6G_MB_LIB.T6G(SCH_1):PAGE42_I159@PURE_QUANTA.GENOA_SP5(CHIPS)':
 'MFA_DQS_L1': CDS_PINID='MFA_DQS_L1';
NODE_NAME     J33 23
 '@T6G_MB_LIB.T6G(SCH_1):PAGE102_I236@PURE_QUANTA.SCONN288_DDR506112002KQ(CHIPS)':
 'DQS1_A_C': CDS_PINID='DQS1_A_C';
NET_NAME
'M_F_CPU1_SA_DQS_DN<2>'
 '@T6G_MB_LIB.T6G(SCH_1):M_F_CPU1_SA_DQS_DN'<2>:
 C_SIGNAL='@t6g_mb_lib.t6g(sch_1):m_f_cpu1_sa_dqs_dn(2)';
NODE_NAME     U26 Y67
 '@T6G_MB_LIB.T6G(SCH_1):PAGE42_I159@PURE_QUANTA.GENOA_SP5(CHIPS)':
 'MFA_DQS_L2': CDS_PINID='MFA_DQS_L2';
NODE_NAME     J33 34
 '@T6G_MB_LIB.T6G(SCH_1):PAGE102_I236@PURE_QUANTA.SCONN288_DDR506112002KQ(CHIPS)':
 'DQS2_A_C': CDS_PINID='DQS2_A_C';
NET_NAME
'M_F_CPU1_SA_DQS_DN<3>'
 '@T6G_MB_LIB.T6G(SCH_1):M_F_CPU1_SA_DQS_DN'<3>:
 C_SIGNAL='@t6g_mb_lib.t6g(sch_1):m_f_cpu1_sa_dqs_dn(3)';
NODE_NAME     U26 AF67
 '@T6G_MB_LIB.T6G(SCH_1):PAGE42_I159@PURE_QUANTA.GENOA_SP5(CHIPS)':
 'MFA_DQS_L3': CDS_PINID='MFA_DQS_L3';
NODE_NAME     J33 45
 '@T6G_MB_LIB.T6G(SCH_1):PAGE102_I236@PURE_QUANTA.SCONN288_DDR506112002KQ(CHIPS)':
 'DQS3_A_C': CDS_PINID='DQS3_A_C';
NET_NAME
'M_F_CPU1_SA_DQS_DN<4>'
 '@T6G_MB_LIB.T6G(SCH_1):M_F_CPU1_SA_DQS_DN'<4>:
 C_SIGNAL='@t6g_mb_lib.t6g(sch_1):m_f_cpu1_sa_dqs_dn(4)';
NODE_NAME     U26 AM67
 '@T6G_MB_LIB.T6G(SCH_1):PAGE42_I159@PURE_QUANTA.GENOA_SP5(CHIPS)':
 'MFA_DQS_L4': CDS_PINID='MFA_DQS_L4';
NODE_NAME     J33 56
 '@T6G_MB_LIB.T6G(SCH_1):PAGE102_I236@PURE_QUANTA.SCONN288_DDR506112002KQ(CHIPS)':
 'DQS4_A_C': CDS_PINID='DQS4_A_C';
NET_NAME
'M_F_CPU1_SA_DQS_DN<5>'
 '@T6G_MB_LIB.T6G(SCH_1):M_F_CPU1_SA_DQS_DN'<5>:
 C_SIGNAL='@t6g_mb_lib.t6g(sch_1):m_f_cpu1_sa_dqs_dn(5)';
NODE_NAME     U26 H65
 '@T6G_MB_LIB.T6G(SCH_1):PAGE42_I159@PURE_QUANTA.GENOA_SP5(CHIPS)':
 'MFA_DQS_L5': CDS_PINID='MFA_DQS_L5';
NODE_NAME     J33 156
 '@T6G_MB_LIB.T6G(SCH_1):PAGE102_I236@PURE_QUANTA.SCONN288_DDR506112002KQ(CHIPS)':
 'DQS5_A_C||TDQS5_A_C||DQS5_A_T||TDQS5_A_T': CDS_PINID='\dqs5_a_c||tdqs5_a_c||dqs5_a_t||tdqs5_a_t\';
NET_NAME
'M_F_CPU1_SA_DQS_DN<6>'
 '@T6G_MB_LIB.T6G(SCH_1):M_F_CPU1_SA_DQS_DN'<6>:
 C_SIGNAL='@t6g_mb_lib.t6g(sch_1):m_f_cpu1_sa_dqs_dn(6)';
NODE_NAME     U26 P65
 '@T6G_MB_LIB.T6G(SCH_1):PAGE42_I159@PURE_QUANTA.GENOA_SP5(CHIPS)':
 'MFA_DQS_L6': CDS_PINID='MFA_DQS_L6';
NODE_NAME     J33 167
 '@T6G_MB_LIB.T6G(SCH_1):PAGE102_I236@PURE_QUANTA.SCONN288_DDR506112002KQ(CHIPS)':
 'DQS6_A_C||TDQS6_A_C||DQS6_A_T||TDQS6_A_T': CDS_PINID='\dqs6_a_c||tdqs6_a_c||dqs6_a_t||tdqs6_a_t\';
NET_NAME
'M_F_CPU1_SA_DQS_DN<7>'
 '@T6G_MB_LIB.T6G(SCH_1):M_F_CPU1_SA_DQS_DN'<7>:
 C_SIGNAL='@t6g_mb_lib.t6g(sch_1):m_f_cpu1_sa_dqs_dn(7)';
NODE_NAME     U26 Y65
 '@T6G_MB_LIB.T6G(SCH_1):PAGE42_I159@PURE_QUANTA.GENOA_SP5(CHIPS)':
 'MFA_DQS_L7': CDS_PINID='MFA_DQS_L7';
NODE_NAME     J33 178
 '@T6G_MB_LIB.T6G(SCH_1):PAGE102_I236@PURE_QUANTA.SCONN288_DDR506112002KQ(CHIPS)':
 'DQS7_A_C||TDQS7_A_C': CDS_PINID='\dqs7_a_c||tdqs7_a_c\';
NET_NAME
'M_F_CPU1_SA_DQS_DN<8>'
 '@T6G_MB_LIB.T6G(SCH_1):M_F_CPU1_SA_DQS_DN'<8>:
 C_SIGNAL='@t6g_mb_lib.t6g(sch_1):m_f_cpu1_sa_dqs_dn(8)';
NODE_NAME     U26 AF65
 '@T6G_MB_LIB.T6G(SCH_1):PAGE42_I159@PURE_QUANTA.GENOA_SP5(CHIPS)':
 'MFA_DQS_L8': CDS_PINID='MFA_DQS_L8';
NODE_NAME     J33 189
 '@T6G_MB_LIB.T6G(SCH_1):PAGE102_I236@PURE_QUANTA.SCONN288_DDR506112002KQ(CHIPS)':
 'DQS8_A_C||TDQS8_A_C': CDS_PINID='\dqs8_a_c||tdqs8_a_c\';
NET_NAME
'M_F_CPU1_SA_DQS_DN<9>'
 '@T6G_MB_LIB.T6G(SCH_1):M_F_CPU1_SA_DQS_DN'<9>:
 C_SIGNAL='@t6g_mb_lib.t6g(sch_1):m_f_cpu1_sa_dqs_dn(9)';
NODE_NAME     U26 AM65
 '@T6G_MB_LIB.T6G(SCH_1):PAGE42_I159@PURE_QUANTA.GENOA_SP5(CHIPS)':
 'MFA_DQS_L9': CDS_PINID='MFA_DQS_L9';
NODE_NAME     J33 200
 '@T6G_MB_LIB.T6G(SCH_1):PAGE102_I236@PURE_QUANTA.SCONN288_DDR506112002KQ(CHIPS)':
 'DQS9_A_C||TDQS9_A_C': CDS_PINID='\dqs9_a_c||tdqs9_a_c\';
NET_NAME
'M_F_CPU1_SA_DQS_DP<0>'
 '@T6G_MB_LIB.T6G(SCH_1):M_F_CPU1_SA_DQS_DP'<0>:
 C_SIGNAL='@t6g_mb_lib.t6g(sch_1):m_f_cpu1_sa_dqs_dp(0)';
NODE_NAME     U26 G67
 '@T6G_MB_LIB.T6G(SCH_1):PAGE42_I159@PURE_QUANTA.GENOA_SP5(CHIPS)':
 'MFA_DQS_H0': CDS_PINID='MFA_DQS_H0';
NODE_NAME     J33 11
 '@T6G_MB_LIB.T6G(SCH_1):PAGE102_I236@PURE_QUANTA.SCONN288_DDR506112002KQ(CHIPS)':
 'DQS0_A_T': CDS_PINID='DQS0_A_T';
NET_NAME
'M_F_CPU1_SA_DQS_DP<1>'
 '@T6G_MB_LIB.T6G(SCH_1):M_F_CPU1_SA_DQS_DP'<1>:
 C_SIGNAL='@t6g_mb_lib.t6g(sch_1):m_f_cpu1_sa_dqs_dp(1)';
NODE_NAME     U26 N67
 '@T6G_MB_LIB.T6G(SCH_1):PAGE42_I159@PURE_QUANTA.GENOA_SP5(CHIPS)':
 'MFA_DQS_H1': CDS_PINID='MFA_DQS_H1';
NODE_NAME     J33 22
 '@T6G_MB_LIB.T6G(SCH_1):PAGE102_I236@PURE_QUANTA.SCONN288_DDR506112002KQ(CHIPS)':
 'DQS1_A_T': CDS_PINID='DQS1_A_T';
NET_NAME
'M_F_CPU1_SA_DQS_DP<2>'
 '@T6G_MB_LIB.T6G(SCH_1):M_F_CPU1_SA_DQS_DP'<2>:
 C_SIGNAL='@t6g_mb_lib.t6g(sch_1):m_f_cpu1_sa_dqs_dp(2)';
NODE_NAME     U26 W67
 '@T6G_MB_LIB.T6G(SCH_1):PAGE42_I159@PURE_QUANTA.GENOA_SP5(CHIPS)':
 'MFA_DQS_H2': CDS_PINID='MFA_DQS_H2';
NODE_NAME     J33 33
 '@T6G_MB_LIB.T6G(SCH_1):PAGE102_I236@PURE_QUANTA.SCONN288_DDR506112002KQ(CHIPS)':
 'DQS2_A_T': CDS_PINID='DQS2_A_T';
NET_NAME
'M_F_CPU1_SA_DQS_DP<3>'
 '@T6G_MB_LIB.T6G(SCH_1):M_F_CPU1_SA_DQS_DP'<3>:
 C_SIGNAL='@t6g_mb_lib.t6g(sch_1):m_f_cpu1_sa_dqs_dp(3)';
NODE_NAME     U26 AE67
 '@T6G_MB_LIB.T6G(SCH_1):PAGE42_I159@PURE_QUANTA.GENOA_SP5(CHIPS)':
 'MFA_DQS_H3': CDS_PINID='MFA_DQS_H3';
NODE_NAME     J33 44
 '@T6G_MB_LIB.T6G(SCH_1):PAGE102_I236@PURE_QUANTA.SCONN288_DDR506112002KQ(CHIPS)':
 'DQS3_A_T': CDS_PINID='DQS3_A_T';
NET_NAME
'M_F_CPU1_SA_DQS_DP<4>'
 '@T6G_MB_LIB.T6G(SCH_1):M_F_CPU1_SA_DQS_DP'<4>:
 C_SIGNAL='@t6g_mb_lib.t6g(sch_1):m_f_cpu1_sa_dqs_dp(4)';
NODE_NAME     U26 AL67
 '@T6G_MB_LIB.T6G(SCH_1):PAGE42_I159@PURE_QUANTA.GENOA_SP5(CHIPS)':
 'MFA_DQS_H4': CDS_PINID='MFA_DQS_H4';
NODE_NAME     J33 55
 '@T6G_MB_LIB.T6G(SCH_1):PAGE102_I236@PURE_QUANTA.SCONN288_DDR506112002KQ(CHIPS)':
 'DQS4_A_T': CDS_PINID='DQS4_A_T';
NET_NAME
'M_F_CPU1_SA_DQS_DP<5>'
 '@T6G_MB_LIB.T6G(SCH_1):M_F_CPU1_SA_DQS_DP'<5>:
 C_SIGNAL='@t6g_mb_lib.t6g(sch_1):m_f_cpu1_sa_dqs_dp(5)';
NODE_NAME     U26 J66
 '@T6G_MB_LIB.T6G(SCH_1):PAGE42_I159@PURE_QUANTA.GENOA_SP5(CHIPS)':
 'MFA_DQS_H5': CDS_PINID='MFA_DQS_H5';
NODE_NAME     J33 157
 '@T6G_MB_LIB.T6G(SCH_1):PAGE102_I236@PURE_QUANTA.SCONN288_DDR506112002KQ(CHIPS)':
 'DQS5_A_T||TDQS5_A_T': CDS_PINID='\dqs5_a_t||tdqs5_a_t\';
NET_NAME
'M_F_CPU1_SA_DQS_DP<6>'
 '@T6G_MB_LIB.T6G(SCH_1):M_F_CPU1_SA_DQS_DP'<6>:
 C_SIGNAL='@t6g_mb_lib.t6g(sch_1):m_f_cpu1_sa_dqs_dp(6)';
NODE_NAME     U26 R66
 '@T6G_MB_LIB.T6G(SCH_1):PAGE42_I159@PURE_QUANTA.GENOA_SP5(CHIPS)':
 'MFA_DQS_H6': CDS_PINID='MFA_DQS_H6';
NODE_NAME     J33 168
 '@T6G_MB_LIB.T6G(SCH_1):PAGE102_I236@PURE_QUANTA.SCONN288_DDR506112002KQ(CHIPS)':
 'DQS6_A_T||TDQS6_A_T': CDS_PINID='\dqs6_a_t||tdqs6_a_t\';
NET_NAME
'M_F_CPU1_SA_DQS_DP<7>'
 '@T6G_MB_LIB.T6G(SCH_1):M_F_CPU1_SA_DQS_DP'<7>:
 C_SIGNAL='@t6g_mb_lib.t6g(sch_1):m_f_cpu1_sa_dqs_dp(7)';
NODE_NAME     U26 AA66
 '@T6G_MB_LIB.T6G(SCH_1):PAGE42_I159@PURE_QUANTA.GENOA_SP5(CHIPS)':
 'MFA_DQS_H7': CDS_PINID='MFA_DQS_H7';
NODE_NAME     J33 179
 '@T6G_MB_LIB.T6G(SCH_1):PAGE102_I236@PURE_QUANTA.SCONN288_DDR506112002KQ(CHIPS)':
 'DQS7_A_T||TDQS7_A_T': CDS_PINID='\dqs7_a_t||tdqs7_a_t\';
NET_NAME
'M_F_CPU1_SA_DQS_DP<8>'
 '@T6G_MB_LIB.T6G(SCH_1):M_F_CPU1_SA_DQS_DP'<8>:
 C_SIGNAL='@t6g_mb_lib.t6g(sch_1):m_f_cpu1_sa_dqs_dp(8)';
NODE_NAME     U26 AG66
 '@T6G_MB_LIB.T6G(SCH_1):PAGE42_I159@PURE_QUANTA.GENOA_SP5(CHIPS)':
 'MFA_DQS_H8': CDS_PINID='MFA_DQS_H8';
NODE_NAME     J33 190
 '@T6G_MB_LIB.T6G(SCH_1):PAGE102_I236@PURE_QUANTA.SCONN288_DDR506112002KQ(CHIPS)':
 'DQS8_A_T||TDQS8_A_T': CDS_PINID='\dqs8_a_t||tdqs8_a_t\';
NET_NAME
'M_F_CPU1_SA_DQS_DP<9>'
 '@T6G_MB_LIB.T6G(SCH_1):M_F_CPU1_SA_DQS_DP'<9>:
 C_SIGNAL='@t6g_mb_lib.t6g(sch_1):m_f_cpu1_sa_dqs_dp(9)';
NODE_NAME     U26 AN66
 '@T6G_MB_LIB.T6G(SCH_1):PAGE42_I159@PURE_QUANTA.GENOA_SP5(CHIPS)':
 'MFA_DQS_H9': CDS_PINID='MFA_DQS_H9';
NODE_NAME     J33 201
 '@T6G_MB_LIB.T6G(SCH_1):PAGE102_I236@PURE_QUANTA.SCONN288_DDR506112002KQ(CHIPS)':
 'DQS9_A_T||TDQS9_A_T': CDS_PINID='\dqs9_a_t||tdqs9_a_t\';
NET_NAME
'M_F_CPU1_SA_PAR'
 '@T6G_MB_LIB.T6G(SCH_1):M_F_CPU1_SA_PAR':
 C_SIGNAL='@t6g_mb_lib.t6g(sch_1):m_f_cpu1_sa_par';
NODE_NAME     U26 BC66
 '@T6G_MB_LIB.T6G(SCH_1):PAGE42_I159@PURE_QUANTA.GENOA_SP5(CHIPS)':
 'MFA_PAR': CDS_PINID='MFA_PAR';
NODE_NAME     J33 74
 '@T6G_MB_LIB.T6G(SCH_1):PAGE102_I22@PURE_QUANTA.SCONN288_DDR506112002KQ(CHIPS)':
 'PAR_A': CDS_PINID='PAR_A';
NET_NAME
'M_F_CPU1_SA_RSP<0>'
 '@T6G_MB_LIB.T6G(SCH_1):M_F_CPU1_SA_RSP'<0>:
 C_SIGNAL='@t6g_mb_lib.t6g(sch_1):m_f_cpu1_sa_rsp(0)';
NODE_NAME     U26 BN66
 '@T6G_MB_LIB.T6G(SCH_1):PAGE42_I159@PURE_QUANTA.GENOA_SP5(CHIPS)':
 'MFA0_RSP_L': CDS_PINID='MFA0_RSP_L';
NODE_NAME     J33 86
 '@T6G_MB_LIB.T6G(SCH_1):PAGE102_I22@PURE_QUANTA.SCONN288_DDR506112002KQ(CHIPS)':
 'LBD||RSP_A_N': CDS_PINID='\lbd||rsp_a_n\';
NET_NAME
'M_F_CPU1_SB_CA<0>'
 '@T6G_MB_LIB.T6G(SCH_1):M_F_CPU1_SB_CA'<0>:
 C_SIGNAL='@t6g_mb_lib.t6g(sch_1):m_f_cpu1_sb_ca(0)';
NODE_NAME     U26 BG66
 '@T6G_MB_LIB.T6G(SCH_1):PAGE42_I159@PURE_QUANTA.GENOA_SP5(CHIPS)':
 'MFB_CA0': CDS_PINID='MFB_CA0';
NODE_NAME     J33 76
 '@T6G_MB_LIB.T6G(SCH_1):PAGE102_I22@PURE_QUANTA.SCONN288_DDR506112002KQ(CHIPS)':
 'CA0_B': CDS_PINID='CA0_B';
NET_NAME
'M_F_CPU1_SB_CA<1>'
 '@T6G_MB_LIB.T6G(SCH_1):M_F_CPU1_SB_CA'<1>:
 C_SIGNAL='@t6g_mb_lib.t6g(sch_1):m_f_cpu1_sb_ca(1)';
NODE_NAME     U26 BH65
 '@T6G_MB_LIB.T6G(SCH_1):PAGE42_I159@PURE_QUANTA.GENOA_SP5(CHIPS)':
 'MFB_CA1': CDS_PINID='MFB_CA1';
NODE_NAME     J33 221
 '@T6G_MB_LIB.T6G(SCH_1):PAGE102_I22@PURE_QUANTA.SCONN288_DDR506112002KQ(CHIPS)':
 'CA1_B': CDS_PINID='CA1_B';
NET_NAME
'M_F_CPU1_SB_CA<2>'
 '@T6G_MB_LIB.T6G(SCH_1):M_F_CPU1_SB_CA'<2>:
 C_SIGNAL='@t6g_mb_lib.t6g(sch_1):m_f_cpu1_sb_ca(2)';
NODE_NAME     U26 BH67
 '@T6G_MB_LIB.T6G(SCH_1):PAGE42_I159@PURE_QUANTA.GENOA_SP5(CHIPS)':
 'MFB_CA2': CDS_PINID='MFB_CA2';
NODE_NAME     J33 78
 '@T6G_MB_LIB.T6G(SCH_1):PAGE102_I22@PURE_QUANTA.SCONN288_DDR506112002KQ(CHIPS)':
 'CA2_B': CDS_PINID='CA2_B';
NET_NAME
'M_F_CPU1_SB_CA<3>'
 '@T6G_MB_LIB.T6G(SCH_1):M_F_CPU1_SB_CA'<3>:
 C_SIGNAL='@t6g_mb_lib.t6g(sch_1):m_f_cpu1_sb_ca(3)';
NODE_NAME     U26 BJ67
 '@T6G_MB_LIB.T6G(SCH_1):PAGE42_I159@PURE_QUANTA.GENOA_SP5(CHIPS)':
 'MFB_CA3': CDS_PINID='MFB_CA3';
NODE_NAME     J33 223
 '@T6G_MB_LIB.T6G(SCH_1):PAGE102_I22@PURE_QUANTA.SCONN288_DDR506112002KQ(CHIPS)':
 'CA3_B': CDS_PINID='CA3_B';
NET_NAME
'M_F_CPU1_SB_CA<4>'
 '@T6G_MB_LIB.T6G(SCH_1):M_F_CPU1_SB_CA'<4>:
 C_SIGNAL='@t6g_mb_lib.t6g(sch_1):m_f_cpu1_sb_ca(4)';
NODE_NAME     U26 BJ66
 '@T6G_MB_LIB.T6G(SCH_1):PAGE42_I159@PURE_QUANTA.GENOA_SP5(CHIPS)':
 'MFB_CA4': CDS_PINID='MFB_CA4';
NODE_NAME     J33 80
 '@T6G_MB_LIB.T6G(SCH_1):PAGE102_I22@PURE_QUANTA.SCONN288_DDR506112002KQ(CHIPS)':
 'CA4_B': CDS_PINID='CA4_B';
NET_NAME
'M_F_CPU1_SB_CA<5>'
 '@T6G_MB_LIB.T6G(SCH_1):M_F_CPU1_SB_CA'<5>:
 C_SIGNAL='@t6g_mb_lib.t6g(sch_1):m_f_cpu1_sb_ca(5)';
NODE_NAME     U26 BK65
 '@T6G_MB_LIB.T6G(SCH_1):PAGE42_I159@PURE_QUANTA.GENOA_SP5(CHIPS)':
 'MFB_CA5': CDS_PINID='MFB_CA5';
NODE_NAME     J33 225
 '@T6G_MB_LIB.T6G(SCH_1):PAGE102_I22@PURE_QUANTA.SCONN288_DDR506112002KQ(CHIPS)':
 'CA5_B': CDS_PINID='CA5_B';
NET_NAME
'M_F_CPU1_SB_CA<6>'
 '@T6G_MB_LIB.T6G(SCH_1):M_F_CPU1_SB_CA'<6>:
 C_SIGNAL='@t6g_mb_lib.t6g(sch_1):m_f_cpu1_sb_ca(6)';
NODE_NAME     U26 BK67
 '@T6G_MB_LIB.T6G(SCH_1):PAGE42_I159@PURE_QUANTA.GENOA_SP5(CHIPS)':
 'MFB_CA6': CDS_PINID='MFB_CA6';
NODE_NAME     J33 82
 '@T6G_MB_LIB.T6G(SCH_1):PAGE102_I22@PURE_QUANTA.SCONN288_DDR506112002KQ(CHIPS)':
 'CA6_B': CDS_PINID='CA6_B';
NET_NAME
'M_F_CPU1_SB_CB<0>'
 '@T6G_MB_LIB.T6G(SCH_1):M_F_CPU1_SB_CB'<0>:
 C_SIGNAL='@t6g_mb_lib.t6g(sch_1):m_f_cpu1_sb_cb(0)';
NODE_NAME     U26 BY67
 '@T6G_MB_LIB.T6G(SCH_1):PAGE42_I159@PURE_QUANTA.GENOA_SP5(CHIPS)':
 'MFB_CHECK0': CDS_PINID='MFB_CHECK0';
NODE_NAME     J33 96
 '@T6G_MB_LIB.T6G(SCH_1):PAGE102_I22@PURE_QUANTA.SCONN288_DDR506112002KQ(CHIPS)':
 'CB0_B': CDS_PINID='CB0_B';
NET_NAME
'M_F_CPU1_SB_CB<1>'
 '@T6G_MB_LIB.T6G(SCH_1):M_F_CPU1_SB_CB'<1>:
 C_SIGNAL='@t6g_mb_lib.t6g(sch_1):m_f_cpu1_sb_cb(1)';
NODE_NAME     U26 CA66
 '@T6G_MB_LIB.T6G(SCH_1):PAGE42_I159@PURE_QUANTA.GENOA_SP5(CHIPS)':
 'MFB_CHECK1': CDS_PINID='MFB_CHECK1';
NODE_NAME     J33 98
 '@T6G_MB_LIB.T6G(SCH_1):PAGE102_I22@PURE_QUANTA.SCONN288_DDR506112002KQ(CHIPS)':
 'CB1_B': CDS_PINID='CB1_B';
NET_NAME
'M_F_CPU1_SB_CB<2>'
 '@T6G_MB_LIB.T6G(SCH_1):M_F_CPU1_SB_CB'<2>:
 C_SIGNAL='@t6g_mb_lib.t6g(sch_1):m_f_cpu1_sb_cb(2)';
NODE_NAME     U26 CA67
 '@T6G_MB_LIB.T6G(SCH_1):PAGE42_I159@PURE_QUANTA.GENOA_SP5(CHIPS)':
 'MFB_CHECK2': CDS_PINID='MFB_CHECK2';
NODE_NAME     J33 241
 '@T6G_MB_LIB.T6G(SCH_1):PAGE102_I22@PURE_QUANTA.SCONN288_DDR506112002KQ(CHIPS)':
 'CB2_B': CDS_PINID='CB2_B';
NET_NAME
'M_F_CPU1_SB_CB<3>'
 '@T6G_MB_LIB.T6G(SCH_1):M_F_CPU1_SB_CB'<3>:
 C_SIGNAL='@t6g_mb_lib.t6g(sch_1):m_f_cpu1_sb_cb(3)';
NODE_NAME     U26 CB65
 '@T6G_MB_LIB.T6G(SCH_1):PAGE42_I159@PURE_QUANTA.GENOA_SP5(CHIPS)':
 'MFB_CHECK3': CDS_PINID='MFB_CHECK3';
NODE_NAME     J33 243
 '@T6G_MB_LIB.T6G(SCH_1):PAGE102_I22@PURE_QUANTA.SCONN288_DDR506112002KQ(CHIPS)':
 'CB3_B': CDS_PINID='CB3_B';
NET_NAME
'M_F_CPU1_SB_CB<4>'
 '@T6G_MB_LIB.T6G(SCH_1):M_F_CPU1_SB_CB'<4>:
 C_SIGNAL='@t6g_mb_lib.t6g(sch_1):m_f_cpu1_sb_cb(4)';
NODE_NAME     U26 BT67
 '@T6G_MB_LIB.T6G(SCH_1):PAGE42_I159@PURE_QUANTA.GENOA_SP5(CHIPS)':
 'MFB_CHECK4': CDS_PINID='MFB_CHECK4';
NODE_NAME     J33 89
 '@T6G_MB_LIB.T6G(SCH_1):PAGE102_I22@PURE_QUANTA.SCONN288_DDR506112002KQ(CHIPS)':
 'CB4_B': CDS_PINID='CB4_B';
NET_NAME
'M_F_CPU1_SB_CB<5>'
 '@T6G_MB_LIB.T6G(SCH_1):M_F_CPU1_SB_CB'<5>:
 C_SIGNAL='@t6g_mb_lib.t6g(sch_1):m_f_cpu1_sb_cb(5)';
NODE_NAME     U26 BU66
 '@T6G_MB_LIB.T6G(SCH_1):PAGE42_I159@PURE_QUANTA.GENOA_SP5(CHIPS)':
 'MFB_CHECK5': CDS_PINID='MFB_CHECK5';
NODE_NAME     J33 91
 '@T6G_MB_LIB.T6G(SCH_1):PAGE102_I22@PURE_QUANTA.SCONN288_DDR506112002KQ(CHIPS)':
 'CB5_B': CDS_PINID='CB5_B';
NET_NAME
'M_F_CPU1_SB_CB<6>'
 '@T6G_MB_LIB.T6G(SCH_1):M_F_CPU1_SB_CB'<6>:
 C_SIGNAL='@t6g_mb_lib.t6g(sch_1):m_f_cpu1_sb_cb(6)';
NODE_NAME     U26 BU67
 '@T6G_MB_LIB.T6G(SCH_1):PAGE42_I159@PURE_QUANTA.GENOA_SP5(CHIPS)':
 'MFB_CHECK6': CDS_PINID='MFB_CHECK6';
NODE_NAME     J33 234
 '@T6G_MB_LIB.T6G(SCH_1):PAGE102_I22@PURE_QUANTA.SCONN288_DDR506112002KQ(CHIPS)':
 'CB6_B': CDS_PINID='CB6_B';
NET_NAME
'M_F_CPU1_SB_CB<7>'
 '@T6G_MB_LIB.T6G(SCH_1):M_F_CPU1_SB_CB'<7>:
 C_SIGNAL='@t6g_mb_lib.t6g(sch_1):m_f_cpu1_sb_cb(7)';
NODE_NAME     U26 BV65
 '@T6G_MB_LIB.T6G(SCH_1):PAGE42_I159@PURE_QUANTA.GENOA_SP5(CHIPS)':
 'MFB_CHECK7': CDS_PINID='MFB_CHECK7';
NODE_NAME     J33 236
 '@T6G_MB_LIB.T6G(SCH_1):PAGE102_I22@PURE_QUANTA.SCONN288_DDR506112002KQ(CHIPS)':
 'CB7_B': CDS_PINID='CB7_B';
NET_NAME
'M_F_CPU1_SB_CS_N<0>'
 '@T6G_MB_LIB.T6G(SCH_1):M_F_CPU1_SB_CS_N'<0>:
 C_SIGNAL='@t6g_mb_lib.t6g(sch_1):m_f_cpu1_sb_cs_n(0)';
NODE_NAME     U26 BM65
 '@T6G_MB_LIB.T6G(SCH_1):PAGE42_I159@PURE_QUANTA.GENOA_SP5(CHIPS)':
 'MFB0_CS_L0': CDS_PINID='MFB0_CS_L0';
NODE_NAME     J33 84
 '@T6G_MB_LIB.T6G(SCH_1):PAGE102_I22@PURE_QUANTA.SCONN288_DDR506112002KQ(CHIPS)':
 'CS0_B_N': CDS_PINID='CS0_B_N';
NET_NAME
'M_F_CPU1_SB_CS_N<1>'
 '@T6G_MB_LIB.T6G(SCH_1):M_F_CPU1_SB_CS_N'<1>:
 C_SIGNAL='@t6g_mb_lib.t6g(sch_1):m_f_cpu1_sb_cs_n(1)';
NODE_NAME     U26 BN67
 '@T6G_MB_LIB.T6G(SCH_1):PAGE42_I159@PURE_QUANTA.GENOA_SP5(CHIPS)':
 'MFB0_CS_L1': CDS_PINID='MFB0_CS_L1';
NODE_NAME     J33 229
 '@T6G_MB_LIB.T6G(SCH_1):PAGE102_I22@PURE_QUANTA.SCONN288_DDR506112002KQ(CHIPS)':
 'CS1_B_N': CDS_PINID='CS1_B_N';
NET_NAME
'M_F_CPU1_SB_DQ<0>'
 '@T6G_MB_LIB.T6G(SCH_1):M_F_CPU1_SB_DQ'<0>:
 C_SIGNAL='@t6g_mb_lib.t6g(sch_1):m_f_cpu1_sb_dq(0)';
NODE_NAME     U26 CB67
 '@T6G_MB_LIB.T6G(SCH_1):PAGE42_I159@PURE_QUANTA.GENOA_SP5(CHIPS)':
 'MFB_DATA0': CDS_PINID='MFB_DATA0';
NODE_NAME     J33 100
 '@T6G_MB_LIB.T6G(SCH_1):PAGE102_I22@PURE_QUANTA.SCONN288_DDR506112002KQ(CHIPS)':
 'DQ0_B': CDS_PINID='DQ0_B';
NET_NAME
'M_F_CPU1_SB_DQ<10>'
 '@T6G_MB_LIB.T6G(SCH_1):M_F_CPU1_SB_DQ'<10>:
 C_SIGNAL='@t6g_mb_lib.t6g(sch_1):m_f_cpu1_sb_dq(10)';
NODE_NAME     U26 CJ67
 '@T6G_MB_LIB.T6G(SCH_1):PAGE42_I159@PURE_QUANTA.GENOA_SP5(CHIPS)':
 'MFB_DATA10': CDS_PINID='MFB_DATA10';
NODE_NAME     J33 256
 '@T6G_MB_LIB.T6G(SCH_1):PAGE102_I22@PURE_QUANTA.SCONN288_DDR506112002KQ(CHIPS)':
 'DQ10_B': CDS_PINID='DQ10_B';
NET_NAME
'M_F_CPU1_SB_DQ<11>'
 '@T6G_MB_LIB.T6G(SCH_1):M_F_CPU1_SB_DQ'<11>:
 C_SIGNAL='@t6g_mb_lib.t6g(sch_1):m_f_cpu1_sb_dq(11)';
NODE_NAME     U26 CK65
 '@T6G_MB_LIB.T6G(SCH_1):PAGE42_I159@PURE_QUANTA.GENOA_SP5(CHIPS)':
 'MFB_DATA11': CDS_PINID='MFB_DATA11';
NODE_NAME     J33 258
 '@T6G_MB_LIB.T6G(SCH_1):PAGE102_I22@PURE_QUANTA.SCONN288_DDR506112002KQ(CHIPS)':
 'DQ11_B': CDS_PINID='DQ11_B';
NET_NAME
'M_F_CPU1_SB_DQ<12>'
 '@T6G_MB_LIB.T6G(SCH_1):M_F_CPU1_SB_DQ'<12>:
 C_SIGNAL='@t6g_mb_lib.t6g(sch_1):m_f_cpu1_sb_dq(12)';
NODE_NAME     U26 CM67
 '@T6G_MB_LIB.T6G(SCH_1):PAGE42_I159@PURE_QUANTA.GENOA_SP5(CHIPS)':
 'MFB_DATA12': CDS_PINID='MFB_DATA12';
NODE_NAME     J33 118
 '@T6G_MB_LIB.T6G(SCH_1):PAGE102_I22@PURE_QUANTA.SCONN288_DDR506112002KQ(CHIPS)':
 'DQ12_B': CDS_PINID='DQ12_B';
NET_NAME
'M_F_CPU1_SB_DQ<13>'
 '@T6G_MB_LIB.T6G(SCH_1):M_F_CPU1_SB_DQ'<13>:
 C_SIGNAL='@t6g_mb_lib.t6g(sch_1):m_f_cpu1_sb_dq(13)';
NODE_NAME     U26 CN66
 '@T6G_MB_LIB.T6G(SCH_1):PAGE42_I159@PURE_QUANTA.GENOA_SP5(CHIPS)':
 'MFB_DATA13': CDS_PINID='MFB_DATA13';
NODE_NAME     J33 120
 '@T6G_MB_LIB.T6G(SCH_1):PAGE102_I22@PURE_QUANTA.SCONN288_DDR506112002KQ(CHIPS)':
 'DQ13_B': CDS_PINID='DQ13_B';
NET_NAME
'M_F_CPU1_SB_DQ<14>'
 '@T6G_MB_LIB.T6G(SCH_1):M_F_CPU1_SB_DQ'<14>:
 C_SIGNAL='@t6g_mb_lib.t6g(sch_1):m_f_cpu1_sb_dq(14)';
NODE_NAME     U26 CN67
 '@T6G_MB_LIB.T6G(SCH_1):PAGE42_I159@PURE_QUANTA.GENOA_SP5(CHIPS)':
 'MFB_DATA14': CDS_PINID='MFB_DATA14';
NODE_NAME     J33 263
 '@T6G_MB_LIB.T6G(SCH_1):PAGE102_I22@PURE_QUANTA.SCONN288_DDR506112002KQ(CHIPS)':
 'DQ14_B': CDS_PINID='DQ14_B';
NET_NAME
'M_F_CPU1_SB_DQ<15>'
 '@T6G_MB_LIB.T6G(SCH_1):M_F_CPU1_SB_DQ'<15>:
 C_SIGNAL='@t6g_mb_lib.t6g(sch_1):m_f_cpu1_sb_dq(15)';
NODE_NAME     U26 CP65
 '@T6G_MB_LIB.T6G(SCH_1):PAGE42_I159@PURE_QUANTA.GENOA_SP5(CHIPS)':
 'MFB_DATA15': CDS_PINID='MFB_DATA15';
NODE_NAME     J33 265
 '@T6G_MB_LIB.T6G(SCH_1):PAGE102_I22@PURE_QUANTA.SCONN288_DDR506112002KQ(CHIPS)':
 'DQ15_B': CDS_PINID='DQ15_B';
NET_NAME
'M_F_CPU1_SB_DQ<16>'
 '@T6G_MB_LIB.T6G(SCH_1):M_F_CPU1_SB_DQ'<16>:
 C_SIGNAL='@t6g_mb_lib.t6g(sch_1):m_f_cpu1_sb_dq(16)';
NODE_NAME     U26 CP67
 '@T6G_MB_LIB.T6G(SCH_1):PAGE42_I159@PURE_QUANTA.GENOA_SP5(CHIPS)':
 'MFB_DATA16': CDS_PINID='MFB_DATA16';
NODE_NAME     J33 122
 '@T6G_MB_LIB.T6G(SCH_1):PAGE102_I22@PURE_QUANTA.SCONN288_DDR506112002KQ(CHIPS)':
 'DQ16_B': CDS_PINID='DQ16_B';
NET_NAME
'M_F_CPU1_SB_DQ<17>'
 '@T6G_MB_LIB.T6G(SCH_1):M_F_CPU1_SB_DQ'<17>:
 C_SIGNAL='@t6g_mb_lib.t6g(sch_1):m_f_cpu1_sb_dq(17)';
NODE_NAME     U26 CR66
 '@T6G_MB_LIB.T6G(SCH_1):PAGE42_I159@PURE_QUANTA.GENOA_SP5(CHIPS)':
 'MFB_DATA17': CDS_PINID='MFB_DATA17';
NODE_NAME     J33 124
 '@T6G_MB_LIB.T6G(SCH_1):PAGE102_I22@PURE_QUANTA.SCONN288_DDR506112002KQ(CHIPS)':
 'DQ17_B': CDS_PINID='DQ17_B';
NET_NAME
'M_F_CPU1_SB_DQ<18>'
 '@T6G_MB_LIB.T6G(SCH_1):M_F_CPU1_SB_DQ'<18>:
 C_SIGNAL='@t6g_mb_lib.t6g(sch_1):m_f_cpu1_sb_dq(18)';
NODE_NAME     U26 CR67
 '@T6G_MB_LIB.T6G(SCH_1):PAGE42_I159@PURE_QUANTA.GENOA_SP5(CHIPS)':
 'MFB_DATA18': CDS_PINID='MFB_DATA18';
NODE_NAME     J33 267
 '@T6G_MB_LIB.T6G(SCH_1):PAGE102_I22@PURE_QUANTA.SCONN288_DDR506112002KQ(CHIPS)':
 'DQ18_B': CDS_PINID='DQ18_B';
NET_NAME
'M_F_CPU1_SB_DQ<19>'
 '@T6G_MB_LIB.T6G(SCH_1):M_F_CPU1_SB_DQ'<19>:
 C_SIGNAL='@t6g_mb_lib.t6g(sch_1):m_f_cpu1_sb_dq(19)';
NODE_NAME     U26 CT65
 '@T6G_MB_LIB.T6G(SCH_1):PAGE42_I159@PURE_QUANTA.GENOA_SP5(CHIPS)':
 'MFB_DATA19': CDS_PINID='MFB_DATA19';
NODE_NAME     J33 269
 '@T6G_MB_LIB.T6G(SCH_1):PAGE102_I22@PURE_QUANTA.SCONN288_DDR506112002KQ(CHIPS)':
 'DQ19_B': CDS_PINID='DQ19_B';
NET_NAME
'M_F_CPU1_SB_DQ<1>'
 '@T6G_MB_LIB.T6G(SCH_1):M_F_CPU1_SB_DQ'<1>:
 C_SIGNAL='@t6g_mb_lib.t6g(sch_1):m_f_cpu1_sb_dq(1)';
NODE_NAME     U26 CC66
 '@T6G_MB_LIB.T6G(SCH_1):PAGE42_I159@PURE_QUANTA.GENOA_SP5(CHIPS)':
 'MFB_DATA1': CDS_PINID='MFB_DATA1';
NODE_NAME     J33 102
 '@T6G_MB_LIB.T6G(SCH_1):PAGE102_I22@PURE_QUANTA.SCONN288_DDR506112002KQ(CHIPS)':
 'DQ1_B': CDS_PINID='DQ1_B';
NET_NAME
'M_F_CPU1_SB_DQ<20>'
 '@T6G_MB_LIB.T6G(SCH_1):M_F_CPU1_SB_DQ'<20>:
 C_SIGNAL='@t6g_mb_lib.t6g(sch_1):m_f_cpu1_sb_dq(20)';
NODE_NAME     U26 CV67
 '@T6G_MB_LIB.T6G(SCH_1):PAGE42_I159@PURE_QUANTA.GENOA_SP5(CHIPS)':
 'MFB_DATA20': CDS_PINID='MFB_DATA20';
NODE_NAME     J33 129
 '@T6G_MB_LIB.T6G(SCH_1):PAGE102_I22@PURE_QUANTA.SCONN288_DDR506112002KQ(CHIPS)':
 'DQ20_B': CDS_PINID='DQ20_B';
NET_NAME
'M_F_CPU1_SB_DQ<21>'
 '@T6G_MB_LIB.T6G(SCH_1):M_F_CPU1_SB_DQ'<21>:
 C_SIGNAL='@t6g_mb_lib.t6g(sch_1):m_f_cpu1_sb_dq(21)';
NODE_NAME     U26 CW66
 '@T6G_MB_LIB.T6G(SCH_1):PAGE42_I159@PURE_QUANTA.GENOA_SP5(CHIPS)':
 'MFB_DATA21': CDS_PINID='MFB_DATA21';
NODE_NAME     J33 131
 '@T6G_MB_LIB.T6G(SCH_1):PAGE102_I22@PURE_QUANTA.SCONN288_DDR506112002KQ(CHIPS)':
 'DQ21_B': CDS_PINID='DQ21_B';
NET_NAME
'M_F_CPU1_SB_DQ<22>'
 '@T6G_MB_LIB.T6G(SCH_1):M_F_CPU1_SB_DQ'<22>:
 C_SIGNAL='@t6g_mb_lib.t6g(sch_1):m_f_cpu1_sb_dq(22)';
NODE_NAME     U26 CW67
 '@T6G_MB_LIB.T6G(SCH_1):PAGE42_I159@PURE_QUANTA.GENOA_SP5(CHIPS)':
 'MFB_DATA22': CDS_PINID='MFB_DATA22';
NODE_NAME     J33 274
 '@T6G_MB_LIB.T6G(SCH_1):PAGE102_I22@PURE_QUANTA.SCONN288_DDR506112002KQ(CHIPS)':
 'DQ22_B': CDS_PINID='DQ22_B';
NET_NAME
'M_F_CPU1_SB_DQ<23>'
 '@T6G_MB_LIB.T6G(SCH_1):M_F_CPU1_SB_DQ'<23>:
 C_SIGNAL='@t6g_mb_lib.t6g(sch_1):m_f_cpu1_sb_dq(23)';
NODE_NAME     U26 CY65
 '@T6G_MB_LIB.T6G(SCH_1):PAGE42_I159@PURE_QUANTA.GENOA_SP5(CHIPS)':
 'MFB_DATA23': CDS_PINID='MFB_DATA23';
NODE_NAME     J33 276
 '@T6G_MB_LIB.T6G(SCH_1):PAGE102_I22@PURE_QUANTA.SCONN288_DDR506112002KQ(CHIPS)':
 'DQ23_B': CDS_PINID='DQ23_B';
NET_NAME
'M_F_CPU1_SB_DQ<24>'
 '@T6G_MB_LIB.T6G(SCH_1):M_F_CPU1_SB_DQ'<24>:
 C_SIGNAL='@t6g_mb_lib.t6g(sch_1):m_f_cpu1_sb_dq(24)';
NODE_NAME     U26 CY67
 '@T6G_MB_LIB.T6G(SCH_1):PAGE42_I159@PURE_QUANTA.GENOA_SP5(CHIPS)':
 'MFB_DATA24': CDS_PINID='MFB_DATA24';
NODE_NAME     J33 133
 '@T6G_MB_LIB.T6G(SCH_1):PAGE102_I22@PURE_QUANTA.SCONN288_DDR506112002KQ(CHIPS)':
 'DQ24_B': CDS_PINID='DQ24_B';
NET_NAME
'M_F_CPU1_SB_DQ<25>'
 '@T6G_MB_LIB.T6G(SCH_1):M_F_CPU1_SB_DQ'<25>:
 C_SIGNAL='@t6g_mb_lib.t6g(sch_1):m_f_cpu1_sb_dq(25)';
NODE_NAME     U26 DA66
 '@T6G_MB_LIB.T6G(SCH_1):PAGE42_I159@PURE_QUANTA.GENOA_SP5(CHIPS)':
 'MFB_DATA25': CDS_PINID='MFB_DATA25';
NODE_NAME     J33 135
 '@T6G_MB_LIB.T6G(SCH_1):PAGE102_I22@PURE_QUANTA.SCONN288_DDR506112002KQ(CHIPS)':
 'DQ25_B': CDS_PINID='DQ25_B';
NET_NAME
'M_F_CPU1_SB_DQ<26>'
 '@T6G_MB_LIB.T6G(SCH_1):M_F_CPU1_SB_DQ'<26>:
 C_SIGNAL='@t6g_mb_lib.t6g(sch_1):m_f_cpu1_sb_dq(26)';
NODE_NAME     U26 DA67
 '@T6G_MB_LIB.T6G(SCH_1):PAGE42_I159@PURE_QUANTA.GENOA_SP5(CHIPS)':
 'MFB_DATA26': CDS_PINID='MFB_DATA26';
NODE_NAME     J33 278
 '@T6G_MB_LIB.T6G(SCH_1):PAGE102_I22@PURE_QUANTA.SCONN288_DDR506112002KQ(CHIPS)':
 'DQ26_B': CDS_PINID='DQ26_B';
NET_NAME
'M_F_CPU1_SB_DQ<27>'
 '@T6G_MB_LIB.T6G(SCH_1):M_F_CPU1_SB_DQ'<27>:
 C_SIGNAL='@t6g_mb_lib.t6g(sch_1):m_f_cpu1_sb_dq(27)';
NODE_NAME     U26 DB65
 '@T6G_MB_LIB.T6G(SCH_1):PAGE42_I159@PURE_QUANTA.GENOA_SP5(CHIPS)':
 'MFB_DATA27': CDS_PINID='MFB_DATA27';
NODE_NAME     J33 280
 '@T6G_MB_LIB.T6G(SCH_1):PAGE102_I22@PURE_QUANTA.SCONN288_DDR506112002KQ(CHIPS)':
 'DQ27_B': CDS_PINID='DQ27_B';
NET_NAME
'M_F_CPU1_SB_DQ<28>'
 '@T6G_MB_LIB.T6G(SCH_1):M_F_CPU1_SB_DQ'<28>:
 C_SIGNAL='@t6g_mb_lib.t6g(sch_1):m_f_cpu1_sb_dq(28)';
NODE_NAME     U26 DD67
 '@T6G_MB_LIB.T6G(SCH_1):PAGE42_I159@PURE_QUANTA.GENOA_SP5(CHIPS)':
 'MFB_DATA28': CDS_PINID='MFB_DATA28';
NODE_NAME     J33 140
 '@T6G_MB_LIB.T6G(SCH_1):PAGE102_I22@PURE_QUANTA.SCONN288_DDR506112002KQ(CHIPS)':
 'DQ28_B': CDS_PINID='DQ28_B';
NET_NAME
'M_F_CPU1_SB_DQ<29>'
 '@T6G_MB_LIB.T6G(SCH_1):M_F_CPU1_SB_DQ'<29>:
 C_SIGNAL='@t6g_mb_lib.t6g(sch_1):m_f_cpu1_sb_dq(29)';
NODE_NAME     U26 DE66
 '@T6G_MB_LIB.T6G(SCH_1):PAGE42_I159@PURE_QUANTA.GENOA_SP5(CHIPS)':
 'MFB_DATA29': CDS_PINID='MFB_DATA29';
NODE_NAME     J33 142
 '@T6G_MB_LIB.T6G(SCH_1):PAGE102_I22@PURE_QUANTA.SCONN288_DDR506112002KQ(CHIPS)':
 'DQ29_B': CDS_PINID='DQ29_B';
NET_NAME
'M_F_CPU1_SB_DQ<2>'
 '@T6G_MB_LIB.T6G(SCH_1):M_F_CPU1_SB_DQ'<2>:
 C_SIGNAL='@t6g_mb_lib.t6g(sch_1):m_f_cpu1_sb_dq(2)';
NODE_NAME     U26 CC67
 '@T6G_MB_LIB.T6G(SCH_1):PAGE42_I159@PURE_QUANTA.GENOA_SP5(CHIPS)':
 'MFB_DATA2': CDS_PINID='MFB_DATA2';
NODE_NAME     J33 245
 '@T6G_MB_LIB.T6G(SCH_1):PAGE102_I22@PURE_QUANTA.SCONN288_DDR506112002KQ(CHIPS)':
 'DQ2_B': CDS_PINID='DQ2_B';
NET_NAME
'M_F_CPU1_SB_DQ<30>'
 '@T6G_MB_LIB.T6G(SCH_1):M_F_CPU1_SB_DQ'<30>:
 C_SIGNAL='@t6g_mb_lib.t6g(sch_1):m_f_cpu1_sb_dq(30)';
NODE_NAME     U26 DE67
 '@T6G_MB_LIB.T6G(SCH_1):PAGE42_I159@PURE_QUANTA.GENOA_SP5(CHIPS)':
 'MFB_DATA30': CDS_PINID='MFB_DATA30';
NODE_NAME     J33 285
 '@T6G_MB_LIB.T6G(SCH_1):PAGE102_I22@PURE_QUANTA.SCONN288_DDR506112002KQ(CHIPS)':
 'DQ30_B': CDS_PINID='DQ30_B';
NET_NAME
'M_F_CPU1_SB_DQ<31>'
 '@T6G_MB_LIB.T6G(SCH_1):M_F_CPU1_SB_DQ'<31>:
 C_SIGNAL='@t6g_mb_lib.t6g(sch_1):m_f_cpu1_sb_dq(31)';
NODE_NAME     U26 DF67
 '@T6G_MB_LIB.T6G(SCH_1):PAGE42_I159@PURE_QUANTA.GENOA_SP5(CHIPS)':
 'MFB_DATA31': CDS_PINID='MFB_DATA31';
NODE_NAME     J33 287
 '@T6G_MB_LIB.T6G(SCH_1):PAGE102_I22@PURE_QUANTA.SCONN288_DDR506112002KQ(CHIPS)':
 'DQ31_B': CDS_PINID='DQ31_B';
NET_NAME
'M_F_CPU1_SB_DQ<3>'
 '@T6G_MB_LIB.T6G(SCH_1):M_F_CPU1_SB_DQ'<3>:
 C_SIGNAL='@t6g_mb_lib.t6g(sch_1):m_f_cpu1_sb_dq(3)';
NODE_NAME     U26 CD65
 '@T6G_MB_LIB.T6G(SCH_1):PAGE42_I159@PURE_QUANTA.GENOA_SP5(CHIPS)':
 'MFB_DATA3': CDS_PINID='MFB_DATA3';
NODE_NAME     J33 247
 '@T6G_MB_LIB.T6G(SCH_1):PAGE102_I22@PURE_QUANTA.SCONN288_DDR506112002KQ(CHIPS)':
 'DQ3_B': CDS_PINID='DQ3_B';
NET_NAME
'M_F_CPU1_SB_DQ<4>'
 '@T6G_MB_LIB.T6G(SCH_1):M_F_CPU1_SB_DQ'<4>:
 C_SIGNAL='@t6g_mb_lib.t6g(sch_1):m_f_cpu1_sb_dq(4)';
NODE_NAME     U26 CF67
 '@T6G_MB_LIB.T6G(SCH_1):PAGE42_I159@PURE_QUANTA.GENOA_SP5(CHIPS)':
 'MFB_DATA4': CDS_PINID='MFB_DATA4';
NODE_NAME     J33 107
 '@T6G_MB_LIB.T6G(SCH_1):PAGE102_I22@PURE_QUANTA.SCONN288_DDR506112002KQ(CHIPS)':
 'DQ4_B': CDS_PINID='DQ4_B';
NET_NAME
'M_F_CPU1_SB_DQ<5>'
 '@T6G_MB_LIB.T6G(SCH_1):M_F_CPU1_SB_DQ'<5>:
 C_SIGNAL='@t6g_mb_lib.t6g(sch_1):m_f_cpu1_sb_dq(5)';
NODE_NAME     U26 CG66
 '@T6G_MB_LIB.T6G(SCH_1):PAGE42_I159@PURE_QUANTA.GENOA_SP5(CHIPS)':
 'MFB_DATA5': CDS_PINID='MFB_DATA5';
NODE_NAME     J33 109
 '@T6G_MB_LIB.T6G(SCH_1):PAGE102_I22@PURE_QUANTA.SCONN288_DDR506112002KQ(CHIPS)':
 'DQ5_B': CDS_PINID='DQ5_B';
NET_NAME
'M_F_CPU1_SB_DQ<6>'
 '@T6G_MB_LIB.T6G(SCH_1):M_F_CPU1_SB_DQ'<6>:
 C_SIGNAL='@t6g_mb_lib.t6g(sch_1):m_f_cpu1_sb_dq(6)';
NODE_NAME     U26 CG67
 '@T6G_MB_LIB.T6G(SCH_1):PAGE42_I159@PURE_QUANTA.GENOA_SP5(CHIPS)':
 'MFB_DATA6': CDS_PINID='MFB_DATA6';
NODE_NAME     J33 252
 '@T6G_MB_LIB.T6G(SCH_1):PAGE102_I22@PURE_QUANTA.SCONN288_DDR506112002KQ(CHIPS)':
 'DQ6_B': CDS_PINID='DQ6_B';
NET_NAME
'M_F_CPU1_SB_DQ<7>'
 '@T6G_MB_LIB.T6G(SCH_1):M_F_CPU1_SB_DQ'<7>:
 C_SIGNAL='@t6g_mb_lib.t6g(sch_1):m_f_cpu1_sb_dq(7)';
NODE_NAME     U26 CH65
 '@T6G_MB_LIB.T6G(SCH_1):PAGE42_I159@PURE_QUANTA.GENOA_SP5(CHIPS)':
 'MFB_DATA7': CDS_PINID='MFB_DATA7';
NODE_NAME     J33 254
 '@T6G_MB_LIB.T6G(SCH_1):PAGE102_I22@PURE_QUANTA.SCONN288_DDR506112002KQ(CHIPS)':
 'DQ7_B': CDS_PINID='DQ7_B';
NET_NAME
'M_F_CPU1_SB_DQ<8>'
 '@T6G_MB_LIB.T6G(SCH_1):M_F_CPU1_SB_DQ'<8>:
 C_SIGNAL='@t6g_mb_lib.t6g(sch_1):m_f_cpu1_sb_dq(8)';
NODE_NAME     U26 CH67
 '@T6G_MB_LIB.T6G(SCH_1):PAGE42_I159@PURE_QUANTA.GENOA_SP5(CHIPS)':
 'MFB_DATA8': CDS_PINID='MFB_DATA8';
NODE_NAME     J33 111
 '@T6G_MB_LIB.T6G(SCH_1):PAGE102_I22@PURE_QUANTA.SCONN288_DDR506112002KQ(CHIPS)':
 'DQ8_B': CDS_PINID='DQ8_B';
NET_NAME
'M_F_CPU1_SB_DQ<9>'
 '@T6G_MB_LIB.T6G(SCH_1):M_F_CPU1_SB_DQ'<9>:
 C_SIGNAL='@t6g_mb_lib.t6g(sch_1):m_f_cpu1_sb_dq(9)';
NODE_NAME     U26 CJ66
 '@T6G_MB_LIB.T6G(SCH_1):PAGE42_I159@PURE_QUANTA.GENOA_SP5(CHIPS)':
 'MFB_DATA9': CDS_PINID='MFB_DATA9';
NODE_NAME     J33 113
 '@T6G_MB_LIB.T6G(SCH_1):PAGE102_I22@PURE_QUANTA.SCONN288_DDR506112002KQ(CHIPS)':
 'DQ9_B': CDS_PINID='DQ9_B';
NET_NAME
'M_F_CPU1_SB_DQS_DN<0>'
 '@T6G_MB_LIB.T6G(SCH_1):M_F_CPU1_SB_DQS_DN'<0>:
 C_SIGNAL='@t6g_mb_lib.t6g(sch_1):m_f_cpu1_sb_dqs_dn(0)';
NODE_NAME     U26 CE67
 '@T6G_MB_LIB.T6G(SCH_1):PAGE42_I159@PURE_QUANTA.GENOA_SP5(CHIPS)':
 'MFB_DQS_L0': CDS_PINID='MFB_DQS_L0';
NODE_NAME     J33 105
 '@T6G_MB_LIB.T6G(SCH_1):PAGE102_I236@PURE_QUANTA.SCONN288_DDR506112002KQ(CHIPS)':
 'DQS0_B_C': CDS_PINID='DQS0_B_C';
NET_NAME
'M_F_CPU1_SB_DQS_DN<1>'
 '@T6G_MB_LIB.T6G(SCH_1):M_F_CPU1_SB_DQS_DN'<1>:
 C_SIGNAL='@t6g_mb_lib.t6g(sch_1):m_f_cpu1_sb_dqs_dn(1)';
NODE_NAME     U26 CL67
 '@T6G_MB_LIB.T6G(SCH_1):PAGE42_I159@PURE_QUANTA.GENOA_SP5(CHIPS)':
 'MFB_DQS_L1': CDS_PINID='MFB_DQS_L1';
NODE_NAME     J33 116
 '@T6G_MB_LIB.T6G(SCH_1):PAGE102_I236@PURE_QUANTA.SCONN288_DDR506112002KQ(CHIPS)':
 'DQS1_B_C': CDS_PINID='DQS1_B_C';
NET_NAME
'M_F_CPU1_SB_DQS_DN<2>'
 '@T6G_MB_LIB.T6G(SCH_1):M_F_CPU1_SB_DQS_DN'<2>:
 C_SIGNAL='@t6g_mb_lib.t6g(sch_1):m_f_cpu1_sb_dqs_dn(2)';
NODE_NAME     U26 CU67
 '@T6G_MB_LIB.T6G(SCH_1):PAGE42_I159@PURE_QUANTA.GENOA_SP5(CHIPS)':
 'MFB_DQS_L2': CDS_PINID='MFB_DQS_L2';
NODE_NAME     J33 127
 '@T6G_MB_LIB.T6G(SCH_1):PAGE102_I236@PURE_QUANTA.SCONN288_DDR506112002KQ(CHIPS)':
 'DQS2_B_C': CDS_PINID='DQS2_B_C';
NET_NAME
'M_F_CPU1_SB_DQS_DN<3>'
 '@T6G_MB_LIB.T6G(SCH_1):M_F_CPU1_SB_DQS_DN'<3>:
 C_SIGNAL='@t6g_mb_lib.t6g(sch_1):m_f_cpu1_sb_dqs_dn(3)';
NODE_NAME     U26 DC67
 '@T6G_MB_LIB.T6G(SCH_1):PAGE42_I159@PURE_QUANTA.GENOA_SP5(CHIPS)':
 'MFB_DQS_L3': CDS_PINID='MFB_DQS_L3';
NODE_NAME     J33 138
 '@T6G_MB_LIB.T6G(SCH_1):PAGE102_I236@PURE_QUANTA.SCONN288_DDR506112002KQ(CHIPS)':
 'DQS3_B_C': CDS_PINID='DQS3_B_C';
NET_NAME
'M_F_CPU1_SB_DQS_DN<4>'
 '@T6G_MB_LIB.T6G(SCH_1):M_F_CPU1_SB_DQS_DN'<4>:
 C_SIGNAL='@t6g_mb_lib.t6g(sch_1):m_f_cpu1_sb_dqs_dn(4)';
NODE_NAME     U26 BW66
 '@T6G_MB_LIB.T6G(SCH_1):PAGE42_I159@PURE_QUANTA.GENOA_SP5(CHIPS)':
 'MFB_DQS_L4': CDS_PINID='MFB_DQS_L4';
NODE_NAME     J33 238
 '@T6G_MB_LIB.T6G(SCH_1):PAGE102_I236@PURE_QUANTA.SCONN288_DDR506112002KQ(CHIPS)':
 'DQS4_B_C': CDS_PINID='DQS4_B_C';
NET_NAME
'M_F_CPU1_SB_DQS_DN<5>'
 '@T6G_MB_LIB.T6G(SCH_1):M_F_CPU1_SB_DQS_DN'<5>:
 C_SIGNAL='@t6g_mb_lib.t6g(sch_1):m_f_cpu1_sb_dqs_dn(5)';
NODE_NAME     U26 CE66
 '@T6G_MB_LIB.T6G(SCH_1):PAGE42_I159@PURE_QUANTA.GENOA_SP5(CHIPS)':
 'MFB_DQS_L5': CDS_PINID='MFB_DQS_L5';
NODE_NAME     J33 249
 '@T6G_MB_LIB.T6G(SCH_1):PAGE102_I236@PURE_QUANTA.SCONN288_DDR506112002KQ(CHIPS)':
 'DQS5_B_C||TDQS5_B_C': CDS_PINID='\dqs5_b_c||tdqs5_b_c\';
NET_NAME
'M_F_CPU1_SB_DQS_DN<6>'
 '@T6G_MB_LIB.T6G(SCH_1):M_F_CPU1_SB_DQS_DN'<6>:
 C_SIGNAL='@t6g_mb_lib.t6g(sch_1):m_f_cpu1_sb_dqs_dn(6)';
NODE_NAME     U26 CL66
 '@T6G_MB_LIB.T6G(SCH_1):PAGE42_I159@PURE_QUANTA.GENOA_SP5(CHIPS)':
 'MFB_DQS_L6': CDS_PINID='MFB_DQS_L6';
NODE_NAME     J33 260
 '@T6G_MB_LIB.T6G(SCH_1):PAGE102_I236@PURE_QUANTA.SCONN288_DDR506112002KQ(CHIPS)':
 'DQS6_B_C||TDQS6_B_C': CDS_PINID='\dqs6_b_c||tdqs6_b_c\';
NET_NAME
'M_F_CPU1_SB_DQS_DN<7>'
 '@T6G_MB_LIB.T6G(SCH_1):M_F_CPU1_SB_DQS_DN'<7>:
 C_SIGNAL='@t6g_mb_lib.t6g(sch_1):m_f_cpu1_sb_dqs_dn(7)';
NODE_NAME     U26 CU66
 '@T6G_MB_LIB.T6G(SCH_1):PAGE42_I159@PURE_QUANTA.GENOA_SP5(CHIPS)':
 'MFB_DQS_L7': CDS_PINID='MFB_DQS_L7';
NODE_NAME     J33 271
 '@T6G_MB_LIB.T6G(SCH_1):PAGE102_I236@PURE_QUANTA.SCONN288_DDR506112002KQ(CHIPS)':
 'DQS7_B_C||TDQS7_B_C': CDS_PINID='\dqs7_b_c||tdqs7_b_c\';
NET_NAME
'M_F_CPU1_SB_DQS_DN<8>'
 '@T6G_MB_LIB.T6G(SCH_1):M_F_CPU1_SB_DQS_DN'<8>:
 C_SIGNAL='@t6g_mb_lib.t6g(sch_1):m_f_cpu1_sb_dqs_dn(8)';
NODE_NAME     U26 DC66
 '@T6G_MB_LIB.T6G(SCH_1):PAGE42_I159@PURE_QUANTA.GENOA_SP5(CHIPS)':
 'MFB_DQS_L8': CDS_PINID='MFB_DQS_L8';
NODE_NAME     J33 282
 '@T6G_MB_LIB.T6G(SCH_1):PAGE102_I236@PURE_QUANTA.SCONN288_DDR506112002KQ(CHIPS)':
 'DQS8_B_C||TDQS8_B_C': CDS_PINID='\dqs8_b_c||tdqs8_b_c\';
NET_NAME
'M_F_CPU1_SB_DQS_DN<9>'
 '@T6G_MB_LIB.T6G(SCH_1):M_F_CPU1_SB_DQS_DN'<9>:
 C_SIGNAL='@t6g_mb_lib.t6g(sch_1):m_f_cpu1_sb_dqs_dn(9)';
NODE_NAME     U26 BW67
 '@T6G_MB_LIB.T6G(SCH_1):PAGE42_I159@PURE_QUANTA.GENOA_SP5(CHIPS)':
 'MFB_DQS_L9': CDS_PINID='MFB_DQS_L9';
NODE_NAME     J33 94
 '@T6G_MB_LIB.T6G(SCH_1):PAGE102_I236@PURE_QUANTA.SCONN288_DDR506112002KQ(CHIPS)':
 'DQS9_B_C||TDQS9_B_C': CDS_PINID='\dqs9_b_c||tdqs9_b_c\';
NET_NAME
'M_F_CPU1_SB_DQS_DP<0>'
 '@T6G_MB_LIB.T6G(SCH_1):M_F_CPU1_SB_DQS_DP'<0>:
 C_SIGNAL='@t6g_mb_lib.t6g(sch_1):m_f_cpu1_sb_dqs_dp(0)';
NODE_NAME     U26 CD67
 '@T6G_MB_LIB.T6G(SCH_1):PAGE42_I159@PURE_QUANTA.GENOA_SP5(CHIPS)':
 'MFB_DQS_H0': CDS_PINID='MFB_DQS_H0';
NODE_NAME     J33 104
 '@T6G_MB_LIB.T6G(SCH_1):PAGE102_I236@PURE_QUANTA.SCONN288_DDR506112002KQ(CHIPS)':
 'DQS0_B_T': CDS_PINID='DQS0_B_T';
NET_NAME
'M_F_CPU1_SB_DQS_DP<1>'
 '@T6G_MB_LIB.T6G(SCH_1):M_F_CPU1_SB_DQS_DP'<1>:
 C_SIGNAL='@t6g_mb_lib.t6g(sch_1):m_f_cpu1_sb_dqs_dp(1)';
NODE_NAME     U26 CK67
 '@T6G_MB_LIB.T6G(SCH_1):PAGE42_I159@PURE_QUANTA.GENOA_SP5(CHIPS)':
 'MFB_DQS_H1': CDS_PINID='MFB_DQS_H1';
NODE_NAME     J33 115
 '@T6G_MB_LIB.T6G(SCH_1):PAGE102_I236@PURE_QUANTA.SCONN288_DDR506112002KQ(CHIPS)':
 'DQS1_B_T': CDS_PINID='DQS1_B_T';
NET_NAME
'M_F_CPU1_SB_DQS_DP<2>'
 '@T6G_MB_LIB.T6G(SCH_1):M_F_CPU1_SB_DQS_DP'<2>:
 C_SIGNAL='@t6g_mb_lib.t6g(sch_1):m_f_cpu1_sb_dqs_dp(2)';
NODE_NAME     U26 CT67
 '@T6G_MB_LIB.T6G(SCH_1):PAGE42_I159@PURE_QUANTA.GENOA_SP5(CHIPS)':
 'MFB_DQS_H2': CDS_PINID='MFB_DQS_H2';
NODE_NAME     J33 126
 '@T6G_MB_LIB.T6G(SCH_1):PAGE102_I236@PURE_QUANTA.SCONN288_DDR506112002KQ(CHIPS)':
 'DQS2_B_T': CDS_PINID='DQS2_B_T';
NET_NAME
'M_F_CPU1_SB_DQS_DP<3>'
 '@T6G_MB_LIB.T6G(SCH_1):M_F_CPU1_SB_DQS_DP'<3>:
 C_SIGNAL='@t6g_mb_lib.t6g(sch_1):m_f_cpu1_sb_dqs_dp(3)';
NODE_NAME     U26 DB67
 '@T6G_MB_LIB.T6G(SCH_1):PAGE42_I159@PURE_QUANTA.GENOA_SP5(CHIPS)':
 'MFB_DQS_H3': CDS_PINID='MFB_DQS_H3';
NODE_NAME     J33 137
 '@T6G_MB_LIB.T6G(SCH_1):PAGE102_I236@PURE_QUANTA.SCONN288_DDR506112002KQ(CHIPS)':
 'DQS3_B_T': CDS_PINID='DQS3_B_T';
NET_NAME
'M_F_CPU1_SB_DQS_DP<4>'
 '@T6G_MB_LIB.T6G(SCH_1):M_F_CPU1_SB_DQS_DP'<4>:
 C_SIGNAL='@t6g_mb_lib.t6g(sch_1):m_f_cpu1_sb_dqs_dp(4)';
NODE_NAME     U26 BY65
 '@T6G_MB_LIB.T6G(SCH_1):PAGE42_I159@PURE_QUANTA.GENOA_SP5(CHIPS)':
 'MFB_DQS_H4': CDS_PINID='MFB_DQS_H4';
NODE_NAME     J33 239
 '@T6G_MB_LIB.T6G(SCH_1):PAGE102_I236@PURE_QUANTA.SCONN288_DDR506112002KQ(CHIPS)':
 'DQS4_B_T': CDS_PINID='DQS4_B_T';
NET_NAME
'M_F_CPU1_SB_DQS_DP<5>'
 '@T6G_MB_LIB.T6G(SCH_1):M_F_CPU1_SB_DQS_DP'<5>:
 C_SIGNAL='@t6g_mb_lib.t6g(sch_1):m_f_cpu1_sb_dqs_dp(5)';
NODE_NAME     U26 CF65
 '@T6G_MB_LIB.T6G(SCH_1):PAGE42_I159@PURE_QUANTA.GENOA_SP5(CHIPS)':
 'MFB_DQS_H5': CDS_PINID='MFB_DQS_H5';
NODE_NAME     J33 250
 '@T6G_MB_LIB.T6G(SCH_1):PAGE102_I236@PURE_QUANTA.SCONN288_DDR506112002KQ(CHIPS)':
 'DQS5_B_T||TDQS5_B_T': CDS_PINID='\dqs5_b_t||tdqs5_b_t\';
NET_NAME
'M_F_CPU1_SB_DQS_DP<6>'
 '@T6G_MB_LIB.T6G(SCH_1):M_F_CPU1_SB_DQS_DP'<6>:
 C_SIGNAL='@t6g_mb_lib.t6g(sch_1):m_f_cpu1_sb_dqs_dp(6)';
NODE_NAME     U26 CM65
 '@T6G_MB_LIB.T6G(SCH_1):PAGE42_I159@PURE_QUANTA.GENOA_SP5(CHIPS)':
 'MFB_DQS_H6': CDS_PINID='MFB_DQS_H6';
NODE_NAME     J33 261
 '@T6G_MB_LIB.T6G(SCH_1):PAGE102_I236@PURE_QUANTA.SCONN288_DDR506112002KQ(CHIPS)':
 'DQS6_B_T||TDQS6_B_T': CDS_PINID='\dqs6_b_t||tdqs6_b_t\';
NET_NAME
'M_F_CPU1_SB_DQS_DP<7>'
 '@T6G_MB_LIB.T6G(SCH_1):M_F_CPU1_SB_DQS_DP'<7>:
 C_SIGNAL='@t6g_mb_lib.t6g(sch_1):m_f_cpu1_sb_dqs_dp(7)';
NODE_NAME     U26 CV65
 '@T6G_MB_LIB.T6G(SCH_1):PAGE42_I159@PURE_QUANTA.GENOA_SP5(CHIPS)':
 'MFB_DQS_H7': CDS_PINID='MFB_DQS_H7';
NODE_NAME     J33 272
 '@T6G_MB_LIB.T6G(SCH_1):PAGE102_I236@PURE_QUANTA.SCONN288_DDR506112002KQ(CHIPS)':
 'DQS7_B_T||TDQS7_B_T': CDS_PINID='\dqs7_b_t||tdqs7_b_t\';
NET_NAME
'M_F_CPU1_SB_DQS_DP<8>'
 '@T6G_MB_LIB.T6G(SCH_1):M_F_CPU1_SB_DQS_DP'<8>:
 C_SIGNAL='@t6g_mb_lib.t6g(sch_1):m_f_cpu1_sb_dqs_dp(8)';
NODE_NAME     U26 DD65
 '@T6G_MB_LIB.T6G(SCH_1):PAGE42_I159@PURE_QUANTA.GENOA_SP5(CHIPS)':
 'MFB_DQS_H8': CDS_PINID='MFB_DQS_H8';
NODE_NAME     J33 283
 '@T6G_MB_LIB.T6G(SCH_1):PAGE102_I236@PURE_QUANTA.SCONN288_DDR506112002KQ(CHIPS)':
 'DQS8_B_T||TDQS8_B_T': CDS_PINID='\dqs8_b_t||tdqs8_b_t\';
NET_NAME
'M_F_CPU1_SB_DQS_DP<9>'
 '@T6G_MB_LIB.T6G(SCH_1):M_F_CPU1_SB_DQS_DP'<9>:
 C_SIGNAL='@t6g_mb_lib.t6g(sch_1):m_f_cpu1_sb_dqs_dp(9)';
NODE_NAME     U26 BV67
 '@T6G_MB_LIB.T6G(SCH_1):PAGE42_I159@PURE_QUANTA.GENOA_SP5(CHIPS)':
 'MFB_DQS_H9': CDS_PINID='MFB_DQS_H9';
NODE_NAME     J33 93
 '@T6G_MB_LIB.T6G(SCH_1):PAGE102_I236@PURE_QUANTA.SCONN288_DDR506112002KQ(CHIPS)':
 'DQS9_B_T||TDQS9_B_T||DBI4_B_N': CDS_PINID='\dqs9_b_t||tdqs9_b_t||dbi4_b_n\';
NET_NAME
'M_F_CPU1_SB_PAR'
 '@T6G_MB_LIB.T6G(SCH_1):M_F_CPU1_SB_PAR':
 C_SIGNAL='@t6g_mb_lib.t6g(sch_1):m_f_cpu1_sb_par';
NODE_NAME     U26 BL67
 '@T6G_MB_LIB.T6G(SCH_1):PAGE42_I159@PURE_QUANTA.GENOA_SP5(CHIPS)':
 'MFB_PAR': CDS_PINID='MFB_PAR';
NODE_NAME     J33 227
 '@T6G_MB_LIB.T6G(SCH_1):PAGE102_I22@PURE_QUANTA.SCONN288_DDR506112002KQ(CHIPS)':
 'PAR_B': CDS_PINID='PAR_B';
NET_NAME
'M_F_CPU1_SB_RSP<0>'
 '@T6G_MB_LIB.T6G(SCH_1):M_F_CPU1_SB_RSP'<0>:
 C_SIGNAL='@t6g_mb_lib.t6g(sch_1):m_f_cpu1_sb_rsp(0)';
NODE_NAME     U26 BP67
 '@T6G_MB_LIB.T6G(SCH_1):PAGE42_I159@PURE_QUANTA.GENOA_SP5(CHIPS)':
 'MFB0_RSP_L': CDS_PINID='MFB0_RSP_L';
NODE_NAME     J33 87
 '@T6G_MB_LIB.T6G(SCH_1):PAGE102_I22@PURE_QUANTA.SCONN288_DDR506112002KQ(CHIPS)':
 'LBS||RSP_B_N': CDS_PINID='\lbs||rsp_b_n\';
NET_NAME
'M_G_CPU0_ALERT_N'
 '@T6G_MB_LIB.T6G(SCH_1):M_G_CPU0_ALERT_N':
 C_SIGNAL='@t6g_mb_lib.t6g(sch_1):m_g_cpu0_alert_n';
NODE_NAME     R381 1
 '@T6G_MB_LIB.T6G(SCH_1):PAGE16_I323@PURE_QUANTA.Q_RES(CHIPS)':
 'A': CDS_PINID='A';
NODE_NAME     J16 62
 '@T6G_MB_LIB.T6G(SCH_1):PAGE91_I22@PURE_QUANTA.SCONN288_DDR506112002KQ(CHIPS)':
 'ALERT_N': CDS_PINID='ALERT_N';
NET_NAME
'M_G_CPU0_ALERT_R_N'
 '@T6G_MB_LIB.T6G(SCH_1):M_G_CPU0_ALERT_R_N':
 C_SIGNAL='@t6g_mb_lib.t6g(sch_1):m_g_cpu0_alert_r_n';
NODE_NAME     U25 AR2
 '@T6G_MB_LIB.T6G(SCH_1):PAGE16_I167@PURE_QUANTA.GENOA_SP5(CHIPS)':
 'MG_ALERT_L': CDS_PINID='MG_ALERT_L';
NODE_NAME     R381 2
 '@T6G_MB_LIB.T6G(SCH_1):PAGE16_I323@PURE_QUANTA.Q_RES(CHIPS)':
 'B': CDS_PINID='B';
NET_NAME
'M_G_CPU0_CLK_DN<0>'
 '@T6G_MB_LIB.T6G(SCH_1):M_G_CPU0_CLK_DN'<0>:
 C_SIGNAL='@t6g_mb_lib.t6g(sch_1):m_g_cpu0_clk_dn(0)';
NODE_NAME     U25 BD2
 '@T6G_MB_LIB.T6G(SCH_1):PAGE16_I167@PURE_QUANTA.GENOA_SP5(CHIPS)':
 'MG0_CLK_L': CDS_PINID='MG0_CLK_L';
NODE_NAME     J16 218
 '@T6G_MB_LIB.T6G(SCH_1):PAGE91_I22@PURE_QUANTA.SCONN288_DDR506112002KQ(CHIPS)':
 'CK_C': CDS_PINID='CK_C';
NET_NAME
'M_G_CPU0_CLK_DP<0>'
 '@T6G_MB_LIB.T6G(SCH_1):M_G_CPU0_CLK_DP'<0>:
 C_SIGNAL='@t6g_mb_lib.t6g(sch_1):m_g_cpu0_clk_dp(0)';
NODE_NAME     U25 BC2
 '@T6G_MB_LIB.T6G(SCH_1):PAGE16_I167@PURE_QUANTA.GENOA_SP5(CHIPS)':
 'MG0_CLK_H': CDS_PINID='MG0_CLK_H';
NODE_NAME     J16 217
 '@T6G_MB_LIB.T6G(SCH_1):PAGE91_I22@PURE_QUANTA.SCONN288_DDR506112002KQ(CHIPS)':
 'CK_T': CDS_PINID='CK_T';
NET_NAME
'M_G_CPU0_RESET_N'
 '@T6G_MB_LIB.T6G(SCH_1):M_G_CPU0_RESET_N':
 C_SIGNAL='@t6g_mb_lib.t6g(sch_1):m_g_cpu0_reset_n';
NODE_NAME     U25 AT2
 '@T6G_MB_LIB.T6G(SCH_1):PAGE16_I167@PURE_QUANTA.GENOA_SP5(CHIPS)':
 'MG_RESET_L': CDS_PINID='MG_RESET_L';
NODE_NAME     J16 207
 '@T6G_MB_LIB.T6G(SCH_1):PAGE91_I22@PURE_QUANTA.SCONN288_DDR506112002KQ(CHIPS)':
 'RESET_N': CDS_PINID='RESET_N';
NET_NAME
'M_G_CPU0_SA_CA<0>'
 '@T6G_MB_LIB.T6G(SCH_1):M_G_CPU0_SA_CA'<0>:
 C_SIGNAL='@t6g_mb_lib.t6g(sch_1):m_g_cpu0_sa_ca(0)';
NODE_NAME     U25 AW2
 '@T6G_MB_LIB.T6G(SCH_1):PAGE16_I167@PURE_QUANTA.GENOA_SP5(CHIPS)':
 'MGA_CA0': CDS_PINID='MGA_CA0';
NODE_NAME     J16 66
 '@T6G_MB_LIB.T6G(SCH_1):PAGE91_I22@PURE_QUANTA.SCONN288_DDR506112002KQ(CHIPS)':
 'CA0_A': CDS_PINID='CA0_A';
NET_NAME
'M_G_CPU0_SA_CA<1>'
 '@T6G_MB_LIB.T6G(SCH_1):M_G_CPU0_SA_CA'<1>:
 C_SIGNAL='@t6g_mb_lib.t6g(sch_1):m_g_cpu0_sa_ca(1)';
NODE_NAME     U25 AY2
 '@T6G_MB_LIB.T6G(SCH_1):PAGE16_I167@PURE_QUANTA.GENOA_SP5(CHIPS)':
 'MGA_CA1': CDS_PINID='MGA_CA1';
NODE_NAME     J16 211
 '@T6G_MB_LIB.T6G(SCH_1):PAGE91_I22@PURE_QUANTA.SCONN288_DDR506112002KQ(CHIPS)':
 'CA1_A': CDS_PINID='CA1_A';
NET_NAME
'M_G_CPU0_SA_CA<2>'
 '@T6G_MB_LIB.T6G(SCH_1):M_G_CPU0_SA_CA'<2>:
 C_SIGNAL='@t6g_mb_lib.t6g(sch_1):m_g_cpu0_sa_ca(2)';
NODE_NAME     U25 AY4
 '@T6G_MB_LIB.T6G(SCH_1):PAGE16_I167@PURE_QUANTA.GENOA_SP5(CHIPS)':
 'MGA_CA2': CDS_PINID='MGA_CA2';
NODE_NAME     J16 68
 '@T6G_MB_LIB.T6G(SCH_1):PAGE91_I22@PURE_QUANTA.SCONN288_DDR506112002KQ(CHIPS)':
 'CA2_A': CDS_PINID='CA2_A';
NET_NAME
'M_G_CPU0_SA_CA<3>'
 '@T6G_MB_LIB.T6G(SCH_1):M_G_CPU0_SA_CA'<3>:
 C_SIGNAL='@t6g_mb_lib.t6g(sch_1):m_g_cpu0_sa_ca(3)';
NODE_NAME     U25 BA3
 '@T6G_MB_LIB.T6G(SCH_1):PAGE16_I167@PURE_QUANTA.GENOA_SP5(CHIPS)':
 'MGA_CA3': CDS_PINID='MGA_CA3';
NODE_NAME     J16 213
 '@T6G_MB_LIB.T6G(SCH_1):PAGE91_I22@PURE_QUANTA.SCONN288_DDR506112002KQ(CHIPS)':
 'CA3_A': CDS_PINID='CA3_A';
NET_NAME
'M_G_CPU0_SA_CA<4>'
 '@T6G_MB_LIB.T6G(SCH_1):M_G_CPU0_SA_CA'<4>:
 C_SIGNAL='@t6g_mb_lib.t6g(sch_1):m_g_cpu0_sa_ca(4)';
NODE_NAME     U25 BA2
 '@T6G_MB_LIB.T6G(SCH_1):PAGE16_I167@PURE_QUANTA.GENOA_SP5(CHIPS)':
 'MGA_CA4': CDS_PINID='MGA_CA4';
NODE_NAME     J16 70
 '@T6G_MB_LIB.T6G(SCH_1):PAGE91_I22@PURE_QUANTA.SCONN288_DDR506112002KQ(CHIPS)':
 'CA4_A': CDS_PINID='CA4_A';
NET_NAME
'M_G_CPU0_SA_CA<5>'
 '@T6G_MB_LIB.T6G(SCH_1):M_G_CPU0_SA_CA'<5>:
 C_SIGNAL='@t6g_mb_lib.t6g(sch_1):m_g_cpu0_sa_ca(5)';
NODE_NAME     U25 BB2
 '@T6G_MB_LIB.T6G(SCH_1):PAGE16_I167@PURE_QUANTA.GENOA_SP5(CHIPS)':
 'MGA_CA5': CDS_PINID='MGA_CA5';
NODE_NAME     J16 215
 '@T6G_MB_LIB.T6G(SCH_1):PAGE91_I22@PURE_QUANTA.SCONN288_DDR506112002KQ(CHIPS)':
 'CA5_A': CDS_PINID='CA5_A';
NET_NAME
'M_G_CPU0_SA_CA<6>'
 '@T6G_MB_LIB.T6G(SCH_1):M_G_CPU0_SA_CA'<6>:
 C_SIGNAL='@t6g_mb_lib.t6g(sch_1):m_g_cpu0_sa_ca(6)';
NODE_NAME     U25 BB4
 '@T6G_MB_LIB.T6G(SCH_1):PAGE16_I167@PURE_QUANTA.GENOA_SP5(CHIPS)':
 'MGA_CA6': CDS_PINID='MGA_CA6';
NODE_NAME     J16 72
 '@T6G_MB_LIB.T6G(SCH_1):PAGE91_I22@PURE_QUANTA.SCONN288_DDR506112002KQ(CHIPS)':
 'CA6_A': CDS_PINID='CA6_A';
NET_NAME
'M_G_CPU0_SA_CB<0>'
 '@T6G_MB_LIB.T6G(SCH_1):M_G_CPU0_SA_CB'<0>:
 C_SIGNAL='@t6g_mb_lib.t6g(sch_1):m_g_cpu0_sa_cb(0)';
NODE_NAME     U25 AJ2
 '@T6G_MB_LIB.T6G(SCH_1):PAGE16_I167@PURE_QUANTA.GENOA_SP5(CHIPS)':
 'MGA_CHECK0': CDS_PINID='MGA_CHECK0';
NODE_NAME     J16 51
 '@T6G_MB_LIB.T6G(SCH_1):PAGE91_I22@PURE_QUANTA.SCONN288_DDR506112002KQ(CHIPS)':
 'CB0_A': CDS_PINID='CB0_A';
NET_NAME
'M_G_CPU0_SA_CB<1>'
 '@T6G_MB_LIB.T6G(SCH_1):M_G_CPU0_SA_CB'<1>:
 C_SIGNAL='@t6g_mb_lib.t6g(sch_1):m_g_cpu0_sa_cb(1)';
NODE_NAME     U25 AK4
 '@T6G_MB_LIB.T6G(SCH_1):PAGE16_I167@PURE_QUANTA.GENOA_SP5(CHIPS)':
 'MGA_CHECK1': CDS_PINID='MGA_CHECK1';
NODE_NAME     J16 53
 '@T6G_MB_LIB.T6G(SCH_1):PAGE91_I22@PURE_QUANTA.SCONN288_DDR506112002KQ(CHIPS)':
 'CB1_A': CDS_PINID='CB1_A';
NET_NAME
'M_G_CPU0_SA_CB<2>'
 '@T6G_MB_LIB.T6G(SCH_1):M_G_CPU0_SA_CB'<2>:
 C_SIGNAL='@t6g_mb_lib.t6g(sch_1):m_g_cpu0_sa_cb(2)';
NODE_NAME     U25 AK2
 '@T6G_MB_LIB.T6G(SCH_1):PAGE16_I167@PURE_QUANTA.GENOA_SP5(CHIPS)':
 'MGA_CHECK2': CDS_PINID='MGA_CHECK2';
NODE_NAME     J16 196
 '@T6G_MB_LIB.T6G(SCH_1):PAGE91_I22@PURE_QUANTA.SCONN288_DDR506112002KQ(CHIPS)':
 'CB2_A': CDS_PINID='CB2_A';
NET_NAME
'M_G_CPU0_SA_CB<3>'
 '@T6G_MB_LIB.T6G(SCH_1):M_G_CPU0_SA_CB'<3>:
 C_SIGNAL='@t6g_mb_lib.t6g(sch_1):m_g_cpu0_sa_cb(3)';
NODE_NAME     U25 AL3
 '@T6G_MB_LIB.T6G(SCH_1):PAGE16_I167@PURE_QUANTA.GENOA_SP5(CHIPS)':
 'MGA_CHECK3': CDS_PINID='MGA_CHECK3';
NODE_NAME     J16 198
 '@T6G_MB_LIB.T6G(SCH_1):PAGE91_I22@PURE_QUANTA.SCONN288_DDR506112002KQ(CHIPS)':
 'CB3_A': CDS_PINID='CB3_A';
NET_NAME
'M_G_CPU0_SA_CB<4>'
 '@T6G_MB_LIB.T6G(SCH_1):M_G_CPU0_SA_CB'<4>:
 C_SIGNAL='@t6g_mb_lib.t6g(sch_1):m_g_cpu0_sa_cb(4)';
NODE_NAME     U25 AN2
 '@T6G_MB_LIB.T6G(SCH_1):PAGE16_I167@PURE_QUANTA.GENOA_SP5(CHIPS)':
 'MGA_CHECK4': CDS_PINID='MGA_CHECK4';
NODE_NAME     J16 58
 '@T6G_MB_LIB.T6G(SCH_1):PAGE91_I22@PURE_QUANTA.SCONN288_DDR506112002KQ(CHIPS)':
 'CB4_A': CDS_PINID='CB4_A';
NET_NAME
'M_G_CPU0_SA_CB<5>'
 '@T6G_MB_LIB.T6G(SCH_1):M_G_CPU0_SA_CB'<5>:
 C_SIGNAL='@t6g_mb_lib.t6g(sch_1):m_g_cpu0_sa_cb(5)';
NODE_NAME     U25 AP4
 '@T6G_MB_LIB.T6G(SCH_1):PAGE16_I167@PURE_QUANTA.GENOA_SP5(CHIPS)':
 'MGA_CHECK5': CDS_PINID='MGA_CHECK5';
NODE_NAME     J16 60
 '@T6G_MB_LIB.T6G(SCH_1):PAGE91_I22@PURE_QUANTA.SCONN288_DDR506112002KQ(CHIPS)':
 'CB5_A': CDS_PINID='CB5_A';
NET_NAME
'M_G_CPU0_SA_CB<6>'
 '@T6G_MB_LIB.T6G(SCH_1):M_G_CPU0_SA_CB'<6>:
 C_SIGNAL='@t6g_mb_lib.t6g(sch_1):m_g_cpu0_sa_cb(6)';
NODE_NAME     U25 AP2
 '@T6G_MB_LIB.T6G(SCH_1):PAGE16_I167@PURE_QUANTA.GENOA_SP5(CHIPS)':
 'MGA_CHECK6': CDS_PINID='MGA_CHECK6';
NODE_NAME     J16 203
 '@T6G_MB_LIB.T6G(SCH_1):PAGE91_I22@PURE_QUANTA.SCONN288_DDR506112002KQ(CHIPS)':
 'CB6_A': CDS_PINID='CB6_A';
NET_NAME
'M_G_CPU0_SA_CB<7>'
 '@T6G_MB_LIB.T6G(SCH_1):M_G_CPU0_SA_CB'<7>:
 C_SIGNAL='@t6g_mb_lib.t6g(sch_1):m_g_cpu0_sa_cb(7)';
NODE_NAME     U25 AR3
 '@T6G_MB_LIB.T6G(SCH_1):PAGE16_I167@PURE_QUANTA.GENOA_SP5(CHIPS)':
 'MGA_CHECK7': CDS_PINID='MGA_CHECK7';
NODE_NAME     J16 205
 '@T6G_MB_LIB.T6G(SCH_1):PAGE91_I22@PURE_QUANTA.SCONN288_DDR506112002KQ(CHIPS)':
 'CB7_A': CDS_PINID='CB7_A';
NET_NAME
'M_G_CPU0_SA_CS_N<0>'
 '@T6G_MB_LIB.T6G(SCH_1):M_G_CPU0_SA_CS_N'<0>:
 C_SIGNAL='@t6g_mb_lib.t6g(sch_1):m_g_cpu0_sa_cs_n(0)';
NODE_NAME     U25 AU2
 '@T6G_MB_LIB.T6G(SCH_1):PAGE16_I167@PURE_QUANTA.GENOA_SP5(CHIPS)':
 'MGA0_CS_L0': CDS_PINID='MGA0_CS_L0';
NODE_NAME     J16 64
 '@T6G_MB_LIB.T6G(SCH_1):PAGE91_I22@PURE_QUANTA.SCONN288_DDR506112002KQ(CHIPS)':
 'CS0_A_N': CDS_PINID='CS0_A_N';
NET_NAME
'M_G_CPU0_SA_CS_N<1>'
 '@T6G_MB_LIB.T6G(SCH_1):M_G_CPU0_SA_CS_N'<1>:
 C_SIGNAL='@t6g_mb_lib.t6g(sch_1):m_g_cpu0_sa_cs_n(1)';
NODE_NAME     U25 AV4
 '@T6G_MB_LIB.T6G(SCH_1):PAGE16_I167@PURE_QUANTA.GENOA_SP5(CHIPS)':
 'MGA0_CS_L1': CDS_PINID='MGA0_CS_L1';
NODE_NAME     J16 209
 '@T6G_MB_LIB.T6G(SCH_1):PAGE91_I22@PURE_QUANTA.SCONN288_DDR506112002KQ(CHIPS)':
 'CS1_A_N': CDS_PINID='CS1_A_N';
NET_NAME
'M_G_CPU0_SA_DQ<0>'
 '@T6G_MB_LIB.T6G(SCH_1):M_G_CPU0_SA_DQ'<0>:
 C_SIGNAL='@t6g_mb_lib.t6g(sch_1):m_g_cpu0_sa_dq(0)';
NODE_NAME     U25 E2
 '@T6G_MB_LIB.T6G(SCH_1):PAGE16_I167@PURE_QUANTA.GENOA_SP5(CHIPS)':
 'MGA_DATA0': CDS_PINID='MGA_DATA0';
NODE_NAME     J16 7
 '@T6G_MB_LIB.T6G(SCH_1):PAGE91_I22@PURE_QUANTA.SCONN288_DDR506112002KQ(CHIPS)':
 'DQ0_A': CDS_PINID='DQ0_A';
NET_NAME
'M_G_CPU0_SA_DQ<10>'
 '@T6G_MB_LIB.T6G(SCH_1):M_G_CPU0_SA_DQ'<10>:
 C_SIGNAL='@t6g_mb_lib.t6g(sch_1):m_g_cpu0_sa_dq(10)';
NODE_NAME     U25 M2
 '@T6G_MB_LIB.T6G(SCH_1):PAGE16_I167@PURE_QUANTA.GENOA_SP5(CHIPS)':
 'MGA_DATA10': CDS_PINID='MGA_DATA10';
NODE_NAME     J16 163
 '@T6G_MB_LIB.T6G(SCH_1):PAGE91_I22@PURE_QUANTA.SCONN288_DDR506112002KQ(CHIPS)':
 'DQ10_A': CDS_PINID='DQ10_A';
NET_NAME
'M_G_CPU0_SA_DQ<11>'
 '@T6G_MB_LIB.T6G(SCH_1):M_G_CPU0_SA_DQ'<11>:
 C_SIGNAL='@t6g_mb_lib.t6g(sch_1):m_g_cpu0_sa_dq(11)';
NODE_NAME     U25 N3
 '@T6G_MB_LIB.T6G(SCH_1):PAGE16_I167@PURE_QUANTA.GENOA_SP5(CHIPS)':
 'MGA_DATA11': CDS_PINID='MGA_DATA11';
NODE_NAME     J16 165
 '@T6G_MB_LIB.T6G(SCH_1):PAGE91_I22@PURE_QUANTA.SCONN288_DDR506112002KQ(CHIPS)':
 'DQ11_A': CDS_PINID='DQ11_A';
NET_NAME
'M_G_CPU0_SA_DQ<12>'
 '@T6G_MB_LIB.T6G(SCH_1):M_G_CPU0_SA_DQ'<12>:
 C_SIGNAL='@t6g_mb_lib.t6g(sch_1):m_g_cpu0_sa_dq(12)';
NODE_NAME     U25 R2
 '@T6G_MB_LIB.T6G(SCH_1):PAGE16_I167@PURE_QUANTA.GENOA_SP5(CHIPS)':
 'MGA_DATA12': CDS_PINID='MGA_DATA12';
NODE_NAME     J16 25
 '@T6G_MB_LIB.T6G(SCH_1):PAGE91_I22@PURE_QUANTA.SCONN288_DDR506112002KQ(CHIPS)':
 'DQ12_A': CDS_PINID='DQ12_A';
NET_NAME
'M_G_CPU0_SA_DQ<13>'
 '@T6G_MB_LIB.T6G(SCH_1):M_G_CPU0_SA_DQ'<13>:
 C_SIGNAL='@t6g_mb_lib.t6g(sch_1):m_g_cpu0_sa_dq(13)';
NODE_NAME     U25 T4
 '@T6G_MB_LIB.T6G(SCH_1):PAGE16_I167@PURE_QUANTA.GENOA_SP5(CHIPS)':
 'MGA_DATA13': CDS_PINID='MGA_DATA13';
NODE_NAME     J16 27
 '@T6G_MB_LIB.T6G(SCH_1):PAGE91_I22@PURE_QUANTA.SCONN288_DDR506112002KQ(CHIPS)':
 'DQ13_A': CDS_PINID='DQ13_A';
NET_NAME
'M_G_CPU0_SA_DQ<14>'
 '@T6G_MB_LIB.T6G(SCH_1):M_G_CPU0_SA_DQ'<14>:
 C_SIGNAL='@t6g_mb_lib.t6g(sch_1):m_g_cpu0_sa_dq(14)';
NODE_NAME     U25 T2
 '@T6G_MB_LIB.T6G(SCH_1):PAGE16_I167@PURE_QUANTA.GENOA_SP5(CHIPS)':
 'MGA_DATA14': CDS_PINID='MGA_DATA14';
NODE_NAME     J16 170
 '@T6G_MB_LIB.T6G(SCH_1):PAGE91_I22@PURE_QUANTA.SCONN288_DDR506112002KQ(CHIPS)':
 'DQ14_A': CDS_PINID='DQ14_A';
NET_NAME
'M_G_CPU0_SA_DQ<15>'
 '@T6G_MB_LIB.T6G(SCH_1):M_G_CPU0_SA_DQ'<15>:
 C_SIGNAL='@t6g_mb_lib.t6g(sch_1):m_g_cpu0_sa_dq(15)';
NODE_NAME     U25 U3
 '@T6G_MB_LIB.T6G(SCH_1):PAGE16_I167@PURE_QUANTA.GENOA_SP5(CHIPS)':
 'MGA_DATA15': CDS_PINID='MGA_DATA15';
NODE_NAME     J16 172
 '@T6G_MB_LIB.T6G(SCH_1):PAGE91_I22@PURE_QUANTA.SCONN288_DDR506112002KQ(CHIPS)':
 'DQ15_A': CDS_PINID='DQ15_A';
NET_NAME
'M_G_CPU0_SA_DQ<16>'
 '@T6G_MB_LIB.T6G(SCH_1):M_G_CPU0_SA_DQ'<16>:
 C_SIGNAL='@t6g_mb_lib.t6g(sch_1):m_g_cpu0_sa_dq(16)';
NODE_NAME     U25 U2
 '@T6G_MB_LIB.T6G(SCH_1):PAGE16_I167@PURE_QUANTA.GENOA_SP5(CHIPS)':
 'MGA_DATA16': CDS_PINID='MGA_DATA16';
NODE_NAME     J16 29
 '@T6G_MB_LIB.T6G(SCH_1):PAGE91_I22@PURE_QUANTA.SCONN288_DDR506112002KQ(CHIPS)':
 'DQ16_A': CDS_PINID='DQ16_A';
NET_NAME
'M_G_CPU0_SA_DQ<17>'
 '@T6G_MB_LIB.T6G(SCH_1):M_G_CPU0_SA_DQ'<17>:
 C_SIGNAL='@t6g_mb_lib.t6g(sch_1):m_g_cpu0_sa_dq(17)';
NODE_NAME     U25 V4
 '@T6G_MB_LIB.T6G(SCH_1):PAGE16_I167@PURE_QUANTA.GENOA_SP5(CHIPS)':
 'MGA_DATA17': CDS_PINID='MGA_DATA17';
NODE_NAME     J16 31
 '@T6G_MB_LIB.T6G(SCH_1):PAGE91_I22@PURE_QUANTA.SCONN288_DDR506112002KQ(CHIPS)':
 'DQ17_A': CDS_PINID='DQ17_A';
NET_NAME
'M_G_CPU0_SA_DQ<18>'
 '@T6G_MB_LIB.T6G(SCH_1):M_G_CPU0_SA_DQ'<18>:
 C_SIGNAL='@t6g_mb_lib.t6g(sch_1):m_g_cpu0_sa_dq(18)';
NODE_NAME     U25 V2
 '@T6G_MB_LIB.T6G(SCH_1):PAGE16_I167@PURE_QUANTA.GENOA_SP5(CHIPS)':
 'MGA_DATA18': CDS_PINID='MGA_DATA18';
NODE_NAME     J16 174
 '@T6G_MB_LIB.T6G(SCH_1):PAGE91_I22@PURE_QUANTA.SCONN288_DDR506112002KQ(CHIPS)':
 'DQ18_A': CDS_PINID='DQ18_A';
NET_NAME
'M_G_CPU0_SA_DQ<19>'
 '@T6G_MB_LIB.T6G(SCH_1):M_G_CPU0_SA_DQ'<19>:
 C_SIGNAL='@t6g_mb_lib.t6g(sch_1):m_g_cpu0_sa_dq(19)';
NODE_NAME     U25 W3
 '@T6G_MB_LIB.T6G(SCH_1):PAGE16_I167@PURE_QUANTA.GENOA_SP5(CHIPS)':
 'MGA_DATA19': CDS_PINID='MGA_DATA19';
NODE_NAME     J16 176
 '@T6G_MB_LIB.T6G(SCH_1):PAGE91_I22@PURE_QUANTA.SCONN288_DDR506112002KQ(CHIPS)':
 'DQ19_A': CDS_PINID='DQ19_A';
NET_NAME
'M_G_CPU0_SA_DQ<1>'
 '@T6G_MB_LIB.T6G(SCH_1):M_G_CPU0_SA_DQ'<1>:
 C_SIGNAL='@t6g_mb_lib.t6g(sch_1):m_g_cpu0_sa_dq(1)';
NODE_NAME     U25 F4
 '@T6G_MB_LIB.T6G(SCH_1):PAGE16_I167@PURE_QUANTA.GENOA_SP5(CHIPS)':
 'MGA_DATA1': CDS_PINID='MGA_DATA1';
NODE_NAME     J16 9
 '@T6G_MB_LIB.T6G(SCH_1):PAGE91_I22@PURE_QUANTA.SCONN288_DDR506112002KQ(CHIPS)':
 'DQ1_A': CDS_PINID='DQ1_A';
NET_NAME
'M_G_CPU0_SA_DQ<20>'
 '@T6G_MB_LIB.T6G(SCH_1):M_G_CPU0_SA_DQ'<20>:
 C_SIGNAL='@t6g_mb_lib.t6g(sch_1):m_g_cpu0_sa_dq(20)';
NODE_NAME     U25 AA2
 '@T6G_MB_LIB.T6G(SCH_1):PAGE16_I167@PURE_QUANTA.GENOA_SP5(CHIPS)':
 'MGA_DATA20': CDS_PINID='MGA_DATA20';
NODE_NAME     J16 36
 '@T6G_MB_LIB.T6G(SCH_1):PAGE91_I22@PURE_QUANTA.SCONN288_DDR506112002KQ(CHIPS)':
 'DQ20_A': CDS_PINID='DQ20_A';
NET_NAME
'M_G_CPU0_SA_DQ<21>'
 '@T6G_MB_LIB.T6G(SCH_1):M_G_CPU0_SA_DQ'<21>:
 C_SIGNAL='@t6g_mb_lib.t6g(sch_1):m_g_cpu0_sa_dq(21)';
NODE_NAME     U25 AB4
 '@T6G_MB_LIB.T6G(SCH_1):PAGE16_I167@PURE_QUANTA.GENOA_SP5(CHIPS)':
 'MGA_DATA21': CDS_PINID='MGA_DATA21';
NODE_NAME     J16 38
 '@T6G_MB_LIB.T6G(SCH_1):PAGE91_I22@PURE_QUANTA.SCONN288_DDR506112002KQ(CHIPS)':
 'DQ21_A': CDS_PINID='DQ21_A';
NET_NAME
'M_G_CPU0_SA_DQ<22>'
 '@T6G_MB_LIB.T6G(SCH_1):M_G_CPU0_SA_DQ'<22>:
 C_SIGNAL='@t6g_mb_lib.t6g(sch_1):m_g_cpu0_sa_dq(22)';
NODE_NAME     U25 AB2
 '@T6G_MB_LIB.T6G(SCH_1):PAGE16_I167@PURE_QUANTA.GENOA_SP5(CHIPS)':
 'MGA_DATA22': CDS_PINID='MGA_DATA22';
NODE_NAME     J16 181
 '@T6G_MB_LIB.T6G(SCH_1):PAGE91_I22@PURE_QUANTA.SCONN288_DDR506112002KQ(CHIPS)':
 'DQ22_A': CDS_PINID='DQ22_A';
NET_NAME
'M_G_CPU0_SA_DQ<23>'
 '@T6G_MB_LIB.T6G(SCH_1):M_G_CPU0_SA_DQ'<23>:
 C_SIGNAL='@t6g_mb_lib.t6g(sch_1):m_g_cpu0_sa_dq(23)';
NODE_NAME     U25 AC3
 '@T6G_MB_LIB.T6G(SCH_1):PAGE16_I167@PURE_QUANTA.GENOA_SP5(CHIPS)':
 'MGA_DATA23': CDS_PINID='MGA_DATA23';
NODE_NAME     J16 183
 '@T6G_MB_LIB.T6G(SCH_1):PAGE91_I22@PURE_QUANTA.SCONN288_DDR506112002KQ(CHIPS)':
 'DQ23_A': CDS_PINID='DQ23_A';
NET_NAME
'M_G_CPU0_SA_DQ<24>'
 '@T6G_MB_LIB.T6G(SCH_1):M_G_CPU0_SA_DQ'<24>:
 C_SIGNAL='@t6g_mb_lib.t6g(sch_1):m_g_cpu0_sa_dq(24)';
NODE_NAME     U25 AC2
 '@T6G_MB_LIB.T6G(SCH_1):PAGE16_I167@PURE_QUANTA.GENOA_SP5(CHIPS)':
 'MGA_DATA24': CDS_PINID='MGA_DATA24';
NODE_NAME     J16 40
 '@T6G_MB_LIB.T6G(SCH_1):PAGE91_I22@PURE_QUANTA.SCONN288_DDR506112002KQ(CHIPS)':
 'DQ24_A': CDS_PINID='DQ24_A';
NET_NAME
'M_G_CPU0_SA_DQ<25>'
 '@T6G_MB_LIB.T6G(SCH_1):M_G_CPU0_SA_DQ'<25>:
 C_SIGNAL='@t6g_mb_lib.t6g(sch_1):m_g_cpu0_sa_dq(25)';
NODE_NAME     U25 AD4
 '@T6G_MB_LIB.T6G(SCH_1):PAGE16_I167@PURE_QUANTA.GENOA_SP5(CHIPS)':
 'MGA_DATA25': CDS_PINID='MGA_DATA25';
NODE_NAME     J16 42
 '@T6G_MB_LIB.T6G(SCH_1):PAGE91_I22@PURE_QUANTA.SCONN288_DDR506112002KQ(CHIPS)':
 'DQ25_A': CDS_PINID='DQ25_A';
NET_NAME
'M_G_CPU0_SA_DQ<26>'
 '@T6G_MB_LIB.T6G(SCH_1):M_G_CPU0_SA_DQ'<26>:
 C_SIGNAL='@t6g_mb_lib.t6g(sch_1):m_g_cpu0_sa_dq(26)';
NODE_NAME     U25 AD2
 '@T6G_MB_LIB.T6G(SCH_1):PAGE16_I167@PURE_QUANTA.GENOA_SP5(CHIPS)':
 'MGA_DATA26': CDS_PINID='MGA_DATA26';
NODE_NAME     J16 185
 '@T6G_MB_LIB.T6G(SCH_1):PAGE91_I22@PURE_QUANTA.SCONN288_DDR506112002KQ(CHIPS)':
 'DQ26_A': CDS_PINID='DQ26_A';
NET_NAME
'M_G_CPU0_SA_DQ<27>'
 '@T6G_MB_LIB.T6G(SCH_1):M_G_CPU0_SA_DQ'<27>:
 C_SIGNAL='@t6g_mb_lib.t6g(sch_1):m_g_cpu0_sa_dq(27)';
NODE_NAME     U25 AE3
 '@T6G_MB_LIB.T6G(SCH_1):PAGE16_I167@PURE_QUANTA.GENOA_SP5(CHIPS)':
 'MGA_DATA27': CDS_PINID='MGA_DATA27';
NODE_NAME     J16 187
 '@T6G_MB_LIB.T6G(SCH_1):PAGE91_I22@PURE_QUANTA.SCONN288_DDR506112002KQ(CHIPS)':
 'DQ27_A': CDS_PINID='DQ27_A';
NET_NAME
'M_G_CPU0_SA_DQ<28>'
 '@T6G_MB_LIB.T6G(SCH_1):M_G_CPU0_SA_DQ'<28>:
 C_SIGNAL='@t6g_mb_lib.t6g(sch_1):m_g_cpu0_sa_dq(28)';
NODE_NAME     U25 AG2
 '@T6G_MB_LIB.T6G(SCH_1):PAGE16_I167@PURE_QUANTA.GENOA_SP5(CHIPS)':
 'MGA_DATA28': CDS_PINID='MGA_DATA28';
NODE_NAME     J16 47
 '@T6G_MB_LIB.T6G(SCH_1):PAGE91_I22@PURE_QUANTA.SCONN288_DDR506112002KQ(CHIPS)':
 'DQ28_A': CDS_PINID='DQ28_A';
NET_NAME
'M_G_CPU0_SA_DQ<29>'
 '@T6G_MB_LIB.T6G(SCH_1):M_G_CPU0_SA_DQ'<29>:
 C_SIGNAL='@t6g_mb_lib.t6g(sch_1):m_g_cpu0_sa_dq(29)';
NODE_NAME     U25 AH4
 '@T6G_MB_LIB.T6G(SCH_1):PAGE16_I167@PURE_QUANTA.GENOA_SP5(CHIPS)':
 'MGA_DATA29': CDS_PINID='MGA_DATA29';
NODE_NAME     J16 49
 '@T6G_MB_LIB.T6G(SCH_1):PAGE91_I22@PURE_QUANTA.SCONN288_DDR506112002KQ(CHIPS)':
 'DQ29_A': CDS_PINID='DQ29_A';
NET_NAME
'M_G_CPU0_SA_DQ<2>'
 '@T6G_MB_LIB.T6G(SCH_1):M_G_CPU0_SA_DQ'<2>:
 C_SIGNAL='@t6g_mb_lib.t6g(sch_1):m_g_cpu0_sa_dq(2)';
NODE_NAME     U25 F2
 '@T6G_MB_LIB.T6G(SCH_1):PAGE16_I167@PURE_QUANTA.GENOA_SP5(CHIPS)':
 'MGA_DATA2': CDS_PINID='MGA_DATA2';
NODE_NAME     J16 152
 '@T6G_MB_LIB.T6G(SCH_1):PAGE91_I22@PURE_QUANTA.SCONN288_DDR506112002KQ(CHIPS)':
 'DQ2_A': CDS_PINID='DQ2_A';
NET_NAME
'M_G_CPU0_SA_DQ<30>'
 '@T6G_MB_LIB.T6G(SCH_1):M_G_CPU0_SA_DQ'<30>:
 C_SIGNAL='@t6g_mb_lib.t6g(sch_1):m_g_cpu0_sa_dq(30)';
NODE_NAME     U25 AH2
 '@T6G_MB_LIB.T6G(SCH_1):PAGE16_I167@PURE_QUANTA.GENOA_SP5(CHIPS)':
 'MGA_DATA30': CDS_PINID='MGA_DATA30';
NODE_NAME     J16 192
 '@T6G_MB_LIB.T6G(SCH_1):PAGE91_I22@PURE_QUANTA.SCONN288_DDR506112002KQ(CHIPS)':
 'DQ30_A': CDS_PINID='DQ30_A';
NET_NAME
'M_G_CPU0_SA_DQ<31>'
 '@T6G_MB_LIB.T6G(SCH_1):M_G_CPU0_SA_DQ'<31>:
 C_SIGNAL='@t6g_mb_lib.t6g(sch_1):m_g_cpu0_sa_dq(31)';
NODE_NAME     U25 AJ3
 '@T6G_MB_LIB.T6G(SCH_1):PAGE16_I167@PURE_QUANTA.GENOA_SP5(CHIPS)':
 'MGA_DATA31': CDS_PINID='MGA_DATA31';
NODE_NAME     J16 194
 '@T6G_MB_LIB.T6G(SCH_1):PAGE91_I22@PURE_QUANTA.SCONN288_DDR506112002KQ(CHIPS)':
 'DQ31_A': CDS_PINID='DQ31_A';
NET_NAME
'M_G_CPU0_SA_DQ<3>'
 '@T6G_MB_LIB.T6G(SCH_1):M_G_CPU0_SA_DQ'<3>:
 C_SIGNAL='@t6g_mb_lib.t6g(sch_1):m_g_cpu0_sa_dq(3)';
NODE_NAME     U25 G3
 '@T6G_MB_LIB.T6G(SCH_1):PAGE16_I167@PURE_QUANTA.GENOA_SP5(CHIPS)':
 'MGA_DATA3': CDS_PINID='MGA_DATA3';
NODE_NAME     J16 154
 '@T6G_MB_LIB.T6G(SCH_1):PAGE91_I22@PURE_QUANTA.SCONN288_DDR506112002KQ(CHIPS)':
 'DQ3_A': CDS_PINID='DQ3_A';
NET_NAME
'M_G_CPU0_SA_DQ<4>'
 '@T6G_MB_LIB.T6G(SCH_1):M_G_CPU0_SA_DQ'<4>:
 C_SIGNAL='@t6g_mb_lib.t6g(sch_1):m_g_cpu0_sa_dq(4)';
NODE_NAME     U25 J2
 '@T6G_MB_LIB.T6G(SCH_1):PAGE16_I167@PURE_QUANTA.GENOA_SP5(CHIPS)':
 'MGA_DATA4': CDS_PINID='MGA_DATA4';
NODE_NAME     J16 14
 '@T6G_MB_LIB.T6G(SCH_1):PAGE91_I22@PURE_QUANTA.SCONN288_DDR506112002KQ(CHIPS)':
 'DQ4_A': CDS_PINID='DQ4_A';
NET_NAME
'M_G_CPU0_SA_DQ<5>'
 '@T6G_MB_LIB.T6G(SCH_1):M_G_CPU0_SA_DQ'<5>:
 C_SIGNAL='@t6g_mb_lib.t6g(sch_1):m_g_cpu0_sa_dq(5)';
NODE_NAME     U25 K4
 '@T6G_MB_LIB.T6G(SCH_1):PAGE16_I167@PURE_QUANTA.GENOA_SP5(CHIPS)':
 'MGA_DATA5': CDS_PINID='MGA_DATA5';
NODE_NAME     J16 16
 '@T6G_MB_LIB.T6G(SCH_1):PAGE91_I22@PURE_QUANTA.SCONN288_DDR506112002KQ(CHIPS)':
 'DQ5_A': CDS_PINID='DQ5_A';
NET_NAME
'M_G_CPU0_SA_DQ<6>'
 '@T6G_MB_LIB.T6G(SCH_1):M_G_CPU0_SA_DQ'<6>:
 C_SIGNAL='@t6g_mb_lib.t6g(sch_1):m_g_cpu0_sa_dq(6)';
NODE_NAME     U25 K2
 '@T6G_MB_LIB.T6G(SCH_1):PAGE16_I167@PURE_QUANTA.GENOA_SP5(CHIPS)':
 'MGA_DATA6': CDS_PINID='MGA_DATA6';
NODE_NAME     J16 159
 '@T6G_MB_LIB.T6G(SCH_1):PAGE91_I22@PURE_QUANTA.SCONN288_DDR506112002KQ(CHIPS)':
 'DQ6_A': CDS_PINID='DQ6_A';
NET_NAME
'M_G_CPU0_SA_DQ<7>'
 '@T6G_MB_LIB.T6G(SCH_1):M_G_CPU0_SA_DQ'<7>:
 C_SIGNAL='@t6g_mb_lib.t6g(sch_1):m_g_cpu0_sa_dq(7)';
NODE_NAME     U25 L3
 '@T6G_MB_LIB.T6G(SCH_1):PAGE16_I167@PURE_QUANTA.GENOA_SP5(CHIPS)':
 'MGA_DATA7': CDS_PINID='MGA_DATA7';
NODE_NAME     J16 161
 '@T6G_MB_LIB.T6G(SCH_1):PAGE91_I22@PURE_QUANTA.SCONN288_DDR506112002KQ(CHIPS)':
 'DQ7_A': CDS_PINID='DQ7_A';
NET_NAME
'M_G_CPU0_SA_DQ<8>'
 '@T6G_MB_LIB.T6G(SCH_1):M_G_CPU0_SA_DQ'<8>:
 C_SIGNAL='@t6g_mb_lib.t6g(sch_1):m_g_cpu0_sa_dq(8)';
NODE_NAME     U25 L2
 '@T6G_MB_LIB.T6G(SCH_1):PAGE16_I167@PURE_QUANTA.GENOA_SP5(CHIPS)':
 'MGA_DATA8': CDS_PINID='MGA_DATA8';
NODE_NAME     J16 18
 '@T6G_MB_LIB.T6G(SCH_1):PAGE91_I22@PURE_QUANTA.SCONN288_DDR506112002KQ(CHIPS)':
 'DQ8_A': CDS_PINID='DQ8_A';
NET_NAME
'M_G_CPU0_SA_DQ<9>'
 '@T6G_MB_LIB.T6G(SCH_1):M_G_CPU0_SA_DQ'<9>:
 C_SIGNAL='@t6g_mb_lib.t6g(sch_1):m_g_cpu0_sa_dq(9)';
NODE_NAME     U25 M4
 '@T6G_MB_LIB.T6G(SCH_1):PAGE16_I167@PURE_QUANTA.GENOA_SP5(CHIPS)':
 'MGA_DATA9': CDS_PINID='MGA_DATA9';
NODE_NAME     J16 20
 '@T6G_MB_LIB.T6G(SCH_1):PAGE91_I22@PURE_QUANTA.SCONN288_DDR506112002KQ(CHIPS)':
 'DQ9_A': CDS_PINID='DQ9_A';
NET_NAME
'M_G_CPU0_SA_DQS_DN<0>'
 '@T6G_MB_LIB.T6G(SCH_1):M_G_CPU0_SA_DQS_DN'<0>:
 C_SIGNAL='@t6g_mb_lib.t6g(sch_1):m_g_cpu0_sa_dqs_dn(0)';
NODE_NAME     U25 H2
 '@T6G_MB_LIB.T6G(SCH_1):PAGE16_I167@PURE_QUANTA.GENOA_SP5(CHIPS)':
 'MGA_DQS_L0': CDS_PINID='MGA_DQS_L0';
NODE_NAME     J16 12
 '@T6G_MB_LIB.T6G(SCH_1):PAGE91_I236@PURE_QUANTA.SCONN288_DDR506112002KQ(CHIPS)':
 'DQS0_A_C': CDS_PINID='DQS0_A_C';
NET_NAME
'M_G_CPU0_SA_DQS_DN<1>'
 '@T6G_MB_LIB.T6G(SCH_1):M_G_CPU0_SA_DQS_DN'<1>:
 C_SIGNAL='@t6g_mb_lib.t6g(sch_1):m_g_cpu0_sa_dqs_dn(1)';
NODE_NAME     U25 P2
 '@T6G_MB_LIB.T6G(SCH_1):PAGE16_I167@PURE_QUANTA.GENOA_SP5(CHIPS)':
 'MGA_DQS_L1': CDS_PINID='MGA_DQS_L1';
NODE_NAME     J16 23
 '@T6G_MB_LIB.T6G(SCH_1):PAGE91_I236@PURE_QUANTA.SCONN288_DDR506112002KQ(CHIPS)':
 'DQS1_A_C': CDS_PINID='DQS1_A_C';
NET_NAME
'M_G_CPU0_SA_DQS_DN<2>'
 '@T6G_MB_LIB.T6G(SCH_1):M_G_CPU0_SA_DQS_DN'<2>:
 C_SIGNAL='@t6g_mb_lib.t6g(sch_1):m_g_cpu0_sa_dqs_dn(2)';
NODE_NAME     U25 Y2
 '@T6G_MB_LIB.T6G(SCH_1):PAGE16_I167@PURE_QUANTA.GENOA_SP5(CHIPS)':
 'MGA_DQS_L2': CDS_PINID='MGA_DQS_L2';
NODE_NAME     J16 34
 '@T6G_MB_LIB.T6G(SCH_1):PAGE91_I236@PURE_QUANTA.SCONN288_DDR506112002KQ(CHIPS)':
 'DQS2_A_C': CDS_PINID='DQS2_A_C';
NET_NAME
'M_G_CPU0_SA_DQS_DN<3>'
 '@T6G_MB_LIB.T6G(SCH_1):M_G_CPU0_SA_DQS_DN'<3>:
 C_SIGNAL='@t6g_mb_lib.t6g(sch_1):m_g_cpu0_sa_dqs_dn(3)';
NODE_NAME     U25 AF2
 '@T6G_MB_LIB.T6G(SCH_1):PAGE16_I167@PURE_QUANTA.GENOA_SP5(CHIPS)':
 'MGA_DQS_L3': CDS_PINID='MGA_DQS_L3';
NODE_NAME     J16 45
 '@T6G_MB_LIB.T6G(SCH_1):PAGE91_I236@PURE_QUANTA.SCONN288_DDR506112002KQ(CHIPS)':
 'DQS3_A_C': CDS_PINID='DQS3_A_C';
NET_NAME
'M_G_CPU0_SA_DQS_DN<4>'
 '@T6G_MB_LIB.T6G(SCH_1):M_G_CPU0_SA_DQS_DN'<4>:
 C_SIGNAL='@t6g_mb_lib.t6g(sch_1):m_g_cpu0_sa_dqs_dn(4)';
NODE_NAME     U25 AM2
 '@T6G_MB_LIB.T6G(SCH_1):PAGE16_I167@PURE_QUANTA.GENOA_SP5(CHIPS)':
 'MGA_DQS_L4': CDS_PINID='MGA_DQS_L4';
NODE_NAME     J16 56
 '@T6G_MB_LIB.T6G(SCH_1):PAGE91_I236@PURE_QUANTA.SCONN288_DDR506112002KQ(CHIPS)':
 'DQS4_A_C': CDS_PINID='DQS4_A_C';
NET_NAME
'M_G_CPU0_SA_DQS_DN<5>'
 '@T6G_MB_LIB.T6G(SCH_1):M_G_CPU0_SA_DQS_DN'<5>:
 C_SIGNAL='@t6g_mb_lib.t6g(sch_1):m_g_cpu0_sa_dqs_dn(5)';
NODE_NAME     U25 H4
 '@T6G_MB_LIB.T6G(SCH_1):PAGE16_I167@PURE_QUANTA.GENOA_SP5(CHIPS)':
 'MGA_DQS_L5': CDS_PINID='MGA_DQS_L5';
NODE_NAME     J16 156
 '@T6G_MB_LIB.T6G(SCH_1):PAGE91_I236@PURE_QUANTA.SCONN288_DDR506112002KQ(CHIPS)':
 'DQS5_A_C||TDQS5_A_C||DQS5_A_T||TDQS5_A_T': CDS_PINID='\dqs5_a_c||tdqs5_a_c||dqs5_a_t||tdqs5_a_t\';
NET_NAME
'M_G_CPU0_SA_DQS_DN<6>'
 '@T6G_MB_LIB.T6G(SCH_1):M_G_CPU0_SA_DQS_DN'<6>:
 C_SIGNAL='@t6g_mb_lib.t6g(sch_1):m_g_cpu0_sa_dqs_dn(6)';
NODE_NAME     U25 P4
 '@T6G_MB_LIB.T6G(SCH_1):PAGE16_I167@PURE_QUANTA.GENOA_SP5(CHIPS)':
 'MGA_DQS_L6': CDS_PINID='MGA_DQS_L6';
NODE_NAME     J16 167
 '@T6G_MB_LIB.T6G(SCH_1):PAGE91_I236@PURE_QUANTA.SCONN288_DDR506112002KQ(CHIPS)':
 'DQS6_A_C||TDQS6_A_C||DQS6_A_T||TDQS6_A_T': CDS_PINID='\dqs6_a_c||tdqs6_a_c||dqs6_a_t||tdqs6_a_t\';
NET_NAME
'M_G_CPU0_SA_DQS_DN<7>'
 '@T6G_MB_LIB.T6G(SCH_1):M_G_CPU0_SA_DQS_DN'<7>:
 C_SIGNAL='@t6g_mb_lib.t6g(sch_1):m_g_cpu0_sa_dqs_dn(7)';
NODE_NAME     U25 Y4
 '@T6G_MB_LIB.T6G(SCH_1):PAGE16_I167@PURE_QUANTA.GENOA_SP5(CHIPS)':
 'MGA_DQS_L7': CDS_PINID='MGA_DQS_L7';
NODE_NAME     J16 178
 '@T6G_MB_LIB.T6G(SCH_1):PAGE91_I236@PURE_QUANTA.SCONN288_DDR506112002KQ(CHIPS)':
 'DQS7_A_C||TDQS7_A_C': CDS_PINID='\dqs7_a_c||tdqs7_a_c\';
NET_NAME
'M_G_CPU0_SA_DQS_DN<8>'
 '@T6G_MB_LIB.T6G(SCH_1):M_G_CPU0_SA_DQS_DN'<8>:
 C_SIGNAL='@t6g_mb_lib.t6g(sch_1):m_g_cpu0_sa_dqs_dn(8)';
NODE_NAME     U25 AF4
 '@T6G_MB_LIB.T6G(SCH_1):PAGE16_I167@PURE_QUANTA.GENOA_SP5(CHIPS)':
 'MGA_DQS_L8': CDS_PINID='MGA_DQS_L8';
NODE_NAME     J16 189
 '@T6G_MB_LIB.T6G(SCH_1):PAGE91_I236@PURE_QUANTA.SCONN288_DDR506112002KQ(CHIPS)':
 'DQS8_A_C||TDQS8_A_C': CDS_PINID='\dqs8_a_c||tdqs8_a_c\';
NET_NAME
'M_G_CPU0_SA_DQS_DN<9>'
 '@T6G_MB_LIB.T6G(SCH_1):M_G_CPU0_SA_DQS_DN'<9>:
 C_SIGNAL='@t6g_mb_lib.t6g(sch_1):m_g_cpu0_sa_dqs_dn(9)';
NODE_NAME     U25 AM4
 '@T6G_MB_LIB.T6G(SCH_1):PAGE16_I167@PURE_QUANTA.GENOA_SP5(CHIPS)':
 'MGA_DQS_L9': CDS_PINID='MGA_DQS_L9';
NODE_NAME     J16 200
 '@T6G_MB_LIB.T6G(SCH_1):PAGE91_I236@PURE_QUANTA.SCONN288_DDR506112002KQ(CHIPS)':
 'DQS9_A_C||TDQS9_A_C': CDS_PINID='\dqs9_a_c||tdqs9_a_c\';
NET_NAME
'M_G_CPU0_SA_DQS_DP<0>'
 '@T6G_MB_LIB.T6G(SCH_1):M_G_CPU0_SA_DQS_DP'<0>:
 C_SIGNAL='@t6g_mb_lib.t6g(sch_1):m_g_cpu0_sa_dqs_dp(0)';
NODE_NAME     U25 G2
 '@T6G_MB_LIB.T6G(SCH_1):PAGE16_I167@PURE_QUANTA.GENOA_SP5(CHIPS)':
 'MGA_DQS_H0': CDS_PINID='MGA_DQS_H0';
NODE_NAME     J16 11
 '@T6G_MB_LIB.T6G(SCH_1):PAGE91_I236@PURE_QUANTA.SCONN288_DDR506112002KQ(CHIPS)':
 'DQS0_A_T': CDS_PINID='DQS0_A_T';
NET_NAME
'M_G_CPU0_SA_DQS_DP<1>'
 '@T6G_MB_LIB.T6G(SCH_1):M_G_CPU0_SA_DQS_DP'<1>:
 C_SIGNAL='@t6g_mb_lib.t6g(sch_1):m_g_cpu0_sa_dqs_dp(1)';
NODE_NAME     U25 N2
 '@T6G_MB_LIB.T6G(SCH_1):PAGE16_I167@PURE_QUANTA.GENOA_SP5(CHIPS)':
 'MGA_DQS_H1': CDS_PINID='MGA_DQS_H1';
NODE_NAME     J16 22
 '@T6G_MB_LIB.T6G(SCH_1):PAGE91_I236@PURE_QUANTA.SCONN288_DDR506112002KQ(CHIPS)':
 'DQS1_A_T': CDS_PINID='DQS1_A_T';
NET_NAME
'M_G_CPU0_SA_DQS_DP<2>'
 '@T6G_MB_LIB.T6G(SCH_1):M_G_CPU0_SA_DQS_DP'<2>:
 C_SIGNAL='@t6g_mb_lib.t6g(sch_1):m_g_cpu0_sa_dqs_dp(2)';
NODE_NAME     U25 W2
 '@T6G_MB_LIB.T6G(SCH_1):PAGE16_I167@PURE_QUANTA.GENOA_SP5(CHIPS)':
 'MGA_DQS_H2': CDS_PINID='MGA_DQS_H2';
NODE_NAME     J16 33
 '@T6G_MB_LIB.T6G(SCH_1):PAGE91_I236@PURE_QUANTA.SCONN288_DDR506112002KQ(CHIPS)':
 'DQS2_A_T': CDS_PINID='DQS2_A_T';
NET_NAME
'M_G_CPU0_SA_DQS_DP<3>'
 '@T6G_MB_LIB.T6G(SCH_1):M_G_CPU0_SA_DQS_DP'<3>:
 C_SIGNAL='@t6g_mb_lib.t6g(sch_1):m_g_cpu0_sa_dqs_dp(3)';
NODE_NAME     U25 AE2
 '@T6G_MB_LIB.T6G(SCH_1):PAGE16_I167@PURE_QUANTA.GENOA_SP5(CHIPS)':
 'MGA_DQS_H3': CDS_PINID='MGA_DQS_H3';
NODE_NAME     J16 44
 '@T6G_MB_LIB.T6G(SCH_1):PAGE91_I236@PURE_QUANTA.SCONN288_DDR506112002KQ(CHIPS)':
 'DQS3_A_T': CDS_PINID='DQS3_A_T';
NET_NAME
'M_G_CPU0_SA_DQS_DP<4>'
 '@T6G_MB_LIB.T6G(SCH_1):M_G_CPU0_SA_DQS_DP'<4>:
 C_SIGNAL='@t6g_mb_lib.t6g(sch_1):m_g_cpu0_sa_dqs_dp(4)';
NODE_NAME     U25 AL2
 '@T6G_MB_LIB.T6G(SCH_1):PAGE16_I167@PURE_QUANTA.GENOA_SP5(CHIPS)':
 'MGA_DQS_H4': CDS_PINID='MGA_DQS_H4';
NODE_NAME     J16 55
 '@T6G_MB_LIB.T6G(SCH_1):PAGE91_I236@PURE_QUANTA.SCONN288_DDR506112002KQ(CHIPS)':
 'DQS4_A_T': CDS_PINID='DQS4_A_T';
NET_NAME
'M_G_CPU0_SA_DQS_DP<5>'
 '@T6G_MB_LIB.T6G(SCH_1):M_G_CPU0_SA_DQS_DP'<5>:
 C_SIGNAL='@t6g_mb_lib.t6g(sch_1):m_g_cpu0_sa_dqs_dp(5)';
NODE_NAME     U25 J3
 '@T6G_MB_LIB.T6G(SCH_1):PAGE16_I167@PURE_QUANTA.GENOA_SP5(CHIPS)':
 'MGA_DQS_H5': CDS_PINID='MGA_DQS_H5';
NODE_NAME     J16 157
 '@T6G_MB_LIB.T6G(SCH_1):PAGE91_I236@PURE_QUANTA.SCONN288_DDR506112002KQ(CHIPS)':
 'DQS5_A_T||TDQS5_A_T': CDS_PINID='\dqs5_a_t||tdqs5_a_t\';
NET_NAME
'M_G_CPU0_SA_DQS_DP<6>'
 '@T6G_MB_LIB.T6G(SCH_1):M_G_CPU0_SA_DQS_DP'<6>:
 C_SIGNAL='@t6g_mb_lib.t6g(sch_1):m_g_cpu0_sa_dqs_dp(6)';
NODE_NAME     U25 R3
 '@T6G_MB_LIB.T6G(SCH_1):PAGE16_I167@PURE_QUANTA.GENOA_SP5(CHIPS)':
 'MGA_DQS_H6': CDS_PINID='MGA_DQS_H6';
NODE_NAME     J16 168
 '@T6G_MB_LIB.T6G(SCH_1):PAGE91_I236@PURE_QUANTA.SCONN288_DDR506112002KQ(CHIPS)':
 'DQS6_A_T||TDQS6_A_T': CDS_PINID='\dqs6_a_t||tdqs6_a_t\';
NET_NAME
'M_G_CPU0_SA_DQS_DP<7>'
 '@T6G_MB_LIB.T6G(SCH_1):M_G_CPU0_SA_DQS_DP'<7>:
 C_SIGNAL='@t6g_mb_lib.t6g(sch_1):m_g_cpu0_sa_dqs_dp(7)';
NODE_NAME     U25 AA3
 '@T6G_MB_LIB.T6G(SCH_1):PAGE16_I167@PURE_QUANTA.GENOA_SP5(CHIPS)':
 'MGA_DQS_H7': CDS_PINID='MGA_DQS_H7';
NODE_NAME     J16 179
 '@T6G_MB_LIB.T6G(SCH_1):PAGE91_I236@PURE_QUANTA.SCONN288_DDR506112002KQ(CHIPS)':
 'DQS7_A_T||TDQS7_A_T': CDS_PINID='\dqs7_a_t||tdqs7_a_t\';
NET_NAME
'M_G_CPU0_SA_DQS_DP<8>'
 '@T6G_MB_LIB.T6G(SCH_1):M_G_CPU0_SA_DQS_DP'<8>:
 C_SIGNAL='@t6g_mb_lib.t6g(sch_1):m_g_cpu0_sa_dqs_dp(8)';
NODE_NAME     U25 AG3
 '@T6G_MB_LIB.T6G(SCH_1):PAGE16_I167@PURE_QUANTA.GENOA_SP5(CHIPS)':
 'MGA_DQS_H8': CDS_PINID='MGA_DQS_H8';
NODE_NAME     J16 190
 '@T6G_MB_LIB.T6G(SCH_1):PAGE91_I236@PURE_QUANTA.SCONN288_DDR506112002KQ(CHIPS)':
 'DQS8_A_T||TDQS8_A_T': CDS_PINID='\dqs8_a_t||tdqs8_a_t\';
NET_NAME
'M_G_CPU0_SA_DQS_DP<9>'
 '@T6G_MB_LIB.T6G(SCH_1):M_G_CPU0_SA_DQS_DP'<9>:
 C_SIGNAL='@t6g_mb_lib.t6g(sch_1):m_g_cpu0_sa_dqs_dp(9)';
NODE_NAME     U25 AN3
 '@T6G_MB_LIB.T6G(SCH_1):PAGE16_I167@PURE_QUANTA.GENOA_SP5(CHIPS)':
 'MGA_DQS_H9': CDS_PINID='MGA_DQS_H9';
NODE_NAME     J16 201
 '@T6G_MB_LIB.T6G(SCH_1):PAGE91_I236@PURE_QUANTA.SCONN288_DDR506112002KQ(CHIPS)':
 'DQS9_A_T||TDQS9_A_T': CDS_PINID='\dqs9_a_t||tdqs9_a_t\';
NET_NAME
'M_G_CPU0_SA_PAR'
 '@T6G_MB_LIB.T6G(SCH_1):M_G_CPU0_SA_PAR':
 C_SIGNAL='@t6g_mb_lib.t6g(sch_1):m_g_cpu0_sa_par';
NODE_NAME     U25 BC3
 '@T6G_MB_LIB.T6G(SCH_1):PAGE16_I167@PURE_QUANTA.GENOA_SP5(CHIPS)':
 'MGA_PAR': CDS_PINID='MGA_PAR';
NODE_NAME     J16 74
 '@T6G_MB_LIB.T6G(SCH_1):PAGE91_I22@PURE_QUANTA.SCONN288_DDR506112002KQ(CHIPS)':
 'PAR_A': CDS_PINID='PAR_A';
NET_NAME
'M_G_CPU0_SA_RSP<0>'
 '@T6G_MB_LIB.T6G(SCH_1):M_G_CPU0_SA_RSP'<0>:
 C_SIGNAL='@t6g_mb_lib.t6g(sch_1):m_g_cpu0_sa_rsp(0)';
NODE_NAME     U25 BN3
 '@T6G_MB_LIB.T6G(SCH_1):PAGE16_I167@PURE_QUANTA.GENOA_SP5(CHIPS)':
 'MGA0_RSP_L': CDS_PINID='MGA0_RSP_L';
NODE_NAME     J16 86
 '@T6G_MB_LIB.T6G(SCH_1):PAGE91_I22@PURE_QUANTA.SCONN288_DDR506112002KQ(CHIPS)':
 'LBD||RSP_A_N': CDS_PINID='\lbd||rsp_a_n\';
NET_NAME
'M_G_CPU0_SB_CA<0>'
 '@T6G_MB_LIB.T6G(SCH_1):M_G_CPU0_SB_CA'<0>:
 C_SIGNAL='@t6g_mb_lib.t6g(sch_1):m_g_cpu0_sb_ca(0)';
NODE_NAME     U25 BG3
 '@T6G_MB_LIB.T6G(SCH_1):PAGE16_I167@PURE_QUANTA.GENOA_SP5(CHIPS)':
 'MGB_CA0': CDS_PINID='MGB_CA0';
NODE_NAME     J16 76
 '@T6G_MB_LIB.T6G(SCH_1):PAGE91_I22@PURE_QUANTA.SCONN288_DDR506112002KQ(CHIPS)':
 'CA0_B': CDS_PINID='CA0_B';
NET_NAME
'M_G_CPU0_SB_CA<1>'
 '@T6G_MB_LIB.T6G(SCH_1):M_G_CPU0_SB_CA'<1>:
 C_SIGNAL='@t6g_mb_lib.t6g(sch_1):m_g_cpu0_sb_ca(1)';
NODE_NAME     U25 BH4
 '@T6G_MB_LIB.T6G(SCH_1):PAGE16_I167@PURE_QUANTA.GENOA_SP5(CHIPS)':
 'MGB_CA1': CDS_PINID='MGB_CA1';
NODE_NAME     J16 221
 '@T6G_MB_LIB.T6G(SCH_1):PAGE91_I22@PURE_QUANTA.SCONN288_DDR506112002KQ(CHIPS)':
 'CA1_B': CDS_PINID='CA1_B';
NET_NAME
'M_G_CPU0_SB_CA<2>'
 '@T6G_MB_LIB.T6G(SCH_1):M_G_CPU0_SB_CA'<2>:
 C_SIGNAL='@t6g_mb_lib.t6g(sch_1):m_g_cpu0_sb_ca(2)';
NODE_NAME     U25 BH2
 '@T6G_MB_LIB.T6G(SCH_1):PAGE16_I167@PURE_QUANTA.GENOA_SP5(CHIPS)':
 'MGB_CA2': CDS_PINID='MGB_CA2';
NODE_NAME     J16 78
 '@T6G_MB_LIB.T6G(SCH_1):PAGE91_I22@PURE_QUANTA.SCONN288_DDR506112002KQ(CHIPS)':
 'CA2_B': CDS_PINID='CA2_B';
NET_NAME
'M_G_CPU0_SB_CA<3>'
 '@T6G_MB_LIB.T6G(SCH_1):M_G_CPU0_SB_CA'<3>:
 C_SIGNAL='@t6g_mb_lib.t6g(sch_1):m_g_cpu0_sb_ca(3)';
NODE_NAME     U25 BJ2
 '@T6G_MB_LIB.T6G(SCH_1):PAGE16_I167@PURE_QUANTA.GENOA_SP5(CHIPS)':
 'MGB_CA3': CDS_PINID='MGB_CA3';
NODE_NAME     J16 223
 '@T6G_MB_LIB.T6G(SCH_1):PAGE91_I22@PURE_QUANTA.SCONN288_DDR506112002KQ(CHIPS)':
 'CA3_B': CDS_PINID='CA3_B';
NET_NAME
'M_G_CPU0_SB_CA<4>'
 '@T6G_MB_LIB.T6G(SCH_1):M_G_CPU0_SB_CA'<4>:
 C_SIGNAL='@t6g_mb_lib.t6g(sch_1):m_g_cpu0_sb_ca(4)';
NODE_NAME     U25 BJ3
 '@T6G_MB_LIB.T6G(SCH_1):PAGE16_I167@PURE_QUANTA.GENOA_SP5(CHIPS)':
 'MGB_CA4': CDS_PINID='MGB_CA4';
NODE_NAME     J16 80
 '@T6G_MB_LIB.T6G(SCH_1):PAGE91_I22@PURE_QUANTA.SCONN288_DDR506112002KQ(CHIPS)':
 'CA4_B': CDS_PINID='CA4_B';
NET_NAME
'M_G_CPU0_SB_CA<5>'
 '@T6G_MB_LIB.T6G(SCH_1):M_G_CPU0_SB_CA'<5>:
 C_SIGNAL='@t6g_mb_lib.t6g(sch_1):m_g_cpu0_sb_ca(5)';
NODE_NAME     U25 BK4
 '@T6G_MB_LIB.T6G(SCH_1):PAGE16_I167@PURE_QUANTA.GENOA_SP5(CHIPS)':
 'MGB_CA5': CDS_PINID='MGB_CA5';
NODE_NAME     J16 225
 '@T6G_MB_LIB.T6G(SCH_1):PAGE91_I22@PURE_QUANTA.SCONN288_DDR506112002KQ(CHIPS)':
 'CA5_B': CDS_PINID='CA5_B';
NET_NAME
'M_G_CPU0_SB_CA<6>'
 '@T6G_MB_LIB.T6G(SCH_1):M_G_CPU0_SB_CA'<6>:
 C_SIGNAL='@t6g_mb_lib.t6g(sch_1):m_g_cpu0_sb_ca(6)';
NODE_NAME     U25 BK2
 '@T6G_MB_LIB.T6G(SCH_1):PAGE16_I167@PURE_QUANTA.GENOA_SP5(CHIPS)':
 'MGB_CA6': CDS_PINID='MGB_CA6';
NODE_NAME     J16 82
 '@T6G_MB_LIB.T6G(SCH_1):PAGE91_I22@PURE_QUANTA.SCONN288_DDR506112002KQ(CHIPS)':
 'CA6_B': CDS_PINID='CA6_B';
NET_NAME
'M_G_CPU0_SB_CB<0>'
 '@T6G_MB_LIB.T6G(SCH_1):M_G_CPU0_SB_CB'<0>:
 C_SIGNAL='@t6g_mb_lib.t6g(sch_1):m_g_cpu0_sb_cb(0)';
NODE_NAME     U25 BY2
 '@T6G_MB_LIB.T6G(SCH_1):PAGE16_I167@PURE_QUANTA.GENOA_SP5(CHIPS)':
 'MGB_CHECK0': CDS_PINID='MGB_CHECK0';
NODE_NAME     J16 96
 '@T6G_MB_LIB.T6G(SCH_1):PAGE91_I22@PURE_QUANTA.SCONN288_DDR506112002KQ(CHIPS)':
 'CB0_B': CDS_PINID='CB0_B';
NET_NAME
'M_G_CPU0_SB_CB<1>'
 '@T6G_MB_LIB.T6G(SCH_1):M_G_CPU0_SB_CB'<1>:
 C_SIGNAL='@t6g_mb_lib.t6g(sch_1):m_g_cpu0_sb_cb(1)';
NODE_NAME     U25 CA3
 '@T6G_MB_LIB.T6G(SCH_1):PAGE16_I167@PURE_QUANTA.GENOA_SP5(CHIPS)':
 'MGB_CHECK1': CDS_PINID='MGB_CHECK1';
NODE_NAME     J16 98
 '@T6G_MB_LIB.T6G(SCH_1):PAGE91_I22@PURE_QUANTA.SCONN288_DDR506112002KQ(CHIPS)':
 'CB1_B': CDS_PINID='CB1_B';
NET_NAME
'M_G_CPU0_SB_CB<2>'
 '@T6G_MB_LIB.T6G(SCH_1):M_G_CPU0_SB_CB'<2>:
 C_SIGNAL='@t6g_mb_lib.t6g(sch_1):m_g_cpu0_sb_cb(2)';
NODE_NAME     U25 CA2
 '@T6G_MB_LIB.T6G(SCH_1):PAGE16_I167@PURE_QUANTA.GENOA_SP5(CHIPS)':
 'MGB_CHECK2': CDS_PINID='MGB_CHECK2';
NODE_NAME     J16 241
 '@T6G_MB_LIB.T6G(SCH_1):PAGE91_I22@PURE_QUANTA.SCONN288_DDR506112002KQ(CHIPS)':
 'CB2_B': CDS_PINID='CB2_B';
NET_NAME
'M_G_CPU0_SB_CB<3>'
 '@T6G_MB_LIB.T6G(SCH_1):M_G_CPU0_SB_CB'<3>:
 C_SIGNAL='@t6g_mb_lib.t6g(sch_1):m_g_cpu0_sb_cb(3)';
NODE_NAME     U25 CB4
 '@T6G_MB_LIB.T6G(SCH_1):PAGE16_I167@PURE_QUANTA.GENOA_SP5(CHIPS)':
 'MGB_CHECK3': CDS_PINID='MGB_CHECK3';
NODE_NAME     J16 243
 '@T6G_MB_LIB.T6G(SCH_1):PAGE91_I22@PURE_QUANTA.SCONN288_DDR506112002KQ(CHIPS)':
 'CB3_B': CDS_PINID='CB3_B';
NET_NAME
'M_G_CPU0_SB_CB<4>'
 '@T6G_MB_LIB.T6G(SCH_1):M_G_CPU0_SB_CB'<4>:
 C_SIGNAL='@t6g_mb_lib.t6g(sch_1):m_g_cpu0_sb_cb(4)';
NODE_NAME     U25 BT2
 '@T6G_MB_LIB.T6G(SCH_1):PAGE16_I167@PURE_QUANTA.GENOA_SP5(CHIPS)':
 'MGB_CHECK4': CDS_PINID='MGB_CHECK4';
NODE_NAME     J16 89
 '@T6G_MB_LIB.T6G(SCH_1):PAGE91_I22@PURE_QUANTA.SCONN288_DDR506112002KQ(CHIPS)':
 'CB4_B': CDS_PINID='CB4_B';
NET_NAME
'M_G_CPU0_SB_CB<5>'
 '@T6G_MB_LIB.T6G(SCH_1):M_G_CPU0_SB_CB'<5>:
 C_SIGNAL='@t6g_mb_lib.t6g(sch_1):m_g_cpu0_sb_cb(5)';
NODE_NAME     U25 BU3
 '@T6G_MB_LIB.T6G(SCH_1):PAGE16_I167@PURE_QUANTA.GENOA_SP5(CHIPS)':
 'MGB_CHECK5': CDS_PINID='MGB_CHECK5';
NODE_NAME     J16 91
 '@T6G_MB_LIB.T6G(SCH_1):PAGE91_I22@PURE_QUANTA.SCONN288_DDR506112002KQ(CHIPS)':
 'CB5_B': CDS_PINID='CB5_B';
NET_NAME
'M_G_CPU0_SB_CB<6>'
 '@T6G_MB_LIB.T6G(SCH_1):M_G_CPU0_SB_CB'<6>:
 C_SIGNAL='@t6g_mb_lib.t6g(sch_1):m_g_cpu0_sb_cb(6)';
NODE_NAME     U25 BU2
 '@T6G_MB_LIB.T6G(SCH_1):PAGE16_I167@PURE_QUANTA.GENOA_SP5(CHIPS)':
 'MGB_CHECK6': CDS_PINID='MGB_CHECK6';
NODE_NAME     J16 234
 '@T6G_MB_LIB.T6G(SCH_1):PAGE91_I22@PURE_QUANTA.SCONN288_DDR506112002KQ(CHIPS)':
 'CB6_B': CDS_PINID='CB6_B';
NET_NAME
'M_G_CPU0_SB_CB<7>'
 '@T6G_MB_LIB.T6G(SCH_1):M_G_CPU0_SB_CB'<7>:
 C_SIGNAL='@t6g_mb_lib.t6g(sch_1):m_g_cpu0_sb_cb(7)';
NODE_NAME     U25 BV4
 '@T6G_MB_LIB.T6G(SCH_1):PAGE16_I167@PURE_QUANTA.GENOA_SP5(CHIPS)':
 'MGB_CHECK7': CDS_PINID='MGB_CHECK7';
NODE_NAME     J16 236
 '@T6G_MB_LIB.T6G(SCH_1):PAGE91_I22@PURE_QUANTA.SCONN288_DDR506112002KQ(CHIPS)':
 'CB7_B': CDS_PINID='CB7_B';
NET_NAME
'M_G_CPU0_SB_CS_N<0>'
 '@T6G_MB_LIB.T6G(SCH_1):M_G_CPU0_SB_CS_N'<0>:
 C_SIGNAL='@t6g_mb_lib.t6g(sch_1):m_g_cpu0_sb_cs_n(0)';
NODE_NAME     U25 BM4
 '@T6G_MB_LIB.T6G(SCH_1):PAGE16_I167@PURE_QUANTA.GENOA_SP5(CHIPS)':
 'MGB0_CS_L0': CDS_PINID='MGB0_CS_L0';
NODE_NAME     J16 84
 '@T6G_MB_LIB.T6G(SCH_1):PAGE91_I22@PURE_QUANTA.SCONN288_DDR506112002KQ(CHIPS)':
 'CS0_B_N': CDS_PINID='CS0_B_N';
NET_NAME
'M_G_CPU0_SB_CS_N<1>'
 '@T6G_MB_LIB.T6G(SCH_1):M_G_CPU0_SB_CS_N'<1>:
 C_SIGNAL='@t6g_mb_lib.t6g(sch_1):m_g_cpu0_sb_cs_n(1)';
NODE_NAME     U25 BN2
 '@T6G_MB_LIB.T6G(SCH_1):PAGE16_I167@PURE_QUANTA.GENOA_SP5(CHIPS)':
 'MGB0_CS_L1': CDS_PINID='MGB0_CS_L1';
NODE_NAME     J16 229
 '@T6G_MB_LIB.T6G(SCH_1):PAGE91_I22@PURE_QUANTA.SCONN288_DDR506112002KQ(CHIPS)':
 'CS1_B_N': CDS_PINID='CS1_B_N';
NET_NAME
'M_G_CPU0_SB_DQ<0>'
 '@T6G_MB_LIB.T6G(SCH_1):M_G_CPU0_SB_DQ'<0>:
 C_SIGNAL='@t6g_mb_lib.t6g(sch_1):m_g_cpu0_sb_dq(0)';
NODE_NAME     U25 CB2
 '@T6G_MB_LIB.T6G(SCH_1):PAGE16_I167@PURE_QUANTA.GENOA_SP5(CHIPS)':
 'MGB_DATA0': CDS_PINID='MGB_DATA0';
NODE_NAME     J16 100
 '@T6G_MB_LIB.T6G(SCH_1):PAGE91_I22@PURE_QUANTA.SCONN288_DDR506112002KQ(CHIPS)':
 'DQ0_B': CDS_PINID='DQ0_B';
NET_NAME
'M_G_CPU0_SB_DQ<10>'
 '@T6G_MB_LIB.T6G(SCH_1):M_G_CPU0_SB_DQ'<10>:
 C_SIGNAL='@t6g_mb_lib.t6g(sch_1):m_g_cpu0_sb_dq(10)';
NODE_NAME     U25 CJ2
 '@T6G_MB_LIB.T6G(SCH_1):PAGE16_I167@PURE_QUANTA.GENOA_SP5(CHIPS)':
 'MGB_DATA10': CDS_PINID='MGB_DATA10';
NODE_NAME     J16 256
 '@T6G_MB_LIB.T6G(SCH_1):PAGE91_I22@PURE_QUANTA.SCONN288_DDR506112002KQ(CHIPS)':
 'DQ10_B': CDS_PINID='DQ10_B';
NET_NAME
'M_G_CPU0_SB_DQ<11>'
 '@T6G_MB_LIB.T6G(SCH_1):M_G_CPU0_SB_DQ'<11>:
 C_SIGNAL='@t6g_mb_lib.t6g(sch_1):m_g_cpu0_sb_dq(11)';
NODE_NAME     U25 CK4
 '@T6G_MB_LIB.T6G(SCH_1):PAGE16_I167@PURE_QUANTA.GENOA_SP5(CHIPS)':
 'MGB_DATA11': CDS_PINID='MGB_DATA11';
NODE_NAME     J16 258
 '@T6G_MB_LIB.T6G(SCH_1):PAGE91_I22@PURE_QUANTA.SCONN288_DDR506112002KQ(CHIPS)':
 'DQ11_B': CDS_PINID='DQ11_B';
NET_NAME
'M_G_CPU0_SB_DQ<12>'
 '@T6G_MB_LIB.T6G(SCH_1):M_G_CPU0_SB_DQ'<12>:
 C_SIGNAL='@t6g_mb_lib.t6g(sch_1):m_g_cpu0_sb_dq(12)';
NODE_NAME     U25 CM2
 '@T6G_MB_LIB.T6G(SCH_1):PAGE16_I167@PURE_QUANTA.GENOA_SP5(CHIPS)':
 'MGB_DATA12': CDS_PINID='MGB_DATA12';
NODE_NAME     J16 118
 '@T6G_MB_LIB.T6G(SCH_1):PAGE91_I22@PURE_QUANTA.SCONN288_DDR506112002KQ(CHIPS)':
 'DQ12_B': CDS_PINID='DQ12_B';
NET_NAME
'M_G_CPU0_SB_DQ<13>'
 '@T6G_MB_LIB.T6G(SCH_1):M_G_CPU0_SB_DQ'<13>:
 C_SIGNAL='@t6g_mb_lib.t6g(sch_1):m_g_cpu0_sb_dq(13)';
NODE_NAME     U25 CN3
 '@T6G_MB_LIB.T6G(SCH_1):PAGE16_I167@PURE_QUANTA.GENOA_SP5(CHIPS)':
 'MGB_DATA13': CDS_PINID='MGB_DATA13';
NODE_NAME     J16 120
 '@T6G_MB_LIB.T6G(SCH_1):PAGE91_I22@PURE_QUANTA.SCONN288_DDR506112002KQ(CHIPS)':
 'DQ13_B': CDS_PINID='DQ13_B';
NET_NAME
'M_G_CPU0_SB_DQ<14>'
 '@T6G_MB_LIB.T6G(SCH_1):M_G_CPU0_SB_DQ'<14>:
 C_SIGNAL='@t6g_mb_lib.t6g(sch_1):m_g_cpu0_sb_dq(14)';
NODE_NAME     U25 CN2
 '@T6G_MB_LIB.T6G(SCH_1):PAGE16_I167@PURE_QUANTA.GENOA_SP5(CHIPS)':
 'MGB_DATA14': CDS_PINID='MGB_DATA14';
NODE_NAME     J16 263
 '@T6G_MB_LIB.T6G(SCH_1):PAGE91_I22@PURE_QUANTA.SCONN288_DDR506112002KQ(CHIPS)':
 'DQ14_B': CDS_PINID='DQ14_B';
NET_NAME
'M_G_CPU0_SB_DQ<15>'
 '@T6G_MB_LIB.T6G(SCH_1):M_G_CPU0_SB_DQ'<15>:
 C_SIGNAL='@t6g_mb_lib.t6g(sch_1):m_g_cpu0_sb_dq(15)';
NODE_NAME     U25 CP4
 '@T6G_MB_LIB.T6G(SCH_1):PAGE16_I167@PURE_QUANTA.GENOA_SP5(CHIPS)':
 'MGB_DATA15': CDS_PINID='MGB_DATA15';
NODE_NAME     J16 265
 '@T6G_MB_LIB.T6G(SCH_1):PAGE91_I22@PURE_QUANTA.SCONN288_DDR506112002KQ(CHIPS)':
 'DQ15_B': CDS_PINID='DQ15_B';
NET_NAME
'M_G_CPU0_SB_DQ<16>'
 '@T6G_MB_LIB.T6G(SCH_1):M_G_CPU0_SB_DQ'<16>:
 C_SIGNAL='@t6g_mb_lib.t6g(sch_1):m_g_cpu0_sb_dq(16)';
NODE_NAME     U25 CP2
 '@T6G_MB_LIB.T6G(SCH_1):PAGE16_I167@PURE_QUANTA.GENOA_SP5(CHIPS)':
 'MGB_DATA16': CDS_PINID='MGB_DATA16';
NODE_NAME     J16 122
 '@T6G_MB_LIB.T6G(SCH_1):PAGE91_I22@PURE_QUANTA.SCONN288_DDR506112002KQ(CHIPS)':
 'DQ16_B': CDS_PINID='DQ16_B';
NET_NAME
'M_G_CPU0_SB_DQ<17>'
 '@T6G_MB_LIB.T6G(SCH_1):M_G_CPU0_SB_DQ'<17>:
 C_SIGNAL='@t6g_mb_lib.t6g(sch_1):m_g_cpu0_sb_dq(17)';
NODE_NAME     U25 CR3
 '@T6G_MB_LIB.T6G(SCH_1):PAGE16_I167@PURE_QUANTA.GENOA_SP5(CHIPS)':
 'MGB_DATA17': CDS_PINID='MGB_DATA17';
NODE_NAME     J16 124
 '@T6G_MB_LIB.T6G(SCH_1):PAGE91_I22@PURE_QUANTA.SCONN288_DDR506112002KQ(CHIPS)':
 'DQ17_B': CDS_PINID='DQ17_B';
NET_NAME
'M_G_CPU0_SB_DQ<18>'
 '@T6G_MB_LIB.T6G(SCH_1):M_G_CPU0_SB_DQ'<18>:
 C_SIGNAL='@t6g_mb_lib.t6g(sch_1):m_g_cpu0_sb_dq(18)';
NODE_NAME     U25 CR2
 '@T6G_MB_LIB.T6G(SCH_1):PAGE16_I167@PURE_QUANTA.GENOA_SP5(CHIPS)':
 'MGB_DATA18': CDS_PINID='MGB_DATA18';
NODE_NAME     J16 267
 '@T6G_MB_LIB.T6G(SCH_1):PAGE91_I22@PURE_QUANTA.SCONN288_DDR506112002KQ(CHIPS)':
 'DQ18_B': CDS_PINID='DQ18_B';
NET_NAME
'M_G_CPU0_SB_DQ<19>'
 '@T6G_MB_LIB.T6G(SCH_1):M_G_CPU0_SB_DQ'<19>:
 C_SIGNAL='@t6g_mb_lib.t6g(sch_1):m_g_cpu0_sb_dq(19)';
NODE_NAME     U25 CT4
 '@T6G_MB_LIB.T6G(SCH_1):PAGE16_I167@PURE_QUANTA.GENOA_SP5(CHIPS)':
 'MGB_DATA19': CDS_PINID='MGB_DATA19';
NODE_NAME     J16 269
 '@T6G_MB_LIB.T6G(SCH_1):PAGE91_I22@PURE_QUANTA.SCONN288_DDR506112002KQ(CHIPS)':
 'DQ19_B': CDS_PINID='DQ19_B';
NET_NAME
'M_G_CPU0_SB_DQ<1>'
 '@T6G_MB_LIB.T6G(SCH_1):M_G_CPU0_SB_DQ'<1>:
 C_SIGNAL='@t6g_mb_lib.t6g(sch_1):m_g_cpu0_sb_dq(1)';
NODE_NAME     U25 CC3
 '@T6G_MB_LIB.T6G(SCH_1):PAGE16_I167@PURE_QUANTA.GENOA_SP5(CHIPS)':
 'MGB_DATA1': CDS_PINID='MGB_DATA1';
NODE_NAME     J16 102
 '@T6G_MB_LIB.T6G(SCH_1):PAGE91_I22@PURE_QUANTA.SCONN288_DDR506112002KQ(CHIPS)':
 'DQ1_B': CDS_PINID='DQ1_B';
NET_NAME
'M_G_CPU0_SB_DQ<20>'
 '@T6G_MB_LIB.T6G(SCH_1):M_G_CPU0_SB_DQ'<20>:
 C_SIGNAL='@t6g_mb_lib.t6g(sch_1):m_g_cpu0_sb_dq(20)';
NODE_NAME     U25 CV2
 '@T6G_MB_LIB.T6G(SCH_1):PAGE16_I167@PURE_QUANTA.GENOA_SP5(CHIPS)':
 'MGB_DATA20': CDS_PINID='MGB_DATA20';
NODE_NAME     J16 129
 '@T6G_MB_LIB.T6G(SCH_1):PAGE91_I22@PURE_QUANTA.SCONN288_DDR506112002KQ(CHIPS)':
 'DQ20_B': CDS_PINID='DQ20_B';
NET_NAME
'M_G_CPU0_SB_DQ<21>'
 '@T6G_MB_LIB.T6G(SCH_1):M_G_CPU0_SB_DQ'<21>:
 C_SIGNAL='@t6g_mb_lib.t6g(sch_1):m_g_cpu0_sb_dq(21)';
NODE_NAME     U25 CW3
 '@T6G_MB_LIB.T6G(SCH_1):PAGE16_I167@PURE_QUANTA.GENOA_SP5(CHIPS)':
 'MGB_DATA21': CDS_PINID='MGB_DATA21';
NODE_NAME     J16 131
 '@T6G_MB_LIB.T6G(SCH_1):PAGE91_I22@PURE_QUANTA.SCONN288_DDR506112002KQ(CHIPS)':
 'DQ21_B': CDS_PINID='DQ21_B';
NET_NAME
'M_G_CPU0_SB_DQ<22>'
 '@T6G_MB_LIB.T6G(SCH_1):M_G_CPU0_SB_DQ'<22>:
 C_SIGNAL='@t6g_mb_lib.t6g(sch_1):m_g_cpu0_sb_dq(22)';
NODE_NAME     U25 CW2
 '@T6G_MB_LIB.T6G(SCH_1):PAGE16_I167@PURE_QUANTA.GENOA_SP5(CHIPS)':
 'MGB_DATA22': CDS_PINID='MGB_DATA22';
NODE_NAME     J16 274
 '@T6G_MB_LIB.T6G(SCH_1):PAGE91_I22@PURE_QUANTA.SCONN288_DDR506112002KQ(CHIPS)':
 'DQ22_B': CDS_PINID='DQ22_B';
NET_NAME
'M_G_CPU0_SB_DQ<23>'
 '@T6G_MB_LIB.T6G(SCH_1):M_G_CPU0_SB_DQ'<23>:
 C_SIGNAL='@t6g_mb_lib.t6g(sch_1):m_g_cpu0_sb_dq(23)';
NODE_NAME     U25 CY4
 '@T6G_MB_LIB.T6G(SCH_1):PAGE16_I167@PURE_QUANTA.GENOA_SP5(CHIPS)':
 'MGB_DATA23': CDS_PINID='MGB_DATA23';
NODE_NAME     J16 276
 '@T6G_MB_LIB.T6G(SCH_1):PAGE91_I22@PURE_QUANTA.SCONN288_DDR506112002KQ(CHIPS)':
 'DQ23_B': CDS_PINID='DQ23_B';
NET_NAME
'M_G_CPU0_SB_DQ<24>'
 '@T6G_MB_LIB.T6G(SCH_1):M_G_CPU0_SB_DQ'<24>:
 C_SIGNAL='@t6g_mb_lib.t6g(sch_1):m_g_cpu0_sb_dq(24)';
NODE_NAME     U25 CY2
 '@T6G_MB_LIB.T6G(SCH_1):PAGE16_I167@PURE_QUANTA.GENOA_SP5(CHIPS)':
 'MGB_DATA24': CDS_PINID='MGB_DATA24';
NODE_NAME     J16 133
 '@T6G_MB_LIB.T6G(SCH_1):PAGE91_I22@PURE_QUANTA.SCONN288_DDR506112002KQ(CHIPS)':
 'DQ24_B': CDS_PINID='DQ24_B';
NET_NAME
'M_G_CPU0_SB_DQ<25>'
 '@T6G_MB_LIB.T6G(SCH_1):M_G_CPU0_SB_DQ'<25>:
 C_SIGNAL='@t6g_mb_lib.t6g(sch_1):m_g_cpu0_sb_dq(25)';
NODE_NAME     U25 DA3
 '@T6G_MB_LIB.T6G(SCH_1):PAGE16_I167@PURE_QUANTA.GENOA_SP5(CHIPS)':
 'MGB_DATA25': CDS_PINID='MGB_DATA25';
NODE_NAME     J16 135
 '@T6G_MB_LIB.T6G(SCH_1):PAGE91_I22@PURE_QUANTA.SCONN288_DDR506112002KQ(CHIPS)':
 'DQ25_B': CDS_PINID='DQ25_B';
NET_NAME
'M_G_CPU0_SB_DQ<26>'
 '@T6G_MB_LIB.T6G(SCH_1):M_G_CPU0_SB_DQ'<26>:
 C_SIGNAL='@t6g_mb_lib.t6g(sch_1):m_g_cpu0_sb_dq(26)';
NODE_NAME     U25 DA2
 '@T6G_MB_LIB.T6G(SCH_1):PAGE16_I167@PURE_QUANTA.GENOA_SP5(CHIPS)':
 'MGB_DATA26': CDS_PINID='MGB_DATA26';
NODE_NAME     J16 278
 '@T6G_MB_LIB.T6G(SCH_1):PAGE91_I22@PURE_QUANTA.SCONN288_DDR506112002KQ(CHIPS)':
 'DQ26_B': CDS_PINID='DQ26_B';
NET_NAME
'M_G_CPU0_SB_DQ<27>'
 '@T6G_MB_LIB.T6G(SCH_1):M_G_CPU0_SB_DQ'<27>:
 C_SIGNAL='@t6g_mb_lib.t6g(sch_1):m_g_cpu0_sb_dq(27)';
NODE_NAME     U25 DB4
 '@T6G_MB_LIB.T6G(SCH_1):PAGE16_I167@PURE_QUANTA.GENOA_SP5(CHIPS)':
 'MGB_DATA27': CDS_PINID='MGB_DATA27';
NODE_NAME     J16 280
 '@T6G_MB_LIB.T6G(SCH_1):PAGE91_I22@PURE_QUANTA.SCONN288_DDR506112002KQ(CHIPS)':
 'DQ27_B': CDS_PINID='DQ27_B';
NET_NAME
'M_G_CPU0_SB_DQ<28>'
 '@T6G_MB_LIB.T6G(SCH_1):M_G_CPU0_SB_DQ'<28>:
 C_SIGNAL='@t6g_mb_lib.t6g(sch_1):m_g_cpu0_sb_dq(28)';
NODE_NAME     U25 DD2
 '@T6G_MB_LIB.T6G(SCH_1):PAGE16_I167@PURE_QUANTA.GENOA_SP5(CHIPS)':
 'MGB_DATA28': CDS_PINID='MGB_DATA28';
NODE_NAME     J16 140
 '@T6G_MB_LIB.T6G(SCH_1):PAGE91_I22@PURE_QUANTA.SCONN288_DDR506112002KQ(CHIPS)':
 'DQ28_B': CDS_PINID='DQ28_B';
NET_NAME
'M_G_CPU0_SB_DQ<29>'
 '@T6G_MB_LIB.T6G(SCH_1):M_G_CPU0_SB_DQ'<29>:
 C_SIGNAL='@t6g_mb_lib.t6g(sch_1):m_g_cpu0_sb_dq(29)';
NODE_NAME     U25 DE3
 '@T6G_MB_LIB.T6G(SCH_1):PAGE16_I167@PURE_QUANTA.GENOA_SP5(CHIPS)':
 'MGB_DATA29': CDS_PINID='MGB_DATA29';
NODE_NAME     J16 142
 '@T6G_MB_LIB.T6G(SCH_1):PAGE91_I22@PURE_QUANTA.SCONN288_DDR506112002KQ(CHIPS)':
 'DQ29_B': CDS_PINID='DQ29_B';
NET_NAME
'M_G_CPU0_SB_DQ<2>'
 '@T6G_MB_LIB.T6G(SCH_1):M_G_CPU0_SB_DQ'<2>:
 C_SIGNAL='@t6g_mb_lib.t6g(sch_1):m_g_cpu0_sb_dq(2)';
NODE_NAME     U25 CC2
 '@T6G_MB_LIB.T6G(SCH_1):PAGE16_I167@PURE_QUANTA.GENOA_SP5(CHIPS)':
 'MGB_DATA2': CDS_PINID='MGB_DATA2';
NODE_NAME     J16 245
 '@T6G_MB_LIB.T6G(SCH_1):PAGE91_I22@PURE_QUANTA.SCONN288_DDR506112002KQ(CHIPS)':
 'DQ2_B': CDS_PINID='DQ2_B';
NET_NAME
'M_G_CPU0_SB_DQ<30>'
 '@T6G_MB_LIB.T6G(SCH_1):M_G_CPU0_SB_DQ'<30>:
 C_SIGNAL='@t6g_mb_lib.t6g(sch_1):m_g_cpu0_sb_dq(30)';
NODE_NAME     U25 DE2
 '@T6G_MB_LIB.T6G(SCH_1):PAGE16_I167@PURE_QUANTA.GENOA_SP5(CHIPS)':
 'MGB_DATA30': CDS_PINID='MGB_DATA30';
NODE_NAME     J16 285
 '@T6G_MB_LIB.T6G(SCH_1):PAGE91_I22@PURE_QUANTA.SCONN288_DDR506112002KQ(CHIPS)':
 'DQ30_B': CDS_PINID='DQ30_B';
NET_NAME
'M_G_CPU0_SB_DQ<31>'
 '@T6G_MB_LIB.T6G(SCH_1):M_G_CPU0_SB_DQ'<31>:
 C_SIGNAL='@t6g_mb_lib.t6g(sch_1):m_g_cpu0_sb_dq(31)';
NODE_NAME     U25 DF2
 '@T6G_MB_LIB.T6G(SCH_1):PAGE16_I167@PURE_QUANTA.GENOA_SP5(CHIPS)':
 'MGB_DATA31': CDS_PINID='MGB_DATA31';
NODE_NAME     J16 287
 '@T6G_MB_LIB.T6G(SCH_1):PAGE91_I22@PURE_QUANTA.SCONN288_DDR506112002KQ(CHIPS)':
 'DQ31_B': CDS_PINID='DQ31_B';
NET_NAME
'M_G_CPU0_SB_DQ<3>'
 '@T6G_MB_LIB.T6G(SCH_1):M_G_CPU0_SB_DQ'<3>:
 C_SIGNAL='@t6g_mb_lib.t6g(sch_1):m_g_cpu0_sb_dq(3)';
NODE_NAME     U25 CD4
 '@T6G_MB_LIB.T6G(SCH_1):PAGE16_I167@PURE_QUANTA.GENOA_SP5(CHIPS)':
 'MGB_DATA3': CDS_PINID='MGB_DATA3';
NODE_NAME     J16 247
 '@T6G_MB_LIB.T6G(SCH_1):PAGE91_I22@PURE_QUANTA.SCONN288_DDR506112002KQ(CHIPS)':
 'DQ3_B': CDS_PINID='DQ3_B';
NET_NAME
'M_G_CPU0_SB_DQ<4>'
 '@T6G_MB_LIB.T6G(SCH_1):M_G_CPU0_SB_DQ'<4>:
 C_SIGNAL='@t6g_mb_lib.t6g(sch_1):m_g_cpu0_sb_dq(4)';
NODE_NAME     U25 CF2
 '@T6G_MB_LIB.T6G(SCH_1):PAGE16_I167@PURE_QUANTA.GENOA_SP5(CHIPS)':
 'MGB_DATA4': CDS_PINID='MGB_DATA4';
NODE_NAME     J16 107
 '@T6G_MB_LIB.T6G(SCH_1):PAGE91_I22@PURE_QUANTA.SCONN288_DDR506112002KQ(CHIPS)':
 'DQ4_B': CDS_PINID='DQ4_B';
NET_NAME
'M_G_CPU0_SB_DQ<5>'
 '@T6G_MB_LIB.T6G(SCH_1):M_G_CPU0_SB_DQ'<5>:
 C_SIGNAL='@t6g_mb_lib.t6g(sch_1):m_g_cpu0_sb_dq(5)';
NODE_NAME     U25 CG3
 '@T6G_MB_LIB.T6G(SCH_1):PAGE16_I167@PURE_QUANTA.GENOA_SP5(CHIPS)':
 'MGB_DATA5': CDS_PINID='MGB_DATA5';
NODE_NAME     J16 109
 '@T6G_MB_LIB.T6G(SCH_1):PAGE91_I22@PURE_QUANTA.SCONN288_DDR506112002KQ(CHIPS)':
 'DQ5_B': CDS_PINID='DQ5_B';
NET_NAME
'M_G_CPU0_SB_DQ<6>'
 '@T6G_MB_LIB.T6G(SCH_1):M_G_CPU0_SB_DQ'<6>:
 C_SIGNAL='@t6g_mb_lib.t6g(sch_1):m_g_cpu0_sb_dq(6)';
NODE_NAME     U25 CG2
 '@T6G_MB_LIB.T6G(SCH_1):PAGE16_I167@PURE_QUANTA.GENOA_SP5(CHIPS)':
 'MGB_DATA6': CDS_PINID='MGB_DATA6';
NODE_NAME     J16 252
 '@T6G_MB_LIB.T6G(SCH_1):PAGE91_I22@PURE_QUANTA.SCONN288_DDR506112002KQ(CHIPS)':
 'DQ6_B': CDS_PINID='DQ6_B';
NET_NAME
'M_G_CPU0_SB_DQ<7>'
 '@T6G_MB_LIB.T6G(SCH_1):M_G_CPU0_SB_DQ'<7>:
 C_SIGNAL='@t6g_mb_lib.t6g(sch_1):m_g_cpu0_sb_dq(7)';
NODE_NAME     U25 CH4
 '@T6G_MB_LIB.T6G(SCH_1):PAGE16_I167@PURE_QUANTA.GENOA_SP5(CHIPS)':
 'MGB_DATA7': CDS_PINID='MGB_DATA7';
NODE_NAME     J16 254
 '@T6G_MB_LIB.T6G(SCH_1):PAGE91_I22@PURE_QUANTA.SCONN288_DDR506112002KQ(CHIPS)':
 'DQ7_B': CDS_PINID='DQ7_B';
NET_NAME
'M_G_CPU0_SB_DQ<8>'
 '@T6G_MB_LIB.T6G(SCH_1):M_G_CPU0_SB_DQ'<8>:
 C_SIGNAL='@t6g_mb_lib.t6g(sch_1):m_g_cpu0_sb_dq(8)';
NODE_NAME     U25 CH2
 '@T6G_MB_LIB.T6G(SCH_1):PAGE16_I167@PURE_QUANTA.GENOA_SP5(CHIPS)':
 'MGB_DATA8': CDS_PINID='MGB_DATA8';
NODE_NAME     J16 111
 '@T6G_MB_LIB.T6G(SCH_1):PAGE91_I22@PURE_QUANTA.SCONN288_DDR506112002KQ(CHIPS)':
 'DQ8_B': CDS_PINID='DQ8_B';
NET_NAME
'M_G_CPU0_SB_DQ<9>'
 '@T6G_MB_LIB.T6G(SCH_1):M_G_CPU0_SB_DQ'<9>:
 C_SIGNAL='@t6g_mb_lib.t6g(sch_1):m_g_cpu0_sb_dq(9)';
NODE_NAME     U25 CJ3
 '@T6G_MB_LIB.T6G(SCH_1):PAGE16_I167@PURE_QUANTA.GENOA_SP5(CHIPS)':
 'MGB_DATA9': CDS_PINID='MGB_DATA9';
NODE_NAME     J16 113
 '@T6G_MB_LIB.T6G(SCH_1):PAGE91_I22@PURE_QUANTA.SCONN288_DDR506112002KQ(CHIPS)':
 'DQ9_B': CDS_PINID='DQ9_B';
NET_NAME
'M_G_CPU0_SB_DQS_DN<0>'
 '@T6G_MB_LIB.T6G(SCH_1):M_G_CPU0_SB_DQS_DN'<0>:
 C_SIGNAL='@t6g_mb_lib.t6g(sch_1):m_g_cpu0_sb_dqs_dn(0)';
NODE_NAME     U25 CE2
 '@T6G_MB_LIB.T6G(SCH_1):PAGE16_I167@PURE_QUANTA.GENOA_SP5(CHIPS)':
 'MGB_DQS_L0': CDS_PINID='MGB_DQS_L0';
NODE_NAME     J16 105
 '@T6G_MB_LIB.T6G(SCH_1):PAGE91_I236@PURE_QUANTA.SCONN288_DDR506112002KQ(CHIPS)':
 'DQS0_B_C': CDS_PINID='DQS0_B_C';
NET_NAME
'M_G_CPU0_SB_DQS_DN<1>'
 '@T6G_MB_LIB.T6G(SCH_1):M_G_CPU0_SB_DQS_DN'<1>:
 C_SIGNAL='@t6g_mb_lib.t6g(sch_1):m_g_cpu0_sb_dqs_dn(1)';
NODE_NAME     U25 CL2
 '@T6G_MB_LIB.T6G(SCH_1):PAGE16_I167@PURE_QUANTA.GENOA_SP5(CHIPS)':
 'MGB_DQS_L1': CDS_PINID='MGB_DQS_L1';
NODE_NAME     J16 116
 '@T6G_MB_LIB.T6G(SCH_1):PAGE91_I236@PURE_QUANTA.SCONN288_DDR506112002KQ(CHIPS)':
 'DQS1_B_C': CDS_PINID='DQS1_B_C';
NET_NAME
'M_G_CPU0_SB_DQS_DN<2>'
 '@T6G_MB_LIB.T6G(SCH_1):M_G_CPU0_SB_DQS_DN'<2>:
 C_SIGNAL='@t6g_mb_lib.t6g(sch_1):m_g_cpu0_sb_dqs_dn(2)';
NODE_NAME     U25 CU2
 '@T6G_MB_LIB.T6G(SCH_1):PAGE16_I167@PURE_QUANTA.GENOA_SP5(CHIPS)':
 'MGB_DQS_L2': CDS_PINID='MGB_DQS_L2';
NODE_NAME     J16 127
 '@T6G_MB_LIB.T6G(SCH_1):PAGE91_I236@PURE_QUANTA.SCONN288_DDR506112002KQ(CHIPS)':
 'DQS2_B_C': CDS_PINID='DQS2_B_C';
NET_NAME
'M_G_CPU0_SB_DQS_DN<3>'
 '@T6G_MB_LIB.T6G(SCH_1):M_G_CPU0_SB_DQS_DN'<3>:
 C_SIGNAL='@t6g_mb_lib.t6g(sch_1):m_g_cpu0_sb_dqs_dn(3)';
NODE_NAME     U25 DC2
 '@T6G_MB_LIB.T6G(SCH_1):PAGE16_I167@PURE_QUANTA.GENOA_SP5(CHIPS)':
 'MGB_DQS_L3': CDS_PINID='MGB_DQS_L3';
NODE_NAME     J16 138
 '@T6G_MB_LIB.T6G(SCH_1):PAGE91_I236@PURE_QUANTA.SCONN288_DDR506112002KQ(CHIPS)':
 'DQS3_B_C': CDS_PINID='DQS3_B_C';
NET_NAME
'M_G_CPU0_SB_DQS_DN<4>'
 '@T6G_MB_LIB.T6G(SCH_1):M_G_CPU0_SB_DQS_DN'<4>:
 C_SIGNAL='@t6g_mb_lib.t6g(sch_1):m_g_cpu0_sb_dqs_dn(4)';
NODE_NAME     U25 BW3
 '@T6G_MB_LIB.T6G(SCH_1):PAGE16_I167@PURE_QUANTA.GENOA_SP5(CHIPS)':
 'MGB_DQS_L4': CDS_PINID='MGB_DQS_L4';
NODE_NAME     J16 238
 '@T6G_MB_LIB.T6G(SCH_1):PAGE91_I236@PURE_QUANTA.SCONN288_DDR506112002KQ(CHIPS)':
 'DQS4_B_C': CDS_PINID='DQS4_B_C';
NET_NAME
'M_G_CPU0_SB_DQS_DN<5>'
 '@T6G_MB_LIB.T6G(SCH_1):M_G_CPU0_SB_DQS_DN'<5>:
 C_SIGNAL='@t6g_mb_lib.t6g(sch_1):m_g_cpu0_sb_dqs_dn(5)';
NODE_NAME     U25 CE3
 '@T6G_MB_LIB.T6G(SCH_1):PAGE16_I167@PURE_QUANTA.GENOA_SP5(CHIPS)':
 'MGB_DQS_L5': CDS_PINID='MGB_DQS_L5';
NODE_NAME     J16 249
 '@T6G_MB_LIB.T6G(SCH_1):PAGE91_I236@PURE_QUANTA.SCONN288_DDR506112002KQ(CHIPS)':
 'DQS5_B_C||TDQS5_B_C': CDS_PINID='\dqs5_b_c||tdqs5_b_c\';
NET_NAME
'M_G_CPU0_SB_DQS_DN<6>'
 '@T6G_MB_LIB.T6G(SCH_1):M_G_CPU0_SB_DQS_DN'<6>:
 C_SIGNAL='@t6g_mb_lib.t6g(sch_1):m_g_cpu0_sb_dqs_dn(6)';
NODE_NAME     U25 CL3
 '@T6G_MB_LIB.T6G(SCH_1):PAGE16_I167@PURE_QUANTA.GENOA_SP5(CHIPS)':
 'MGB_DQS_L6': CDS_PINID='MGB_DQS_L6';
NODE_NAME     J16 260
 '@T6G_MB_LIB.T6G(SCH_1):PAGE91_I236@PURE_QUANTA.SCONN288_DDR506112002KQ(CHIPS)':
 'DQS6_B_C||TDQS6_B_C': CDS_PINID='\dqs6_b_c||tdqs6_b_c\';
NET_NAME
'M_G_CPU0_SB_DQS_DN<7>'
 '@T6G_MB_LIB.T6G(SCH_1):M_G_CPU0_SB_DQS_DN'<7>:
 C_SIGNAL='@t6g_mb_lib.t6g(sch_1):m_g_cpu0_sb_dqs_dn(7)';
NODE_NAME     U25 CU3
 '@T6G_MB_LIB.T6G(SCH_1):PAGE16_I167@PURE_QUANTA.GENOA_SP5(CHIPS)':
 'MGB_DQS_L7': CDS_PINID='MGB_DQS_L7';
NODE_NAME     J16 271
 '@T6G_MB_LIB.T6G(SCH_1):PAGE91_I236@PURE_QUANTA.SCONN288_DDR506112002KQ(CHIPS)':
 'DQS7_B_C||TDQS7_B_C': CDS_PINID='\dqs7_b_c||tdqs7_b_c\';
NET_NAME
'M_G_CPU0_SB_DQS_DN<8>'
 '@T6G_MB_LIB.T6G(SCH_1):M_G_CPU0_SB_DQS_DN'<8>:
 C_SIGNAL='@t6g_mb_lib.t6g(sch_1):m_g_cpu0_sb_dqs_dn(8)';
NODE_NAME     U25 DC3
 '@T6G_MB_LIB.T6G(SCH_1):PAGE16_I167@PURE_QUANTA.GENOA_SP5(CHIPS)':
 'MGB_DQS_L8': CDS_PINID='MGB_DQS_L8';
NODE_NAME     J16 282
 '@T6G_MB_LIB.T6G(SCH_1):PAGE91_I236@PURE_QUANTA.SCONN288_DDR506112002KQ(CHIPS)':
 'DQS8_B_C||TDQS8_B_C': CDS_PINID='\dqs8_b_c||tdqs8_b_c\';
NET_NAME
'M_G_CPU0_SB_DQS_DN<9>'
 '@T6G_MB_LIB.T6G(SCH_1):M_G_CPU0_SB_DQS_DN'<9>:
 C_SIGNAL='@t6g_mb_lib.t6g(sch_1):m_g_cpu0_sb_dqs_dn(9)';
NODE_NAME     U25 BW2
 '@T6G_MB_LIB.T6G(SCH_1):PAGE16_I167@PURE_QUANTA.GENOA_SP5(CHIPS)':
 'MGB_DQS_L9': CDS_PINID='MGB_DQS_L9';
NODE_NAME     J16 94
 '@T6G_MB_LIB.T6G(SCH_1):PAGE91_I236@PURE_QUANTA.SCONN288_DDR506112002KQ(CHIPS)':
 'DQS9_B_C||TDQS9_B_C': CDS_PINID='\dqs9_b_c||tdqs9_b_c\';
NET_NAME
'M_G_CPU0_SB_DQS_DP<0>'
 '@T6G_MB_LIB.T6G(SCH_1):M_G_CPU0_SB_DQS_DP'<0>:
 C_SIGNAL='@t6g_mb_lib.t6g(sch_1):m_g_cpu0_sb_dqs_dp(0)';
NODE_NAME     U25 CD2
 '@T6G_MB_LIB.T6G(SCH_1):PAGE16_I167@PURE_QUANTA.GENOA_SP5(CHIPS)':
 'MGB_DQS_H0': CDS_PINID='MGB_DQS_H0';
NODE_NAME     J16 104
 '@T6G_MB_LIB.T6G(SCH_1):PAGE91_I236@PURE_QUANTA.SCONN288_DDR506112002KQ(CHIPS)':
 'DQS0_B_T': CDS_PINID='DQS0_B_T';
NET_NAME
'M_G_CPU0_SB_DQS_DP<1>'
 '@T6G_MB_LIB.T6G(SCH_1):M_G_CPU0_SB_DQS_DP'<1>:
 C_SIGNAL='@t6g_mb_lib.t6g(sch_1):m_g_cpu0_sb_dqs_dp(1)';
NODE_NAME     U25 CK2
 '@T6G_MB_LIB.T6G(SCH_1):PAGE16_I167@PURE_QUANTA.GENOA_SP5(CHIPS)':
 'MGB_DQS_H1': CDS_PINID='MGB_DQS_H1';
NODE_NAME     J16 115
 '@T6G_MB_LIB.T6G(SCH_1):PAGE91_I236@PURE_QUANTA.SCONN288_DDR506112002KQ(CHIPS)':
 'DQS1_B_T': CDS_PINID='DQS1_B_T';
NET_NAME
'M_G_CPU0_SB_DQS_DP<2>'
 '@T6G_MB_LIB.T6G(SCH_1):M_G_CPU0_SB_DQS_DP'<2>:
 C_SIGNAL='@t6g_mb_lib.t6g(sch_1):m_g_cpu0_sb_dqs_dp(2)';
NODE_NAME     U25 CT2
 '@T6G_MB_LIB.T6G(SCH_1):PAGE16_I167@PURE_QUANTA.GENOA_SP5(CHIPS)':
 'MGB_DQS_H2': CDS_PINID='MGB_DQS_H2';
NODE_NAME     J16 126
 '@T6G_MB_LIB.T6G(SCH_1):PAGE91_I236@PURE_QUANTA.SCONN288_DDR506112002KQ(CHIPS)':
 'DQS2_B_T': CDS_PINID='DQS2_B_T';
NET_NAME
'M_G_CPU0_SB_DQS_DP<3>'
 '@T6G_MB_LIB.T6G(SCH_1):M_G_CPU0_SB_DQS_DP'<3>:
 C_SIGNAL='@t6g_mb_lib.t6g(sch_1):m_g_cpu0_sb_dqs_dp(3)';
NODE_NAME     U25 DB2
 '@T6G_MB_LIB.T6G(SCH_1):PAGE16_I167@PURE_QUANTA.GENOA_SP5(CHIPS)':
 'MGB_DQS_H3': CDS_PINID='MGB_DQS_H3';
NODE_NAME     J16 137
 '@T6G_MB_LIB.T6G(SCH_1):PAGE91_I236@PURE_QUANTA.SCONN288_DDR506112002KQ(CHIPS)':
 'DQS3_B_T': CDS_PINID='DQS3_B_T';
NET_NAME
'M_G_CPU0_SB_DQS_DP<4>'
 '@T6G_MB_LIB.T6G(SCH_1):M_G_CPU0_SB_DQS_DP'<4>:
 C_SIGNAL='@t6g_mb_lib.t6g(sch_1):m_g_cpu0_sb_dqs_dp(4)';
NODE_NAME     U25 BY4
 '@T6G_MB_LIB.T6G(SCH_1):PAGE16_I167@PURE_QUANTA.GENOA_SP5(CHIPS)':
 'MGB_DQS_H4': CDS_PINID='MGB_DQS_H4';
NODE_NAME     J16 239
 '@T6G_MB_LIB.T6G(SCH_1):PAGE91_I236@PURE_QUANTA.SCONN288_DDR506112002KQ(CHIPS)':
 'DQS4_B_T': CDS_PINID='DQS4_B_T';
NET_NAME
'M_G_CPU0_SB_DQS_DP<5>'
 '@T6G_MB_LIB.T6G(SCH_1):M_G_CPU0_SB_DQS_DP'<5>:
 C_SIGNAL='@t6g_mb_lib.t6g(sch_1):m_g_cpu0_sb_dqs_dp(5)';
NODE_NAME     U25 CF4
 '@T6G_MB_LIB.T6G(SCH_1):PAGE16_I167@PURE_QUANTA.GENOA_SP5(CHIPS)':
 'MGB_DQS_H5': CDS_PINID='MGB_DQS_H5';
NODE_NAME     J16 250
 '@T6G_MB_LIB.T6G(SCH_1):PAGE91_I236@PURE_QUANTA.SCONN288_DDR506112002KQ(CHIPS)':
 'DQS5_B_T||TDQS5_B_T': CDS_PINID='\dqs5_b_t||tdqs5_b_t\';
NET_NAME
'M_G_CPU0_SB_DQS_DP<6>'
 '@T6G_MB_LIB.T6G(SCH_1):M_G_CPU0_SB_DQS_DP'<6>:
 C_SIGNAL='@t6g_mb_lib.t6g(sch_1):m_g_cpu0_sb_dqs_dp(6)';
NODE_NAME     U25 CM4
 '@T6G_MB_LIB.T6G(SCH_1):PAGE16_I167@PURE_QUANTA.GENOA_SP5(CHIPS)':
 'MGB_DQS_H6': CDS_PINID='MGB_DQS_H6';
NODE_NAME     J16 261
 '@T6G_MB_LIB.T6G(SCH_1):PAGE91_I236@PURE_QUANTA.SCONN288_DDR506112002KQ(CHIPS)':
 'DQS6_B_T||TDQS6_B_T': CDS_PINID='\dqs6_b_t||tdqs6_b_t\';
NET_NAME
'M_G_CPU0_SB_DQS_DP<7>'
 '@T6G_MB_LIB.T6G(SCH_1):M_G_CPU0_SB_DQS_DP'<7>:
 C_SIGNAL='@t6g_mb_lib.t6g(sch_1):m_g_cpu0_sb_dqs_dp(7)';
NODE_NAME     U25 CV4
 '@T6G_MB_LIB.T6G(SCH_1):PAGE16_I167@PURE_QUANTA.GENOA_SP5(CHIPS)':
 'MGB_DQS_H7': CDS_PINID='MGB_DQS_H7';
NODE_NAME     J16 272
 '@T6G_MB_LIB.T6G(SCH_1):PAGE91_I236@PURE_QUANTA.SCONN288_DDR506112002KQ(CHIPS)':
 'DQS7_B_T||TDQS7_B_T': CDS_PINID='\dqs7_b_t||tdqs7_b_t\';
NET_NAME
'M_G_CPU0_SB_DQS_DP<8>'
 '@T6G_MB_LIB.T6G(SCH_1):M_G_CPU0_SB_DQS_DP'<8>:
 C_SIGNAL='@t6g_mb_lib.t6g(sch_1):m_g_cpu0_sb_dqs_dp(8)';
NODE_NAME     U25 DD4
 '@T6G_MB_LIB.T6G(SCH_1):PAGE16_I167@PURE_QUANTA.GENOA_SP5(CHIPS)':
 'MGB_DQS_H8': CDS_PINID='MGB_DQS_H8';
NODE_NAME     J16 283
 '@T6G_MB_LIB.T6G(SCH_1):PAGE91_I236@PURE_QUANTA.SCONN288_DDR506112002KQ(CHIPS)':
 'DQS8_B_T||TDQS8_B_T': CDS_PINID='\dqs8_b_t||tdqs8_b_t\';
NET_NAME
'M_G_CPU0_SB_DQS_DP<9>'
 '@T6G_MB_LIB.T6G(SCH_1):M_G_CPU0_SB_DQS_DP'<9>:
 C_SIGNAL='@t6g_mb_lib.t6g(sch_1):m_g_cpu0_sb_dqs_dp(9)';
NODE_NAME     U25 BV2
 '@T6G_MB_LIB.T6G(SCH_1):PAGE16_I167@PURE_QUANTA.GENOA_SP5(CHIPS)':
 'MGB_DQS_H9': CDS_PINID='MGB_DQS_H9';
NODE_NAME     J16 93
 '@T6G_MB_LIB.T6G(SCH_1):PAGE91_I236@PURE_QUANTA.SCONN288_DDR506112002KQ(CHIPS)':
 'DQS9_B_T||TDQS9_B_T||DBI4_B_N': CDS_PINID='\dqs9_b_t||tdqs9_b_t||dbi4_b_n\';
NET_NAME
'M_G_CPU0_SB_PAR'
 '@T6G_MB_LIB.T6G(SCH_1):M_G_CPU0_SB_PAR':
 C_SIGNAL='@t6g_mb_lib.t6g(sch_1):m_g_cpu0_sb_par';
NODE_NAME     U25 BL3
 '@T6G_MB_LIB.T6G(SCH_1):PAGE16_I167@PURE_QUANTA.GENOA_SP5(CHIPS)':
 'MGB_PAR': CDS_PINID='MGB_PAR';
NODE_NAME     J16 227
 '@T6G_MB_LIB.T6G(SCH_1):PAGE91_I22@PURE_QUANTA.SCONN288_DDR506112002KQ(CHIPS)':
 'PAR_B': CDS_PINID='PAR_B';
NET_NAME
'M_G_CPU0_SB_RSP<0>'
 '@T6G_MB_LIB.T6G(SCH_1):M_G_CPU0_SB_RSP'<0>:
 C_SIGNAL='@t6g_mb_lib.t6g(sch_1):m_g_cpu0_sb_rsp(0)';
NODE_NAME     U25 BP2
 '@T6G_MB_LIB.T6G(SCH_1):PAGE16_I167@PURE_QUANTA.GENOA_SP5(CHIPS)':
 'MGB0_RSP_L': CDS_PINID='MGB0_RSP_L';
NODE_NAME     J16 87
 '@T6G_MB_LIB.T6G(SCH_1):PAGE91_I22@PURE_QUANTA.SCONN288_DDR506112002KQ(CHIPS)':
 'LBS||RSP_B_N': CDS_PINID='\lbs||rsp_b_n\';
NET_NAME
'M_G_CPU1_ALERT_N'
 '@T6G_MB_LIB.T6G(SCH_1):M_G_CPU1_ALERT_N':
 C_SIGNAL='@t6g_mb_lib.t6g(sch_1):m_g_cpu1_alert_n';
NODE_NAME     R506 1
 '@T6G_MB_LIB.T6G(SCH_1):PAGE43_I322@PURE_QUANTA.Q_RES(CHIPS)':
 'A': CDS_PINID='A';
NODE_NAME     J102 62
 '@T6G_MB_LIB.T6G(SCH_1):PAGE103_I22@PURE_QUANTA.SCONN288_DDR506112002KQ(CHIPS)':
 'ALERT_N': CDS_PINID='ALERT_N';
NET_NAME
'M_G_CPU1_ALERT_R_N'
 '@T6G_MB_LIB.T6G(SCH_1):M_G_CPU1_ALERT_R_N':
 C_SIGNAL='@t6g_mb_lib.t6g(sch_1):m_g_cpu1_alert_r_n';
NODE_NAME     U26 AR2
 '@T6G_MB_LIB.T6G(SCH_1):PAGE43_I167@PURE_QUANTA.GENOA_SP5(CHIPS)':
 'MG_ALERT_L': CDS_PINID='MG_ALERT_L';
NODE_NAME     R506 2
 '@T6G_MB_LIB.T6G(SCH_1):PAGE43_I322@PURE_QUANTA.Q_RES(CHIPS)':
 'B': CDS_PINID='B';
NET_NAME
'M_G_CPU1_CLK_DN<0>'
 '@T6G_MB_LIB.T6G(SCH_1):M_G_CPU1_CLK_DN'<0>:
 C_SIGNAL='@t6g_mb_lib.t6g(sch_1):m_g_cpu1_clk_dn(0)';
NODE_NAME     U26 BD2
 '@T6G_MB_LIB.T6G(SCH_1):PAGE43_I167@PURE_QUANTA.GENOA_SP5(CHIPS)':
 'MG0_CLK_L': CDS_PINID='MG0_CLK_L';
NODE_NAME     J102 218
 '@T6G_MB_LIB.T6G(SCH_1):PAGE103_I22@PURE_QUANTA.SCONN288_DDR506112002KQ(CHIPS)':
 'CK_C': CDS_PINID='CK_C';
NET_NAME
'M_G_CPU1_CLK_DP<0>'
 '@T6G_MB_LIB.T6G(SCH_1):M_G_CPU1_CLK_DP'<0>:
 C_SIGNAL='@t6g_mb_lib.t6g(sch_1):m_g_cpu1_clk_dp(0)';
NODE_NAME     U26 BC2
 '@T6G_MB_LIB.T6G(SCH_1):PAGE43_I167@PURE_QUANTA.GENOA_SP5(CHIPS)':
 'MG0_CLK_H': CDS_PINID='MG0_CLK_H';
NODE_NAME     J102 217
 '@T6G_MB_LIB.T6G(SCH_1):PAGE103_I22@PURE_QUANTA.SCONN288_DDR506112002KQ(CHIPS)':
 'CK_T': CDS_PINID='CK_T';
NET_NAME
'M_G_CPU1_RESET_N'
 '@T6G_MB_LIB.T6G(SCH_1):M_G_CPU1_RESET_N':
 C_SIGNAL='@t6g_mb_lib.t6g(sch_1):m_g_cpu1_reset_n';
NODE_NAME     U26 AT2
 '@T6G_MB_LIB.T6G(SCH_1):PAGE43_I167@PURE_QUANTA.GENOA_SP5(CHIPS)':
 'MG_RESET_L': CDS_PINID='MG_RESET_L';
NODE_NAME     J102 207
 '@T6G_MB_LIB.T6G(SCH_1):PAGE103_I22@PURE_QUANTA.SCONN288_DDR506112002KQ(CHIPS)':
 'RESET_N': CDS_PINID='RESET_N';
NET_NAME
'M_G_CPU1_SA_CA<0>'
 '@T6G_MB_LIB.T6G(SCH_1):M_G_CPU1_SA_CA'<0>:
 C_SIGNAL='@t6g_mb_lib.t6g(sch_1):m_g_cpu1_sa_ca(0)';
NODE_NAME     U26 AW2
 '@T6G_MB_LIB.T6G(SCH_1):PAGE43_I167@PURE_QUANTA.GENOA_SP5(CHIPS)':
 'MGA_CA0': CDS_PINID='MGA_CA0';
NODE_NAME     J102 66
 '@T6G_MB_LIB.T6G(SCH_1):PAGE103_I22@PURE_QUANTA.SCONN288_DDR506112002KQ(CHIPS)':
 'CA0_A': CDS_PINID='CA0_A';
NET_NAME
'M_G_CPU1_SA_CA<1>'
 '@T6G_MB_LIB.T6G(SCH_1):M_G_CPU1_SA_CA'<1>:
 C_SIGNAL='@t6g_mb_lib.t6g(sch_1):m_g_cpu1_sa_ca(1)';
NODE_NAME     U26 AY2
 '@T6G_MB_LIB.T6G(SCH_1):PAGE43_I167@PURE_QUANTA.GENOA_SP5(CHIPS)':
 'MGA_CA1': CDS_PINID='MGA_CA1';
NODE_NAME     J102 211
 '@T6G_MB_LIB.T6G(SCH_1):PAGE103_I22@PURE_QUANTA.SCONN288_DDR506112002KQ(CHIPS)':
 'CA1_A': CDS_PINID='CA1_A';
NET_NAME
'M_G_CPU1_SA_CA<2>'
 '@T6G_MB_LIB.T6G(SCH_1):M_G_CPU1_SA_CA'<2>:
 C_SIGNAL='@t6g_mb_lib.t6g(sch_1):m_g_cpu1_sa_ca(2)';
NODE_NAME     U26 AY4
 '@T6G_MB_LIB.T6G(SCH_1):PAGE43_I167@PURE_QUANTA.GENOA_SP5(CHIPS)':
 'MGA_CA2': CDS_PINID='MGA_CA2';
NODE_NAME     J102 68
 '@T6G_MB_LIB.T6G(SCH_1):PAGE103_I22@PURE_QUANTA.SCONN288_DDR506112002KQ(CHIPS)':
 'CA2_A': CDS_PINID='CA2_A';
NET_NAME
'M_G_CPU1_SA_CA<3>'
 '@T6G_MB_LIB.T6G(SCH_1):M_G_CPU1_SA_CA'<3>:
 C_SIGNAL='@t6g_mb_lib.t6g(sch_1):m_g_cpu1_sa_ca(3)';
NODE_NAME     U26 BA3
 '@T6G_MB_LIB.T6G(SCH_1):PAGE43_I167@PURE_QUANTA.GENOA_SP5(CHIPS)':
 'MGA_CA3': CDS_PINID='MGA_CA3';
NODE_NAME     J102 213
 '@T6G_MB_LIB.T6G(SCH_1):PAGE103_I22@PURE_QUANTA.SCONN288_DDR506112002KQ(CHIPS)':
 'CA3_A': CDS_PINID='CA3_A';
NET_NAME
'M_G_CPU1_SA_CA<4>'
 '@T6G_MB_LIB.T6G(SCH_1):M_G_CPU1_SA_CA'<4>:
 C_SIGNAL='@t6g_mb_lib.t6g(sch_1):m_g_cpu1_sa_ca(4)';
NODE_NAME     U26 BA2
 '@T6G_MB_LIB.T6G(SCH_1):PAGE43_I167@PURE_QUANTA.GENOA_SP5(CHIPS)':
 'MGA_CA4': CDS_PINID='MGA_CA4';
NODE_NAME     J102 70
 '@T6G_MB_LIB.T6G(SCH_1):PAGE103_I22@PURE_QUANTA.SCONN288_DDR506112002KQ(CHIPS)':
 'CA4_A': CDS_PINID='CA4_A';
NET_NAME
'M_G_CPU1_SA_CA<5>'
 '@T6G_MB_LIB.T6G(SCH_1):M_G_CPU1_SA_CA'<5>:
 C_SIGNAL='@t6g_mb_lib.t6g(sch_1):m_g_cpu1_sa_ca(5)';
NODE_NAME     U26 BB2
 '@T6G_MB_LIB.T6G(SCH_1):PAGE43_I167@PURE_QUANTA.GENOA_SP5(CHIPS)':
 'MGA_CA5': CDS_PINID='MGA_CA5';
NODE_NAME     J102 215
 '@T6G_MB_LIB.T6G(SCH_1):PAGE103_I22@PURE_QUANTA.SCONN288_DDR506112002KQ(CHIPS)':
 'CA5_A': CDS_PINID='CA5_A';
NET_NAME
'M_G_CPU1_SA_CA<6>'
 '@T6G_MB_LIB.T6G(SCH_1):M_G_CPU1_SA_CA'<6>:
 C_SIGNAL='@t6g_mb_lib.t6g(sch_1):m_g_cpu1_sa_ca(6)';
NODE_NAME     U26 BB4
 '@T6G_MB_LIB.T6G(SCH_1):PAGE43_I167@PURE_QUANTA.GENOA_SP5(CHIPS)':
 'MGA_CA6': CDS_PINID='MGA_CA6';
NODE_NAME     J102 72
 '@T6G_MB_LIB.T6G(SCH_1):PAGE103_I22@PURE_QUANTA.SCONN288_DDR506112002KQ(CHIPS)':
 'CA6_A': CDS_PINID='CA6_A';
NET_NAME
'M_G_CPU1_SA_CB<0>'
 '@T6G_MB_LIB.T6G(SCH_1):M_G_CPU1_SA_CB'<0>:
 C_SIGNAL='@t6g_mb_lib.t6g(sch_1):m_g_cpu1_sa_cb(0)';
NODE_NAME     U26 AJ2
 '@T6G_MB_LIB.T6G(SCH_1):PAGE43_I167@PURE_QUANTA.GENOA_SP5(CHIPS)':
 'MGA_CHECK0': CDS_PINID='MGA_CHECK0';
NODE_NAME     J102 51
 '@T6G_MB_LIB.T6G(SCH_1):PAGE103_I22@PURE_QUANTA.SCONN288_DDR506112002KQ(CHIPS)':
 'CB0_A': CDS_PINID='CB0_A';
NET_NAME
'M_G_CPU1_SA_CB<1>'
 '@T6G_MB_LIB.T6G(SCH_1):M_G_CPU1_SA_CB'<1>:
 C_SIGNAL='@t6g_mb_lib.t6g(sch_1):m_g_cpu1_sa_cb(1)';
NODE_NAME     U26 AK4
 '@T6G_MB_LIB.T6G(SCH_1):PAGE43_I167@PURE_QUANTA.GENOA_SP5(CHIPS)':
 'MGA_CHECK1': CDS_PINID='MGA_CHECK1';
NODE_NAME     J102 53
 '@T6G_MB_LIB.T6G(SCH_1):PAGE103_I22@PURE_QUANTA.SCONN288_DDR506112002KQ(CHIPS)':
 'CB1_A': CDS_PINID='CB1_A';
NET_NAME
'M_G_CPU1_SA_CB<2>'
 '@T6G_MB_LIB.T6G(SCH_1):M_G_CPU1_SA_CB'<2>:
 C_SIGNAL='@t6g_mb_lib.t6g(sch_1):m_g_cpu1_sa_cb(2)';
NODE_NAME     U26 AK2
 '@T6G_MB_LIB.T6G(SCH_1):PAGE43_I167@PURE_QUANTA.GENOA_SP5(CHIPS)':
 'MGA_CHECK2': CDS_PINID='MGA_CHECK2';
NODE_NAME     J102 196
 '@T6G_MB_LIB.T6G(SCH_1):PAGE103_I22@PURE_QUANTA.SCONN288_DDR506112002KQ(CHIPS)':
 'CB2_A': CDS_PINID='CB2_A';
NET_NAME
'M_G_CPU1_SA_CB<3>'
 '@T6G_MB_LIB.T6G(SCH_1):M_G_CPU1_SA_CB'<3>:
 C_SIGNAL='@t6g_mb_lib.t6g(sch_1):m_g_cpu1_sa_cb(3)';
NODE_NAME     U26 AL3
 '@T6G_MB_LIB.T6G(SCH_1):PAGE43_I167@PURE_QUANTA.GENOA_SP5(CHIPS)':
 'MGA_CHECK3': CDS_PINID='MGA_CHECK3';
NODE_NAME     J102 198
 '@T6G_MB_LIB.T6G(SCH_1):PAGE103_I22@PURE_QUANTA.SCONN288_DDR506112002KQ(CHIPS)':
 'CB3_A': CDS_PINID='CB3_A';
NET_NAME
'M_G_CPU1_SA_CB<4>'
 '@T6G_MB_LIB.T6G(SCH_1):M_G_CPU1_SA_CB'<4>:
 C_SIGNAL='@t6g_mb_lib.t6g(sch_1):m_g_cpu1_sa_cb(4)';
NODE_NAME     U26 AN2
 '@T6G_MB_LIB.T6G(SCH_1):PAGE43_I167@PURE_QUANTA.GENOA_SP5(CHIPS)':
 'MGA_CHECK4': CDS_PINID='MGA_CHECK4';
NODE_NAME     J102 58
 '@T6G_MB_LIB.T6G(SCH_1):PAGE103_I22@PURE_QUANTA.SCONN288_DDR506112002KQ(CHIPS)':
 'CB4_A': CDS_PINID='CB4_A';
NET_NAME
'M_G_CPU1_SA_CB<5>'
 '@T6G_MB_LIB.T6G(SCH_1):M_G_CPU1_SA_CB'<5>:
 C_SIGNAL='@t6g_mb_lib.t6g(sch_1):m_g_cpu1_sa_cb(5)';
NODE_NAME     U26 AP4
 '@T6G_MB_LIB.T6G(SCH_1):PAGE43_I167@PURE_QUANTA.GENOA_SP5(CHIPS)':
 'MGA_CHECK5': CDS_PINID='MGA_CHECK5';
NODE_NAME     J102 60
 '@T6G_MB_LIB.T6G(SCH_1):PAGE103_I22@PURE_QUANTA.SCONN288_DDR506112002KQ(CHIPS)':
 'CB5_A': CDS_PINID='CB5_A';
NET_NAME
'M_G_CPU1_SA_CB<6>'
 '@T6G_MB_LIB.T6G(SCH_1):M_G_CPU1_SA_CB'<6>:
 C_SIGNAL='@t6g_mb_lib.t6g(sch_1):m_g_cpu1_sa_cb(6)';
NODE_NAME     U26 AP2
 '@T6G_MB_LIB.T6G(SCH_1):PAGE43_I167@PURE_QUANTA.GENOA_SP5(CHIPS)':
 'MGA_CHECK6': CDS_PINID='MGA_CHECK6';
NODE_NAME     J102 203
 '@T6G_MB_LIB.T6G(SCH_1):PAGE103_I22@PURE_QUANTA.SCONN288_DDR506112002KQ(CHIPS)':
 'CB6_A': CDS_PINID='CB6_A';
NET_NAME
'M_G_CPU1_SA_CB<7>'
 '@T6G_MB_LIB.T6G(SCH_1):M_G_CPU1_SA_CB'<7>:
 C_SIGNAL='@t6g_mb_lib.t6g(sch_1):m_g_cpu1_sa_cb(7)';
NODE_NAME     U26 AR3
 '@T6G_MB_LIB.T6G(SCH_1):PAGE43_I167@PURE_QUANTA.GENOA_SP5(CHIPS)':
 'MGA_CHECK7': CDS_PINID='MGA_CHECK7';
NODE_NAME     J102 205
 '@T6G_MB_LIB.T6G(SCH_1):PAGE103_I22@PURE_QUANTA.SCONN288_DDR506112002KQ(CHIPS)':
 'CB7_A': CDS_PINID='CB7_A';
NET_NAME
'M_G_CPU1_SA_CS_N<0>'
 '@T6G_MB_LIB.T6G(SCH_1):M_G_CPU1_SA_CS_N'<0>:
 C_SIGNAL='@t6g_mb_lib.t6g(sch_1):m_g_cpu1_sa_cs_n(0)';
NODE_NAME     U26 AU2
 '@T6G_MB_LIB.T6G(SCH_1):PAGE43_I167@PURE_QUANTA.GENOA_SP5(CHIPS)':
 'MGA0_CS_L0': CDS_PINID='MGA0_CS_L0';
NODE_NAME     J102 64
 '@T6G_MB_LIB.T6G(SCH_1):PAGE103_I22@PURE_QUANTA.SCONN288_DDR506112002KQ(CHIPS)':
 'CS0_A_N': CDS_PINID='CS0_A_N';
NET_NAME
'M_G_CPU1_SA_CS_N<1>'
 '@T6G_MB_LIB.T6G(SCH_1):M_G_CPU1_SA_CS_N'<1>:
 C_SIGNAL='@t6g_mb_lib.t6g(sch_1):m_g_cpu1_sa_cs_n(1)';
NODE_NAME     U26 AV4
 '@T6G_MB_LIB.T6G(SCH_1):PAGE43_I167@PURE_QUANTA.GENOA_SP5(CHIPS)':
 'MGA0_CS_L1': CDS_PINID='MGA0_CS_L1';
NODE_NAME     J102 209
 '@T6G_MB_LIB.T6G(SCH_1):PAGE103_I22@PURE_QUANTA.SCONN288_DDR506112002KQ(CHIPS)':
 'CS1_A_N': CDS_PINID='CS1_A_N';
NET_NAME
'M_G_CPU1_SA_DQ<0>'
 '@T6G_MB_LIB.T6G(SCH_1):M_G_CPU1_SA_DQ'<0>:
 C_SIGNAL='@t6g_mb_lib.t6g(sch_1):m_g_cpu1_sa_dq(0)';
NODE_NAME     U26 E2
 '@T6G_MB_LIB.T6G(SCH_1):PAGE43_I167@PURE_QUANTA.GENOA_SP5(CHIPS)':
 'MGA_DATA0': CDS_PINID='MGA_DATA0';
NODE_NAME     J102 7
 '@T6G_MB_LIB.T6G(SCH_1):PAGE103_I22@PURE_QUANTA.SCONN288_DDR506112002KQ(CHIPS)':
 'DQ0_A': CDS_PINID='DQ0_A';
NET_NAME
'M_G_CPU1_SA_DQ<10>'
 '@T6G_MB_LIB.T6G(SCH_1):M_G_CPU1_SA_DQ'<10>:
 C_SIGNAL='@t6g_mb_lib.t6g(sch_1):m_g_cpu1_sa_dq(10)';
NODE_NAME     U26 M2
 '@T6G_MB_LIB.T6G(SCH_1):PAGE43_I167@PURE_QUANTA.GENOA_SP5(CHIPS)':
 'MGA_DATA10': CDS_PINID='MGA_DATA10';
NODE_NAME     J102 163
 '@T6G_MB_LIB.T6G(SCH_1):PAGE103_I22@PURE_QUANTA.SCONN288_DDR506112002KQ(CHIPS)':
 'DQ10_A': CDS_PINID='DQ10_A';
NET_NAME
'M_G_CPU1_SA_DQ<11>'
 '@T6G_MB_LIB.T6G(SCH_1):M_G_CPU1_SA_DQ'<11>:
 C_SIGNAL='@t6g_mb_lib.t6g(sch_1):m_g_cpu1_sa_dq(11)';
NODE_NAME     U26 N3
 '@T6G_MB_LIB.T6G(SCH_1):PAGE43_I167@PURE_QUANTA.GENOA_SP5(CHIPS)':
 'MGA_DATA11': CDS_PINID='MGA_DATA11';
NODE_NAME     J102 165
 '@T6G_MB_LIB.T6G(SCH_1):PAGE103_I22@PURE_QUANTA.SCONN288_DDR506112002KQ(CHIPS)':
 'DQ11_A': CDS_PINID='DQ11_A';
NET_NAME
'M_G_CPU1_SA_DQ<12>'
 '@T6G_MB_LIB.T6G(SCH_1):M_G_CPU1_SA_DQ'<12>:
 C_SIGNAL='@t6g_mb_lib.t6g(sch_1):m_g_cpu1_sa_dq(12)';
NODE_NAME     U26 R2
 '@T6G_MB_LIB.T6G(SCH_1):PAGE43_I167@PURE_QUANTA.GENOA_SP5(CHIPS)':
 'MGA_DATA12': CDS_PINID='MGA_DATA12';
NODE_NAME     J102 25
 '@T6G_MB_LIB.T6G(SCH_1):PAGE103_I22@PURE_QUANTA.SCONN288_DDR506112002KQ(CHIPS)':
 'DQ12_A': CDS_PINID='DQ12_A';
NET_NAME
'M_G_CPU1_SA_DQ<13>'
 '@T6G_MB_LIB.T6G(SCH_1):M_G_CPU1_SA_DQ'<13>:
 C_SIGNAL='@t6g_mb_lib.t6g(sch_1):m_g_cpu1_sa_dq(13)';
NODE_NAME     U26 T4
 '@T6G_MB_LIB.T6G(SCH_1):PAGE43_I167@PURE_QUANTA.GENOA_SP5(CHIPS)':
 'MGA_DATA13': CDS_PINID='MGA_DATA13';
NODE_NAME     J102 27
 '@T6G_MB_LIB.T6G(SCH_1):PAGE103_I22@PURE_QUANTA.SCONN288_DDR506112002KQ(CHIPS)':
 'DQ13_A': CDS_PINID='DQ13_A';
NET_NAME
'M_G_CPU1_SA_DQ<14>'
 '@T6G_MB_LIB.T6G(SCH_1):M_G_CPU1_SA_DQ'<14>:
 C_SIGNAL='@t6g_mb_lib.t6g(sch_1):m_g_cpu1_sa_dq(14)';
NODE_NAME     U26 T2
 '@T6G_MB_LIB.T6G(SCH_1):PAGE43_I167@PURE_QUANTA.GENOA_SP5(CHIPS)':
 'MGA_DATA14': CDS_PINID='MGA_DATA14';
NODE_NAME     J102 170
 '@T6G_MB_LIB.T6G(SCH_1):PAGE103_I22@PURE_QUANTA.SCONN288_DDR506112002KQ(CHIPS)':
 'DQ14_A': CDS_PINID='DQ14_A';
NET_NAME
'M_G_CPU1_SA_DQ<15>'
 '@T6G_MB_LIB.T6G(SCH_1):M_G_CPU1_SA_DQ'<15>:
 C_SIGNAL='@t6g_mb_lib.t6g(sch_1):m_g_cpu1_sa_dq(15)';
NODE_NAME     U26 U3
 '@T6G_MB_LIB.T6G(SCH_1):PAGE43_I167@PURE_QUANTA.GENOA_SP5(CHIPS)':
 'MGA_DATA15': CDS_PINID='MGA_DATA15';
NODE_NAME     J102 172
 '@T6G_MB_LIB.T6G(SCH_1):PAGE103_I22@PURE_QUANTA.SCONN288_DDR506112002KQ(CHIPS)':
 'DQ15_A': CDS_PINID='DQ15_A';
NET_NAME
'M_G_CPU1_SA_DQ<16>'
 '@T6G_MB_LIB.T6G(SCH_1):M_G_CPU1_SA_DQ'<16>:
 C_SIGNAL='@t6g_mb_lib.t6g(sch_1):m_g_cpu1_sa_dq(16)';
NODE_NAME     U26 U2
 '@T6G_MB_LIB.T6G(SCH_1):PAGE43_I167@PURE_QUANTA.GENOA_SP5(CHIPS)':
 'MGA_DATA16': CDS_PINID='MGA_DATA16';
NODE_NAME     J102 29
 '@T6G_MB_LIB.T6G(SCH_1):PAGE103_I22@PURE_QUANTA.SCONN288_DDR506112002KQ(CHIPS)':
 'DQ16_A': CDS_PINID='DQ16_A';
NET_NAME
'M_G_CPU1_SA_DQ<17>'
 '@T6G_MB_LIB.T6G(SCH_1):M_G_CPU1_SA_DQ'<17>:
 C_SIGNAL='@t6g_mb_lib.t6g(sch_1):m_g_cpu1_sa_dq(17)';
NODE_NAME     U26 V4
 '@T6G_MB_LIB.T6G(SCH_1):PAGE43_I167@PURE_QUANTA.GENOA_SP5(CHIPS)':
 'MGA_DATA17': CDS_PINID='MGA_DATA17';
NODE_NAME     J102 31
 '@T6G_MB_LIB.T6G(SCH_1):PAGE103_I22@PURE_QUANTA.SCONN288_DDR506112002KQ(CHIPS)':
 'DQ17_A': CDS_PINID='DQ17_A';
NET_NAME
'M_G_CPU1_SA_DQ<18>'
 '@T6G_MB_LIB.T6G(SCH_1):M_G_CPU1_SA_DQ'<18>:
 C_SIGNAL='@t6g_mb_lib.t6g(sch_1):m_g_cpu1_sa_dq(18)';
NODE_NAME     U26 V2
 '@T6G_MB_LIB.T6G(SCH_1):PAGE43_I167@PURE_QUANTA.GENOA_SP5(CHIPS)':
 'MGA_DATA18': CDS_PINID='MGA_DATA18';
NODE_NAME     J102 174
 '@T6G_MB_LIB.T6G(SCH_1):PAGE103_I22@PURE_QUANTA.SCONN288_DDR506112002KQ(CHIPS)':
 'DQ18_A': CDS_PINID='DQ18_A';
NET_NAME
'M_G_CPU1_SA_DQ<19>'
 '@T6G_MB_LIB.T6G(SCH_1):M_G_CPU1_SA_DQ'<19>:
 C_SIGNAL='@t6g_mb_lib.t6g(sch_1):m_g_cpu1_sa_dq(19)';
NODE_NAME     U26 W3
 '@T6G_MB_LIB.T6G(SCH_1):PAGE43_I167@PURE_QUANTA.GENOA_SP5(CHIPS)':
 'MGA_DATA19': CDS_PINID='MGA_DATA19';
NODE_NAME     J102 176
 '@T6G_MB_LIB.T6G(SCH_1):PAGE103_I22@PURE_QUANTA.SCONN288_DDR506112002KQ(CHIPS)':
 'DQ19_A': CDS_PINID='DQ19_A';
NET_NAME
'M_G_CPU1_SA_DQ<1>'
 '@T6G_MB_LIB.T6G(SCH_1):M_G_CPU1_SA_DQ'<1>:
 C_SIGNAL='@t6g_mb_lib.t6g(sch_1):m_g_cpu1_sa_dq(1)';
NODE_NAME     U26 F4
 '@T6G_MB_LIB.T6G(SCH_1):PAGE43_I167@PURE_QUANTA.GENOA_SP5(CHIPS)':
 'MGA_DATA1': CDS_PINID='MGA_DATA1';
NODE_NAME     J102 9
 '@T6G_MB_LIB.T6G(SCH_1):PAGE103_I22@PURE_QUANTA.SCONN288_DDR506112002KQ(CHIPS)':
 'DQ1_A': CDS_PINID='DQ1_A';
NET_NAME
'M_G_CPU1_SA_DQ<20>'
 '@T6G_MB_LIB.T6G(SCH_1):M_G_CPU1_SA_DQ'<20>:
 C_SIGNAL='@t6g_mb_lib.t6g(sch_1):m_g_cpu1_sa_dq(20)';
NODE_NAME     U26 AA2
 '@T6G_MB_LIB.T6G(SCH_1):PAGE43_I167@PURE_QUANTA.GENOA_SP5(CHIPS)':
 'MGA_DATA20': CDS_PINID='MGA_DATA20';
NODE_NAME     J102 36
 '@T6G_MB_LIB.T6G(SCH_1):PAGE103_I22@PURE_QUANTA.SCONN288_DDR506112002KQ(CHIPS)':
 'DQ20_A': CDS_PINID='DQ20_A';
NET_NAME
'M_G_CPU1_SA_DQ<21>'
 '@T6G_MB_LIB.T6G(SCH_1):M_G_CPU1_SA_DQ'<21>:
 C_SIGNAL='@t6g_mb_lib.t6g(sch_1):m_g_cpu1_sa_dq(21)';
NODE_NAME     U26 AB4
 '@T6G_MB_LIB.T6G(SCH_1):PAGE43_I167@PURE_QUANTA.GENOA_SP5(CHIPS)':
 'MGA_DATA21': CDS_PINID='MGA_DATA21';
NODE_NAME     J102 38
 '@T6G_MB_LIB.T6G(SCH_1):PAGE103_I22@PURE_QUANTA.SCONN288_DDR506112002KQ(CHIPS)':
 'DQ21_A': CDS_PINID='DQ21_A';
NET_NAME
'M_G_CPU1_SA_DQ<22>'
 '@T6G_MB_LIB.T6G(SCH_1):M_G_CPU1_SA_DQ'<22>:
 C_SIGNAL='@t6g_mb_lib.t6g(sch_1):m_g_cpu1_sa_dq(22)';
NODE_NAME     U26 AB2
 '@T6G_MB_LIB.T6G(SCH_1):PAGE43_I167@PURE_QUANTA.GENOA_SP5(CHIPS)':
 'MGA_DATA22': CDS_PINID='MGA_DATA22';
NODE_NAME     J102 181
 '@T6G_MB_LIB.T6G(SCH_1):PAGE103_I22@PURE_QUANTA.SCONN288_DDR506112002KQ(CHIPS)':
 'DQ22_A': CDS_PINID='DQ22_A';
NET_NAME
'M_G_CPU1_SA_DQ<23>'
 '@T6G_MB_LIB.T6G(SCH_1):M_G_CPU1_SA_DQ'<23>:
 C_SIGNAL='@t6g_mb_lib.t6g(sch_1):m_g_cpu1_sa_dq(23)';
NODE_NAME     U26 AC3
 '@T6G_MB_LIB.T6G(SCH_1):PAGE43_I167@PURE_QUANTA.GENOA_SP5(CHIPS)':
 'MGA_DATA23': CDS_PINID='MGA_DATA23';
NODE_NAME     J102 183
 '@T6G_MB_LIB.T6G(SCH_1):PAGE103_I22@PURE_QUANTA.SCONN288_DDR506112002KQ(CHIPS)':
 'DQ23_A': CDS_PINID='DQ23_A';
NET_NAME
'M_G_CPU1_SA_DQ<24>'
 '@T6G_MB_LIB.T6G(SCH_1):M_G_CPU1_SA_DQ'<24>:
 C_SIGNAL='@t6g_mb_lib.t6g(sch_1):m_g_cpu1_sa_dq(24)';
NODE_NAME     U26 AC2
 '@T6G_MB_LIB.T6G(SCH_1):PAGE43_I167@PURE_QUANTA.GENOA_SP5(CHIPS)':
 'MGA_DATA24': CDS_PINID='MGA_DATA24';
NODE_NAME     J102 40
 '@T6G_MB_LIB.T6G(SCH_1):PAGE103_I22@PURE_QUANTA.SCONN288_DDR506112002KQ(CHIPS)':
 'DQ24_A': CDS_PINID='DQ24_A';
NET_NAME
'M_G_CPU1_SA_DQ<25>'
 '@T6G_MB_LIB.T6G(SCH_1):M_G_CPU1_SA_DQ'<25>:
 C_SIGNAL='@t6g_mb_lib.t6g(sch_1):m_g_cpu1_sa_dq(25)';
NODE_NAME     U26 AD4
 '@T6G_MB_LIB.T6G(SCH_1):PAGE43_I167@PURE_QUANTA.GENOA_SP5(CHIPS)':
 'MGA_DATA25': CDS_PINID='MGA_DATA25';
NODE_NAME     J102 42
 '@T6G_MB_LIB.T6G(SCH_1):PAGE103_I22@PURE_QUANTA.SCONN288_DDR506112002KQ(CHIPS)':
 'DQ25_A': CDS_PINID='DQ25_A';
NET_NAME
'M_G_CPU1_SA_DQ<26>'
 '@T6G_MB_LIB.T6G(SCH_1):M_G_CPU1_SA_DQ'<26>:
 C_SIGNAL='@t6g_mb_lib.t6g(sch_1):m_g_cpu1_sa_dq(26)';
NODE_NAME     U26 AD2
 '@T6G_MB_LIB.T6G(SCH_1):PAGE43_I167@PURE_QUANTA.GENOA_SP5(CHIPS)':
 'MGA_DATA26': CDS_PINID='MGA_DATA26';
NODE_NAME     J102 185
 '@T6G_MB_LIB.T6G(SCH_1):PAGE103_I22@PURE_QUANTA.SCONN288_DDR506112002KQ(CHIPS)':
 'DQ26_A': CDS_PINID='DQ26_A';
NET_NAME
'M_G_CPU1_SA_DQ<27>'
 '@T6G_MB_LIB.T6G(SCH_1):M_G_CPU1_SA_DQ'<27>:
 C_SIGNAL='@t6g_mb_lib.t6g(sch_1):m_g_cpu1_sa_dq(27)';
NODE_NAME     U26 AE3
 '@T6G_MB_LIB.T6G(SCH_1):PAGE43_I167@PURE_QUANTA.GENOA_SP5(CHIPS)':
 'MGA_DATA27': CDS_PINID='MGA_DATA27';
NODE_NAME     J102 187
 '@T6G_MB_LIB.T6G(SCH_1):PAGE103_I22@PURE_QUANTA.SCONN288_DDR506112002KQ(CHIPS)':
 'DQ27_A': CDS_PINID='DQ27_A';
NET_NAME
'M_G_CPU1_SA_DQ<28>'
 '@T6G_MB_LIB.T6G(SCH_1):M_G_CPU1_SA_DQ'<28>:
 C_SIGNAL='@t6g_mb_lib.t6g(sch_1):m_g_cpu1_sa_dq(28)';
NODE_NAME     U26 AG2
 '@T6G_MB_LIB.T6G(SCH_1):PAGE43_I167@PURE_QUANTA.GENOA_SP5(CHIPS)':
 'MGA_DATA28': CDS_PINID='MGA_DATA28';
NODE_NAME     J102 47
 '@T6G_MB_LIB.T6G(SCH_1):PAGE103_I22@PURE_QUANTA.SCONN288_DDR506112002KQ(CHIPS)':
 'DQ28_A': CDS_PINID='DQ28_A';
NET_NAME
'M_G_CPU1_SA_DQ<29>'
 '@T6G_MB_LIB.T6G(SCH_1):M_G_CPU1_SA_DQ'<29>:
 C_SIGNAL='@t6g_mb_lib.t6g(sch_1):m_g_cpu1_sa_dq(29)';
NODE_NAME     U26 AH4
 '@T6G_MB_LIB.T6G(SCH_1):PAGE43_I167@PURE_QUANTA.GENOA_SP5(CHIPS)':
 'MGA_DATA29': CDS_PINID='MGA_DATA29';
NODE_NAME     J102 49
 '@T6G_MB_LIB.T6G(SCH_1):PAGE103_I22@PURE_QUANTA.SCONN288_DDR506112002KQ(CHIPS)':
 'DQ29_A': CDS_PINID='DQ29_A';
NET_NAME
'M_G_CPU1_SA_DQ<2>'
 '@T6G_MB_LIB.T6G(SCH_1):M_G_CPU1_SA_DQ'<2>:
 C_SIGNAL='@t6g_mb_lib.t6g(sch_1):m_g_cpu1_sa_dq(2)';
NODE_NAME     U26 F2
 '@T6G_MB_LIB.T6G(SCH_1):PAGE43_I167@PURE_QUANTA.GENOA_SP5(CHIPS)':
 'MGA_DATA2': CDS_PINID='MGA_DATA2';
NODE_NAME     J102 152
 '@T6G_MB_LIB.T6G(SCH_1):PAGE103_I22@PURE_QUANTA.SCONN288_DDR506112002KQ(CHIPS)':
 'DQ2_A': CDS_PINID='DQ2_A';
NET_NAME
'M_G_CPU1_SA_DQ<30>'
 '@T6G_MB_LIB.T6G(SCH_1):M_G_CPU1_SA_DQ'<30>:
 C_SIGNAL='@t6g_mb_lib.t6g(sch_1):m_g_cpu1_sa_dq(30)';
NODE_NAME     U26 AH2
 '@T6G_MB_LIB.T6G(SCH_1):PAGE43_I167@PURE_QUANTA.GENOA_SP5(CHIPS)':
 'MGA_DATA30': CDS_PINID='MGA_DATA30';
NODE_NAME     J102 192
 '@T6G_MB_LIB.T6G(SCH_1):PAGE103_I22@PURE_QUANTA.SCONN288_DDR506112002KQ(CHIPS)':
 'DQ30_A': CDS_PINID='DQ30_A';
NET_NAME
'M_G_CPU1_SA_DQ<31>'
 '@T6G_MB_LIB.T6G(SCH_1):M_G_CPU1_SA_DQ'<31>:
 C_SIGNAL='@t6g_mb_lib.t6g(sch_1):m_g_cpu1_sa_dq(31)';
NODE_NAME     U26 AJ3
 '@T6G_MB_LIB.T6G(SCH_1):PAGE43_I167@PURE_QUANTA.GENOA_SP5(CHIPS)':
 'MGA_DATA31': CDS_PINID='MGA_DATA31';
NODE_NAME     J102 194
 '@T6G_MB_LIB.T6G(SCH_1):PAGE103_I22@PURE_QUANTA.SCONN288_DDR506112002KQ(CHIPS)':
 'DQ31_A': CDS_PINID='DQ31_A';
NET_NAME
'M_G_CPU1_SA_DQ<3>'
 '@T6G_MB_LIB.T6G(SCH_1):M_G_CPU1_SA_DQ'<3>:
 C_SIGNAL='@t6g_mb_lib.t6g(sch_1):m_g_cpu1_sa_dq(3)';
NODE_NAME     U26 G3
 '@T6G_MB_LIB.T6G(SCH_1):PAGE43_I167@PURE_QUANTA.GENOA_SP5(CHIPS)':
 'MGA_DATA3': CDS_PINID='MGA_DATA3';
NODE_NAME     J102 154
 '@T6G_MB_LIB.T6G(SCH_1):PAGE103_I22@PURE_QUANTA.SCONN288_DDR506112002KQ(CHIPS)':
 'DQ3_A': CDS_PINID='DQ3_A';
NET_NAME
'M_G_CPU1_SA_DQ<4>'
 '@T6G_MB_LIB.T6G(SCH_1):M_G_CPU1_SA_DQ'<4>:
 C_SIGNAL='@t6g_mb_lib.t6g(sch_1):m_g_cpu1_sa_dq(4)';
NODE_NAME     U26 J2
 '@T6G_MB_LIB.T6G(SCH_1):PAGE43_I167@PURE_QUANTA.GENOA_SP5(CHIPS)':
 'MGA_DATA4': CDS_PINID='MGA_DATA4';
NODE_NAME     J102 14
 '@T6G_MB_LIB.T6G(SCH_1):PAGE103_I22@PURE_QUANTA.SCONN288_DDR506112002KQ(CHIPS)':
 'DQ4_A': CDS_PINID='DQ4_A';
NET_NAME
'M_G_CPU1_SA_DQ<5>'
 '@T6G_MB_LIB.T6G(SCH_1):M_G_CPU1_SA_DQ'<5>:
 C_SIGNAL='@t6g_mb_lib.t6g(sch_1):m_g_cpu1_sa_dq(5)';
NODE_NAME     U26 K4
 '@T6G_MB_LIB.T6G(SCH_1):PAGE43_I167@PURE_QUANTA.GENOA_SP5(CHIPS)':
 'MGA_DATA5': CDS_PINID='MGA_DATA5';
NODE_NAME     J102 16
 '@T6G_MB_LIB.T6G(SCH_1):PAGE103_I22@PURE_QUANTA.SCONN288_DDR506112002KQ(CHIPS)':
 'DQ5_A': CDS_PINID='DQ5_A';
NET_NAME
'M_G_CPU1_SA_DQ<6>'
 '@T6G_MB_LIB.T6G(SCH_1):M_G_CPU1_SA_DQ'<6>:
 C_SIGNAL='@t6g_mb_lib.t6g(sch_1):m_g_cpu1_sa_dq(6)';
NODE_NAME     U26 K2
 '@T6G_MB_LIB.T6G(SCH_1):PAGE43_I167@PURE_QUANTA.GENOA_SP5(CHIPS)':
 'MGA_DATA6': CDS_PINID='MGA_DATA6';
NODE_NAME     J102 159
 '@T6G_MB_LIB.T6G(SCH_1):PAGE103_I22@PURE_QUANTA.SCONN288_DDR506112002KQ(CHIPS)':
 'DQ6_A': CDS_PINID='DQ6_A';
NET_NAME
'M_G_CPU1_SA_DQ<7>'
 '@T6G_MB_LIB.T6G(SCH_1):M_G_CPU1_SA_DQ'<7>:
 C_SIGNAL='@t6g_mb_lib.t6g(sch_1):m_g_cpu1_sa_dq(7)';
NODE_NAME     U26 L3
 '@T6G_MB_LIB.T6G(SCH_1):PAGE43_I167@PURE_QUANTA.GENOA_SP5(CHIPS)':
 'MGA_DATA7': CDS_PINID='MGA_DATA7';
NODE_NAME     J102 161
 '@T6G_MB_LIB.T6G(SCH_1):PAGE103_I22@PURE_QUANTA.SCONN288_DDR506112002KQ(CHIPS)':
 'DQ7_A': CDS_PINID='DQ7_A';
NET_NAME
'M_G_CPU1_SA_DQ<8>'
 '@T6G_MB_LIB.T6G(SCH_1):M_G_CPU1_SA_DQ'<8>:
 C_SIGNAL='@t6g_mb_lib.t6g(sch_1):m_g_cpu1_sa_dq(8)';
NODE_NAME     U26 L2
 '@T6G_MB_LIB.T6G(SCH_1):PAGE43_I167@PURE_QUANTA.GENOA_SP5(CHIPS)':
 'MGA_DATA8': CDS_PINID='MGA_DATA8';
NODE_NAME     J102 18
 '@T6G_MB_LIB.T6G(SCH_1):PAGE103_I22@PURE_QUANTA.SCONN288_DDR506112002KQ(CHIPS)':
 'DQ8_A': CDS_PINID='DQ8_A';
NET_NAME
'M_G_CPU1_SA_DQ<9>'
 '@T6G_MB_LIB.T6G(SCH_1):M_G_CPU1_SA_DQ'<9>:
 C_SIGNAL='@t6g_mb_lib.t6g(sch_1):m_g_cpu1_sa_dq(9)';
NODE_NAME     U26 M4
 '@T6G_MB_LIB.T6G(SCH_1):PAGE43_I167@PURE_QUANTA.GENOA_SP5(CHIPS)':
 'MGA_DATA9': CDS_PINID='MGA_DATA9';
NODE_NAME     J102 20
 '@T6G_MB_LIB.T6G(SCH_1):PAGE103_I22@PURE_QUANTA.SCONN288_DDR506112002KQ(CHIPS)':
 'DQ9_A': CDS_PINID='DQ9_A';
NET_NAME
'M_G_CPU1_SA_DQS_DN<0>'
 '@T6G_MB_LIB.T6G(SCH_1):M_G_CPU1_SA_DQS_DN'<0>:
 C_SIGNAL='@t6g_mb_lib.t6g(sch_1):m_g_cpu1_sa_dqs_dn(0)';
NODE_NAME     U26 H2
 '@T6G_MB_LIB.T6G(SCH_1):PAGE43_I167@PURE_QUANTA.GENOA_SP5(CHIPS)':
 'MGA_DQS_L0': CDS_PINID='MGA_DQS_L0';
NODE_NAME     J102 12
 '@T6G_MB_LIB.T6G(SCH_1):PAGE103_I238@PURE_QUANTA.SCONN288_DDR506112002KQ(CHIPS)':
 'DQS0_A_C': CDS_PINID='DQS0_A_C';
NET_NAME
'M_G_CPU1_SA_DQS_DN<1>'
 '@T6G_MB_LIB.T6G(SCH_1):M_G_CPU1_SA_DQS_DN'<1>:
 C_SIGNAL='@t6g_mb_lib.t6g(sch_1):m_g_cpu1_sa_dqs_dn(1)';
NODE_NAME     U26 P2
 '@T6G_MB_LIB.T6G(SCH_1):PAGE43_I167@PURE_QUANTA.GENOA_SP5(CHIPS)':
 'MGA_DQS_L1': CDS_PINID='MGA_DQS_L1';
NODE_NAME     J102 23
 '@T6G_MB_LIB.T6G(SCH_1):PAGE103_I238@PURE_QUANTA.SCONN288_DDR506112002KQ(CHIPS)':
 'DQS1_A_C': CDS_PINID='DQS1_A_C';
NET_NAME
'M_G_CPU1_SA_DQS_DN<2>'
 '@T6G_MB_LIB.T6G(SCH_1):M_G_CPU1_SA_DQS_DN'<2>:
 C_SIGNAL='@t6g_mb_lib.t6g(sch_1):m_g_cpu1_sa_dqs_dn(2)';
NODE_NAME     U26 Y2
 '@T6G_MB_LIB.T6G(SCH_1):PAGE43_I167@PURE_QUANTA.GENOA_SP5(CHIPS)':
 'MGA_DQS_L2': CDS_PINID='MGA_DQS_L2';
NODE_NAME     J102 34
 '@T6G_MB_LIB.T6G(SCH_1):PAGE103_I238@PURE_QUANTA.SCONN288_DDR506112002KQ(CHIPS)':
 'DQS2_A_C': CDS_PINID='DQS2_A_C';
NET_NAME
'M_G_CPU1_SA_DQS_DN<3>'
 '@T6G_MB_LIB.T6G(SCH_1):M_G_CPU1_SA_DQS_DN'<3>:
 C_SIGNAL='@t6g_mb_lib.t6g(sch_1):m_g_cpu1_sa_dqs_dn(3)';
NODE_NAME     U26 AF2
 '@T6G_MB_LIB.T6G(SCH_1):PAGE43_I167@PURE_QUANTA.GENOA_SP5(CHIPS)':
 'MGA_DQS_L3': CDS_PINID='MGA_DQS_L3';
NODE_NAME     J102 45
 '@T6G_MB_LIB.T6G(SCH_1):PAGE103_I238@PURE_QUANTA.SCONN288_DDR506112002KQ(CHIPS)':
 'DQS3_A_C': CDS_PINID='DQS3_A_C';
NET_NAME
'M_G_CPU1_SA_DQS_DN<4>'
 '@T6G_MB_LIB.T6G(SCH_1):M_G_CPU1_SA_DQS_DN'<4>:
 C_SIGNAL='@t6g_mb_lib.t6g(sch_1):m_g_cpu1_sa_dqs_dn(4)';
NODE_NAME     U26 AM2
 '@T6G_MB_LIB.T6G(SCH_1):PAGE43_I167@PURE_QUANTA.GENOA_SP5(CHIPS)':
 'MGA_DQS_L4': CDS_PINID='MGA_DQS_L4';
NODE_NAME     J102 56
 '@T6G_MB_LIB.T6G(SCH_1):PAGE103_I238@PURE_QUANTA.SCONN288_DDR506112002KQ(CHIPS)':
 'DQS4_A_C': CDS_PINID='DQS4_A_C';
NET_NAME
'M_G_CPU1_SA_DQS_DN<5>'
 '@T6G_MB_LIB.T6G(SCH_1):M_G_CPU1_SA_DQS_DN'<5>:
 C_SIGNAL='@t6g_mb_lib.t6g(sch_1):m_g_cpu1_sa_dqs_dn(5)';
NODE_NAME     U26 H4
 '@T6G_MB_LIB.T6G(SCH_1):PAGE43_I167@PURE_QUANTA.GENOA_SP5(CHIPS)':
 'MGA_DQS_L5': CDS_PINID='MGA_DQS_L5';
NODE_NAME     J102 156
 '@T6G_MB_LIB.T6G(SCH_1):PAGE103_I238@PURE_QUANTA.SCONN288_DDR506112002KQ(CHIPS)':
 'DQS5_A_C||TDQS5_A_C||DQS5_A_T||TDQS5_A_T': CDS_PINID='\dqs5_a_c||tdqs5_a_c||dqs5_a_t||tdqs5_a_t\';
NET_NAME
'M_G_CPU1_SA_DQS_DN<6>'
 '@T6G_MB_LIB.T6G(SCH_1):M_G_CPU1_SA_DQS_DN'<6>:
 C_SIGNAL='@t6g_mb_lib.t6g(sch_1):m_g_cpu1_sa_dqs_dn(6)';
NODE_NAME     U26 P4
 '@T6G_MB_LIB.T6G(SCH_1):PAGE43_I167@PURE_QUANTA.GENOA_SP5(CHIPS)':
 'MGA_DQS_L6': CDS_PINID='MGA_DQS_L6';
NODE_NAME     J102 167
 '@T6G_MB_LIB.T6G(SCH_1):PAGE103_I238@PURE_QUANTA.SCONN288_DDR506112002KQ(CHIPS)':
 'DQS6_A_C||TDQS6_A_C||DQS6_A_T||TDQS6_A_T': CDS_PINID='\dqs6_a_c||tdqs6_a_c||dqs6_a_t||tdqs6_a_t\';
NET_NAME
'M_G_CPU1_SA_DQS_DN<7>'
 '@T6G_MB_LIB.T6G(SCH_1):M_G_CPU1_SA_DQS_DN'<7>:
 C_SIGNAL='@t6g_mb_lib.t6g(sch_1):m_g_cpu1_sa_dqs_dn(7)';
NODE_NAME     U26 Y4
 '@T6G_MB_LIB.T6G(SCH_1):PAGE43_I167@PURE_QUANTA.GENOA_SP5(CHIPS)':
 'MGA_DQS_L7': CDS_PINID='MGA_DQS_L7';
NODE_NAME     J102 178
 '@T6G_MB_LIB.T6G(SCH_1):PAGE103_I238@PURE_QUANTA.SCONN288_DDR506112002KQ(CHIPS)':
 'DQS7_A_C||TDQS7_A_C': CDS_PINID='\dqs7_a_c||tdqs7_a_c\';
NET_NAME
'M_G_CPU1_SA_DQS_DN<8>'
 '@T6G_MB_LIB.T6G(SCH_1):M_G_CPU1_SA_DQS_DN'<8>:
 C_SIGNAL='@t6g_mb_lib.t6g(sch_1):m_g_cpu1_sa_dqs_dn(8)';
NODE_NAME     U26 AF4
 '@T6G_MB_LIB.T6G(SCH_1):PAGE43_I167@PURE_QUANTA.GENOA_SP5(CHIPS)':
 'MGA_DQS_L8': CDS_PINID='MGA_DQS_L8';
NODE_NAME     J102 189
 '@T6G_MB_LIB.T6G(SCH_1):PAGE103_I238@PURE_QUANTA.SCONN288_DDR506112002KQ(CHIPS)':
 'DQS8_A_C||TDQS8_A_C': CDS_PINID='\dqs8_a_c||tdqs8_a_c\';
NET_NAME
'M_G_CPU1_SA_DQS_DN<9>'
 '@T6G_MB_LIB.T6G(SCH_1):M_G_CPU1_SA_DQS_DN'<9>:
 C_SIGNAL='@t6g_mb_lib.t6g(sch_1):m_g_cpu1_sa_dqs_dn(9)';
NODE_NAME     U26 AM4
 '@T6G_MB_LIB.T6G(SCH_1):PAGE43_I167@PURE_QUANTA.GENOA_SP5(CHIPS)':
 'MGA_DQS_L9': CDS_PINID='MGA_DQS_L9';
NODE_NAME     J102 200
 '@T6G_MB_LIB.T6G(SCH_1):PAGE103_I238@PURE_QUANTA.SCONN288_DDR506112002KQ(CHIPS)':
 'DQS9_A_C||TDQS9_A_C': CDS_PINID='\dqs9_a_c||tdqs9_a_c\';
NET_NAME
'M_G_CPU1_SA_DQS_DP<0>'
 '@T6G_MB_LIB.T6G(SCH_1):M_G_CPU1_SA_DQS_DP'<0>:
 C_SIGNAL='@t6g_mb_lib.t6g(sch_1):m_g_cpu1_sa_dqs_dp(0)';
NODE_NAME     U26 G2
 '@T6G_MB_LIB.T6G(SCH_1):PAGE43_I167@PURE_QUANTA.GENOA_SP5(CHIPS)':
 'MGA_DQS_H0': CDS_PINID='MGA_DQS_H0';
NODE_NAME     J102 11
 '@T6G_MB_LIB.T6G(SCH_1):PAGE103_I238@PURE_QUANTA.SCONN288_DDR506112002KQ(CHIPS)':
 'DQS0_A_T': CDS_PINID='DQS0_A_T';
NET_NAME
'M_G_CPU1_SA_DQS_DP<1>'
 '@T6G_MB_LIB.T6G(SCH_1):M_G_CPU1_SA_DQS_DP'<1>:
 C_SIGNAL='@t6g_mb_lib.t6g(sch_1):m_g_cpu1_sa_dqs_dp(1)';
NODE_NAME     U26 N2
 '@T6G_MB_LIB.T6G(SCH_1):PAGE43_I167@PURE_QUANTA.GENOA_SP5(CHIPS)':
 'MGA_DQS_H1': CDS_PINID='MGA_DQS_H1';
NODE_NAME     J102 22
 '@T6G_MB_LIB.T6G(SCH_1):PAGE103_I238@PURE_QUANTA.SCONN288_DDR506112002KQ(CHIPS)':
 'DQS1_A_T': CDS_PINID='DQS1_A_T';
NET_NAME
'M_G_CPU1_SA_DQS_DP<2>'
 '@T6G_MB_LIB.T6G(SCH_1):M_G_CPU1_SA_DQS_DP'<2>:
 C_SIGNAL='@t6g_mb_lib.t6g(sch_1):m_g_cpu1_sa_dqs_dp(2)';
NODE_NAME     U26 W2
 '@T6G_MB_LIB.T6G(SCH_1):PAGE43_I167@PURE_QUANTA.GENOA_SP5(CHIPS)':
 'MGA_DQS_H2': CDS_PINID='MGA_DQS_H2';
NODE_NAME     J102 33
 '@T6G_MB_LIB.T6G(SCH_1):PAGE103_I238@PURE_QUANTA.SCONN288_DDR506112002KQ(CHIPS)':
 'DQS2_A_T': CDS_PINID='DQS2_A_T';
NET_NAME
'M_G_CPU1_SA_DQS_DP<3>'
 '@T6G_MB_LIB.T6G(SCH_1):M_G_CPU1_SA_DQS_DP'<3>:
 C_SIGNAL='@t6g_mb_lib.t6g(sch_1):m_g_cpu1_sa_dqs_dp(3)';
NODE_NAME     U26 AE2
 '@T6G_MB_LIB.T6G(SCH_1):PAGE43_I167@PURE_QUANTA.GENOA_SP5(CHIPS)':
 'MGA_DQS_H3': CDS_PINID='MGA_DQS_H3';
NODE_NAME     J102 44
 '@T6G_MB_LIB.T6G(SCH_1):PAGE103_I238@PURE_QUANTA.SCONN288_DDR506112002KQ(CHIPS)':
 'DQS3_A_T': CDS_PINID='DQS3_A_T';
NET_NAME
'M_G_CPU1_SA_DQS_DP<4>'
 '@T6G_MB_LIB.T6G(SCH_1):M_G_CPU1_SA_DQS_DP'<4>:
 C_SIGNAL='@t6g_mb_lib.t6g(sch_1):m_g_cpu1_sa_dqs_dp(4)';
NODE_NAME     U26 AL2
 '@T6G_MB_LIB.T6G(SCH_1):PAGE43_I167@PURE_QUANTA.GENOA_SP5(CHIPS)':
 'MGA_DQS_H4': CDS_PINID='MGA_DQS_H4';
NODE_NAME     J102 55
 '@T6G_MB_LIB.T6G(SCH_1):PAGE103_I238@PURE_QUANTA.SCONN288_DDR506112002KQ(CHIPS)':
 'DQS4_A_T': CDS_PINID='DQS4_A_T';
NET_NAME
'M_G_CPU1_SA_DQS_DP<5>'
 '@T6G_MB_LIB.T6G(SCH_1):M_G_CPU1_SA_DQS_DP'<5>:
 C_SIGNAL='@t6g_mb_lib.t6g(sch_1):m_g_cpu1_sa_dqs_dp(5)';
NODE_NAME     U26 J3
 '@T6G_MB_LIB.T6G(SCH_1):PAGE43_I167@PURE_QUANTA.GENOA_SP5(CHIPS)':
 'MGA_DQS_H5': CDS_PINID='MGA_DQS_H5';
NODE_NAME     J102 157
 '@T6G_MB_LIB.T6G(SCH_1):PAGE103_I238@PURE_QUANTA.SCONN288_DDR506112002KQ(CHIPS)':
 'DQS5_A_T||TDQS5_A_T': CDS_PINID='\dqs5_a_t||tdqs5_a_t\';
NET_NAME
'M_G_CPU1_SA_DQS_DP<6>'
 '@T6G_MB_LIB.T6G(SCH_1):M_G_CPU1_SA_DQS_DP'<6>:
 C_SIGNAL='@t6g_mb_lib.t6g(sch_1):m_g_cpu1_sa_dqs_dp(6)';
NODE_NAME     U26 R3
 '@T6G_MB_LIB.T6G(SCH_1):PAGE43_I167@PURE_QUANTA.GENOA_SP5(CHIPS)':
 'MGA_DQS_H6': CDS_PINID='MGA_DQS_H6';
NODE_NAME     J102 168
 '@T6G_MB_LIB.T6G(SCH_1):PAGE103_I238@PURE_QUANTA.SCONN288_DDR506112002KQ(CHIPS)':
 'DQS6_A_T||TDQS6_A_T': CDS_PINID='\dqs6_a_t||tdqs6_a_t\';
NET_NAME
'M_G_CPU1_SA_DQS_DP<7>'
 '@T6G_MB_LIB.T6G(SCH_1):M_G_CPU1_SA_DQS_DP'<7>:
 C_SIGNAL='@t6g_mb_lib.t6g(sch_1):m_g_cpu1_sa_dqs_dp(7)';
NODE_NAME     U26 AA3
 '@T6G_MB_LIB.T6G(SCH_1):PAGE43_I167@PURE_QUANTA.GENOA_SP5(CHIPS)':
 'MGA_DQS_H7': CDS_PINID='MGA_DQS_H7';
NODE_NAME     J102 179
 '@T6G_MB_LIB.T6G(SCH_1):PAGE103_I238@PURE_QUANTA.SCONN288_DDR506112002KQ(CHIPS)':
 'DQS7_A_T||TDQS7_A_T': CDS_PINID='\dqs7_a_t||tdqs7_a_t\';
NET_NAME
'M_G_CPU1_SA_DQS_DP<8>'
 '@T6G_MB_LIB.T6G(SCH_1):M_G_CPU1_SA_DQS_DP'<8>:
 C_SIGNAL='@t6g_mb_lib.t6g(sch_1):m_g_cpu1_sa_dqs_dp(8)';
NODE_NAME     U26 AG3
 '@T6G_MB_LIB.T6G(SCH_1):PAGE43_I167@PURE_QUANTA.GENOA_SP5(CHIPS)':
 'MGA_DQS_H8': CDS_PINID='MGA_DQS_H8';
NODE_NAME     J102 190
 '@T6G_MB_LIB.T6G(SCH_1):PAGE103_I238@PURE_QUANTA.SCONN288_DDR506112002KQ(CHIPS)':
 'DQS8_A_T||TDQS8_A_T': CDS_PINID='\dqs8_a_t||tdqs8_a_t\';
NET_NAME
'M_G_CPU1_SA_DQS_DP<9>'
 '@T6G_MB_LIB.T6G(SCH_1):M_G_CPU1_SA_DQS_DP'<9>:
 C_SIGNAL='@t6g_mb_lib.t6g(sch_1):m_g_cpu1_sa_dqs_dp(9)';
NODE_NAME     U26 AN3
 '@T6G_MB_LIB.T6G(SCH_1):PAGE43_I167@PURE_QUANTA.GENOA_SP5(CHIPS)':
 'MGA_DQS_H9': CDS_PINID='MGA_DQS_H9';
NODE_NAME     J102 201
 '@T6G_MB_LIB.T6G(SCH_1):PAGE103_I238@PURE_QUANTA.SCONN288_DDR506112002KQ(CHIPS)':
 'DQS9_A_T||TDQS9_A_T': CDS_PINID='\dqs9_a_t||tdqs9_a_t\';
NET_NAME
'M_G_CPU1_SA_PAR'
 '@T6G_MB_LIB.T6G(SCH_1):M_G_CPU1_SA_PAR':
 C_SIGNAL='@t6g_mb_lib.t6g(sch_1):m_g_cpu1_sa_par';
NODE_NAME     U26 BC3
 '@T6G_MB_LIB.T6G(SCH_1):PAGE43_I167@PURE_QUANTA.GENOA_SP5(CHIPS)':
 'MGA_PAR': CDS_PINID='MGA_PAR';
NODE_NAME     J102 74
 '@T6G_MB_LIB.T6G(SCH_1):PAGE103_I22@PURE_QUANTA.SCONN288_DDR506112002KQ(CHIPS)':
 'PAR_A': CDS_PINID='PAR_A';
NET_NAME
'M_G_CPU1_SA_RSP<0>'
 '@T6G_MB_LIB.T6G(SCH_1):M_G_CPU1_SA_RSP'<0>:
 C_SIGNAL='@t6g_mb_lib.t6g(sch_1):m_g_cpu1_sa_rsp(0)';
NODE_NAME     U26 BN3
 '@T6G_MB_LIB.T6G(SCH_1):PAGE43_I167@PURE_QUANTA.GENOA_SP5(CHIPS)':
 'MGA0_RSP_L': CDS_PINID='MGA0_RSP_L';
NODE_NAME     J102 86
 '@T6G_MB_LIB.T6G(SCH_1):PAGE103_I22@PURE_QUANTA.SCONN288_DDR506112002KQ(CHIPS)':
 'LBD||RSP_A_N': CDS_PINID='\lbd||rsp_a_n\';
NET_NAME
'M_G_CPU1_SB_CA<0>'
 '@T6G_MB_LIB.T6G(SCH_1):M_G_CPU1_SB_CA'<0>:
 C_SIGNAL='@t6g_mb_lib.t6g(sch_1):m_g_cpu1_sb_ca(0)';
NODE_NAME     U26 BG3
 '@T6G_MB_LIB.T6G(SCH_1):PAGE43_I167@PURE_QUANTA.GENOA_SP5(CHIPS)':
 'MGB_CA0': CDS_PINID='MGB_CA0';
NODE_NAME     J102 76
 '@T6G_MB_LIB.T6G(SCH_1):PAGE103_I22@PURE_QUANTA.SCONN288_DDR506112002KQ(CHIPS)':
 'CA0_B': CDS_PINID='CA0_B';
NET_NAME
'M_G_CPU1_SB_CA<1>'
 '@T6G_MB_LIB.T6G(SCH_1):M_G_CPU1_SB_CA'<1>:
 C_SIGNAL='@t6g_mb_lib.t6g(sch_1):m_g_cpu1_sb_ca(1)';
NODE_NAME     U26 BH4
 '@T6G_MB_LIB.T6G(SCH_1):PAGE43_I167@PURE_QUANTA.GENOA_SP5(CHIPS)':
 'MGB_CA1': CDS_PINID='MGB_CA1';
NODE_NAME     J102 221
 '@T6G_MB_LIB.T6G(SCH_1):PAGE103_I22@PURE_QUANTA.SCONN288_DDR506112002KQ(CHIPS)':
 'CA1_B': CDS_PINID='CA1_B';
NET_NAME
'M_G_CPU1_SB_CA<2>'
 '@T6G_MB_LIB.T6G(SCH_1):M_G_CPU1_SB_CA'<2>:
 C_SIGNAL='@t6g_mb_lib.t6g(sch_1):m_g_cpu1_sb_ca(2)';
NODE_NAME     U26 BH2
 '@T6G_MB_LIB.T6G(SCH_1):PAGE43_I167@PURE_QUANTA.GENOA_SP5(CHIPS)':
 'MGB_CA2': CDS_PINID='MGB_CA2';
NODE_NAME     J102 78
 '@T6G_MB_LIB.T6G(SCH_1):PAGE103_I22@PURE_QUANTA.SCONN288_DDR506112002KQ(CHIPS)':
 'CA2_B': CDS_PINID='CA2_B';
NET_NAME
'M_G_CPU1_SB_CA<3>'
 '@T6G_MB_LIB.T6G(SCH_1):M_G_CPU1_SB_CA'<3>:
 C_SIGNAL='@t6g_mb_lib.t6g(sch_1):m_g_cpu1_sb_ca(3)';
NODE_NAME     U26 BJ2
 '@T6G_MB_LIB.T6G(SCH_1):PAGE43_I167@PURE_QUANTA.GENOA_SP5(CHIPS)':
 'MGB_CA3': CDS_PINID='MGB_CA3';
NODE_NAME     J102 223
 '@T6G_MB_LIB.T6G(SCH_1):PAGE103_I22@PURE_QUANTA.SCONN288_DDR506112002KQ(CHIPS)':
 'CA3_B': CDS_PINID='CA3_B';
NET_NAME
'M_G_CPU1_SB_CA<4>'
 '@T6G_MB_LIB.T6G(SCH_1):M_G_CPU1_SB_CA'<4>:
 C_SIGNAL='@t6g_mb_lib.t6g(sch_1):m_g_cpu1_sb_ca(4)';
NODE_NAME     U26 BJ3
 '@T6G_MB_LIB.T6G(SCH_1):PAGE43_I167@PURE_QUANTA.GENOA_SP5(CHIPS)':
 'MGB_CA4': CDS_PINID='MGB_CA4';
NODE_NAME     J102 80
 '@T6G_MB_LIB.T6G(SCH_1):PAGE103_I22@PURE_QUANTA.SCONN288_DDR506112002KQ(CHIPS)':
 'CA4_B': CDS_PINID='CA4_B';
NET_NAME
'M_G_CPU1_SB_CA<5>'
 '@T6G_MB_LIB.T6G(SCH_1):M_G_CPU1_SB_CA'<5>:
 C_SIGNAL='@t6g_mb_lib.t6g(sch_1):m_g_cpu1_sb_ca(5)';
NODE_NAME     U26 BK4
 '@T6G_MB_LIB.T6G(SCH_1):PAGE43_I167@PURE_QUANTA.GENOA_SP5(CHIPS)':
 'MGB_CA5': CDS_PINID='MGB_CA5';
NODE_NAME     J102 225
 '@T6G_MB_LIB.T6G(SCH_1):PAGE103_I22@PURE_QUANTA.SCONN288_DDR506112002KQ(CHIPS)':
 'CA5_B': CDS_PINID='CA5_B';
NET_NAME
'M_G_CPU1_SB_CA<6>'
 '@T6G_MB_LIB.T6G(SCH_1):M_G_CPU1_SB_CA'<6>:
 C_SIGNAL='@t6g_mb_lib.t6g(sch_1):m_g_cpu1_sb_ca(6)';
NODE_NAME     U26 BK2
 '@T6G_MB_LIB.T6G(SCH_1):PAGE43_I167@PURE_QUANTA.GENOA_SP5(CHIPS)':
 'MGB_CA6': CDS_PINID='MGB_CA6';
NODE_NAME     J102 82
 '@T6G_MB_LIB.T6G(SCH_1):PAGE103_I22@PURE_QUANTA.SCONN288_DDR506112002KQ(CHIPS)':
 'CA6_B': CDS_PINID='CA6_B';
NET_NAME
'M_G_CPU1_SB_CB<0>'
 '@T6G_MB_LIB.T6G(SCH_1):M_G_CPU1_SB_CB'<0>:
 C_SIGNAL='@t6g_mb_lib.t6g(sch_1):m_g_cpu1_sb_cb(0)';
NODE_NAME     U26 BY2
 '@T6G_MB_LIB.T6G(SCH_1):PAGE43_I167@PURE_QUANTA.GENOA_SP5(CHIPS)':
 'MGB_CHECK0': CDS_PINID='MGB_CHECK0';
NODE_NAME     J102 96
 '@T6G_MB_LIB.T6G(SCH_1):PAGE103_I22@PURE_QUANTA.SCONN288_DDR506112002KQ(CHIPS)':
 'CB0_B': CDS_PINID='CB0_B';
NET_NAME
'M_G_CPU1_SB_CB<1>'
 '@T6G_MB_LIB.T6G(SCH_1):M_G_CPU1_SB_CB'<1>:
 C_SIGNAL='@t6g_mb_lib.t6g(sch_1):m_g_cpu1_sb_cb(1)';
NODE_NAME     U26 CA3
 '@T6G_MB_LIB.T6G(SCH_1):PAGE43_I167@PURE_QUANTA.GENOA_SP5(CHIPS)':
 'MGB_CHECK1': CDS_PINID='MGB_CHECK1';
NODE_NAME     J102 98
 '@T6G_MB_LIB.T6G(SCH_1):PAGE103_I22@PURE_QUANTA.SCONN288_DDR506112002KQ(CHIPS)':
 'CB1_B': CDS_PINID='CB1_B';
NET_NAME
'M_G_CPU1_SB_CB<2>'
 '@T6G_MB_LIB.T6G(SCH_1):M_G_CPU1_SB_CB'<2>:
 C_SIGNAL='@t6g_mb_lib.t6g(sch_1):m_g_cpu1_sb_cb(2)';
NODE_NAME     U26 CA2
 '@T6G_MB_LIB.T6G(SCH_1):PAGE43_I167@PURE_QUANTA.GENOA_SP5(CHIPS)':
 'MGB_CHECK2': CDS_PINID='MGB_CHECK2';
NODE_NAME     J102 241
 '@T6G_MB_LIB.T6G(SCH_1):PAGE103_I22@PURE_QUANTA.SCONN288_DDR506112002KQ(CHIPS)':
 'CB2_B': CDS_PINID='CB2_B';
NET_NAME
'M_G_CPU1_SB_CB<3>'
 '@T6G_MB_LIB.T6G(SCH_1):M_G_CPU1_SB_CB'<3>:
 C_SIGNAL='@t6g_mb_lib.t6g(sch_1):m_g_cpu1_sb_cb(3)';
NODE_NAME     U26 CB4
 '@T6G_MB_LIB.T6G(SCH_1):PAGE43_I167@PURE_QUANTA.GENOA_SP5(CHIPS)':
 'MGB_CHECK3': CDS_PINID='MGB_CHECK3';
NODE_NAME     J102 243
 '@T6G_MB_LIB.T6G(SCH_1):PAGE103_I22@PURE_QUANTA.SCONN288_DDR506112002KQ(CHIPS)':
 'CB3_B': CDS_PINID='CB3_B';
NET_NAME
'M_G_CPU1_SB_CB<4>'
 '@T6G_MB_LIB.T6G(SCH_1):M_G_CPU1_SB_CB'<4>:
 C_SIGNAL='@t6g_mb_lib.t6g(sch_1):m_g_cpu1_sb_cb(4)';
NODE_NAME     U26 BT2
 '@T6G_MB_LIB.T6G(SCH_1):PAGE43_I167@PURE_QUANTA.GENOA_SP5(CHIPS)':
 'MGB_CHECK4': CDS_PINID='MGB_CHECK4';
NODE_NAME     J102 89
 '@T6G_MB_LIB.T6G(SCH_1):PAGE103_I22@PURE_QUANTA.SCONN288_DDR506112002KQ(CHIPS)':
 'CB4_B': CDS_PINID='CB4_B';
NET_NAME
'M_G_CPU1_SB_CB<5>'
 '@T6G_MB_LIB.T6G(SCH_1):M_G_CPU1_SB_CB'<5>:
 C_SIGNAL='@t6g_mb_lib.t6g(sch_1):m_g_cpu1_sb_cb(5)';
NODE_NAME     U26 BU3
 '@T6G_MB_LIB.T6G(SCH_1):PAGE43_I167@PURE_QUANTA.GENOA_SP5(CHIPS)':
 'MGB_CHECK5': CDS_PINID='MGB_CHECK5';
NODE_NAME     J102 91
 '@T6G_MB_LIB.T6G(SCH_1):PAGE103_I22@PURE_QUANTA.SCONN288_DDR506112002KQ(CHIPS)':
 'CB5_B': CDS_PINID='CB5_B';
NET_NAME
'M_G_CPU1_SB_CB<6>'
 '@T6G_MB_LIB.T6G(SCH_1):M_G_CPU1_SB_CB'<6>:
 C_SIGNAL='@t6g_mb_lib.t6g(sch_1):m_g_cpu1_sb_cb(6)';
NODE_NAME     U26 BU2
 '@T6G_MB_LIB.T6G(SCH_1):PAGE43_I167@PURE_QUANTA.GENOA_SP5(CHIPS)':
 'MGB_CHECK6': CDS_PINID='MGB_CHECK6';
NODE_NAME     J102 234
 '@T6G_MB_LIB.T6G(SCH_1):PAGE103_I22@PURE_QUANTA.SCONN288_DDR506112002KQ(CHIPS)':
 'CB6_B': CDS_PINID='CB6_B';
NET_NAME
'M_G_CPU1_SB_CB<7>'
 '@T6G_MB_LIB.T6G(SCH_1):M_G_CPU1_SB_CB'<7>:
 C_SIGNAL='@t6g_mb_lib.t6g(sch_1):m_g_cpu1_sb_cb(7)';
NODE_NAME     U26 BV4
 '@T6G_MB_LIB.T6G(SCH_1):PAGE43_I167@PURE_QUANTA.GENOA_SP5(CHIPS)':
 'MGB_CHECK7': CDS_PINID='MGB_CHECK7';
NODE_NAME     J102 236
 '@T6G_MB_LIB.T6G(SCH_1):PAGE103_I22@PURE_QUANTA.SCONN288_DDR506112002KQ(CHIPS)':
 'CB7_B': CDS_PINID='CB7_B';
NET_NAME
'M_G_CPU1_SB_CS_N<0>'
 '@T6G_MB_LIB.T6G(SCH_1):M_G_CPU1_SB_CS_N'<0>:
 C_SIGNAL='@t6g_mb_lib.t6g(sch_1):m_g_cpu1_sb_cs_n(0)';
NODE_NAME     U26 BM4
 '@T6G_MB_LIB.T6G(SCH_1):PAGE43_I167@PURE_QUANTA.GENOA_SP5(CHIPS)':
 'MGB0_CS_L0': CDS_PINID='MGB0_CS_L0';
NODE_NAME     J102 84
 '@T6G_MB_LIB.T6G(SCH_1):PAGE103_I22@PURE_QUANTA.SCONN288_DDR506112002KQ(CHIPS)':
 'CS0_B_N': CDS_PINID='CS0_B_N';
NET_NAME
'M_G_CPU1_SB_CS_N<1>'
 '@T6G_MB_LIB.T6G(SCH_1):M_G_CPU1_SB_CS_N'<1>:
 C_SIGNAL='@t6g_mb_lib.t6g(sch_1):m_g_cpu1_sb_cs_n(1)';
NODE_NAME     U26 BN2
 '@T6G_MB_LIB.T6G(SCH_1):PAGE43_I167@PURE_QUANTA.GENOA_SP5(CHIPS)':
 'MGB0_CS_L1': CDS_PINID='MGB0_CS_L1';
NODE_NAME     J102 229
 '@T6G_MB_LIB.T6G(SCH_1):PAGE103_I22@PURE_QUANTA.SCONN288_DDR506112002KQ(CHIPS)':
 'CS1_B_N': CDS_PINID='CS1_B_N';
NET_NAME
'M_G_CPU1_SB_DQ<0>'
 '@T6G_MB_LIB.T6G(SCH_1):M_G_CPU1_SB_DQ'<0>:
 C_SIGNAL='@t6g_mb_lib.t6g(sch_1):m_g_cpu1_sb_dq(0)';
NODE_NAME     U26 CB2
 '@T6G_MB_LIB.T6G(SCH_1):PAGE43_I167@PURE_QUANTA.GENOA_SP5(CHIPS)':
 'MGB_DATA0': CDS_PINID='MGB_DATA0';
NODE_NAME     J102 100
 '@T6G_MB_LIB.T6G(SCH_1):PAGE103_I22@PURE_QUANTA.SCONN288_DDR506112002KQ(CHIPS)':
 'DQ0_B': CDS_PINID='DQ0_B';
NET_NAME
'M_G_CPU1_SB_DQ<10>'
 '@T6G_MB_LIB.T6G(SCH_1):M_G_CPU1_SB_DQ'<10>:
 C_SIGNAL='@t6g_mb_lib.t6g(sch_1):m_g_cpu1_sb_dq(10)';
NODE_NAME     U26 CJ2
 '@T6G_MB_LIB.T6G(SCH_1):PAGE43_I167@PURE_QUANTA.GENOA_SP5(CHIPS)':
 'MGB_DATA10': CDS_PINID='MGB_DATA10';
NODE_NAME     J102 256
 '@T6G_MB_LIB.T6G(SCH_1):PAGE103_I22@PURE_QUANTA.SCONN288_DDR506112002KQ(CHIPS)':
 'DQ10_B': CDS_PINID='DQ10_B';
NET_NAME
'M_G_CPU1_SB_DQ<11>'
 '@T6G_MB_LIB.T6G(SCH_1):M_G_CPU1_SB_DQ'<11>:
 C_SIGNAL='@t6g_mb_lib.t6g(sch_1):m_g_cpu1_sb_dq(11)';
NODE_NAME     U26 CK4
 '@T6G_MB_LIB.T6G(SCH_1):PAGE43_I167@PURE_QUANTA.GENOA_SP5(CHIPS)':
 'MGB_DATA11': CDS_PINID='MGB_DATA11';
NODE_NAME     J102 258
 '@T6G_MB_LIB.T6G(SCH_1):PAGE103_I22@PURE_QUANTA.SCONN288_DDR506112002KQ(CHIPS)':
 'DQ11_B': CDS_PINID='DQ11_B';
NET_NAME
'M_G_CPU1_SB_DQ<12>'
 '@T6G_MB_LIB.T6G(SCH_1):M_G_CPU1_SB_DQ'<12>:
 C_SIGNAL='@t6g_mb_lib.t6g(sch_1):m_g_cpu1_sb_dq(12)';
NODE_NAME     U26 CM2
 '@T6G_MB_LIB.T6G(SCH_1):PAGE43_I167@PURE_QUANTA.GENOA_SP5(CHIPS)':
 'MGB_DATA12': CDS_PINID='MGB_DATA12';
NODE_NAME     J102 118
 '@T6G_MB_LIB.T6G(SCH_1):PAGE103_I22@PURE_QUANTA.SCONN288_DDR506112002KQ(CHIPS)':
 'DQ12_B': CDS_PINID='DQ12_B';
NET_NAME
'M_G_CPU1_SB_DQ<13>'
 '@T6G_MB_LIB.T6G(SCH_1):M_G_CPU1_SB_DQ'<13>:
 C_SIGNAL='@t6g_mb_lib.t6g(sch_1):m_g_cpu1_sb_dq(13)';
NODE_NAME     U26 CN3
 '@T6G_MB_LIB.T6G(SCH_1):PAGE43_I167@PURE_QUANTA.GENOA_SP5(CHIPS)':
 'MGB_DATA13': CDS_PINID='MGB_DATA13';
NODE_NAME     J102 120
 '@T6G_MB_LIB.T6G(SCH_1):PAGE103_I22@PURE_QUANTA.SCONN288_DDR506112002KQ(CHIPS)':
 'DQ13_B': CDS_PINID='DQ13_B';
NET_NAME
'M_G_CPU1_SB_DQ<14>'
 '@T6G_MB_LIB.T6G(SCH_1):M_G_CPU1_SB_DQ'<14>:
 C_SIGNAL='@t6g_mb_lib.t6g(sch_1):m_g_cpu1_sb_dq(14)';
NODE_NAME     U26 CN2
 '@T6G_MB_LIB.T6G(SCH_1):PAGE43_I167@PURE_QUANTA.GENOA_SP5(CHIPS)':
 'MGB_DATA14': CDS_PINID='MGB_DATA14';
NODE_NAME     J102 263
 '@T6G_MB_LIB.T6G(SCH_1):PAGE103_I22@PURE_QUANTA.SCONN288_DDR506112002KQ(CHIPS)':
 'DQ14_B': CDS_PINID='DQ14_B';
NET_NAME
'M_G_CPU1_SB_DQ<15>'
 '@T6G_MB_LIB.T6G(SCH_1):M_G_CPU1_SB_DQ'<15>:
 C_SIGNAL='@t6g_mb_lib.t6g(sch_1):m_g_cpu1_sb_dq(15)';
NODE_NAME     U26 CP4
 '@T6G_MB_LIB.T6G(SCH_1):PAGE43_I167@PURE_QUANTA.GENOA_SP5(CHIPS)':
 'MGB_DATA15': CDS_PINID='MGB_DATA15';
NODE_NAME     J102 265
 '@T6G_MB_LIB.T6G(SCH_1):PAGE103_I22@PURE_QUANTA.SCONN288_DDR506112002KQ(CHIPS)':
 'DQ15_B': CDS_PINID='DQ15_B';
NET_NAME
'M_G_CPU1_SB_DQ<16>'
 '@T6G_MB_LIB.T6G(SCH_1):M_G_CPU1_SB_DQ'<16>:
 C_SIGNAL='@t6g_mb_lib.t6g(sch_1):m_g_cpu1_sb_dq(16)';
NODE_NAME     U26 CP2
 '@T6G_MB_LIB.T6G(SCH_1):PAGE43_I167@PURE_QUANTA.GENOA_SP5(CHIPS)':
 'MGB_DATA16': CDS_PINID='MGB_DATA16';
NODE_NAME     J102 122
 '@T6G_MB_LIB.T6G(SCH_1):PAGE103_I22@PURE_QUANTA.SCONN288_DDR506112002KQ(CHIPS)':
 'DQ16_B': CDS_PINID='DQ16_B';
NET_NAME
'M_G_CPU1_SB_DQ<17>'
 '@T6G_MB_LIB.T6G(SCH_1):M_G_CPU1_SB_DQ'<17>:
 C_SIGNAL='@t6g_mb_lib.t6g(sch_1):m_g_cpu1_sb_dq(17)';
NODE_NAME     U26 CR3
 '@T6G_MB_LIB.T6G(SCH_1):PAGE43_I167@PURE_QUANTA.GENOA_SP5(CHIPS)':
 'MGB_DATA17': CDS_PINID='MGB_DATA17';
NODE_NAME     J102 124
 '@T6G_MB_LIB.T6G(SCH_1):PAGE103_I22@PURE_QUANTA.SCONN288_DDR506112002KQ(CHIPS)':
 'DQ17_B': CDS_PINID='DQ17_B';
NET_NAME
'M_G_CPU1_SB_DQ<18>'
 '@T6G_MB_LIB.T6G(SCH_1):M_G_CPU1_SB_DQ'<18>:
 C_SIGNAL='@t6g_mb_lib.t6g(sch_1):m_g_cpu1_sb_dq(18)';
NODE_NAME     U26 CR2
 '@T6G_MB_LIB.T6G(SCH_1):PAGE43_I167@PURE_QUANTA.GENOA_SP5(CHIPS)':
 'MGB_DATA18': CDS_PINID='MGB_DATA18';
NODE_NAME     J102 267
 '@T6G_MB_LIB.T6G(SCH_1):PAGE103_I22@PURE_QUANTA.SCONN288_DDR506112002KQ(CHIPS)':
 'DQ18_B': CDS_PINID='DQ18_B';
NET_NAME
'M_G_CPU1_SB_DQ<19>'
 '@T6G_MB_LIB.T6G(SCH_1):M_G_CPU1_SB_DQ'<19>:
 C_SIGNAL='@t6g_mb_lib.t6g(sch_1):m_g_cpu1_sb_dq(19)';
NODE_NAME     U26 CT4
 '@T6G_MB_LIB.T6G(SCH_1):PAGE43_I167@PURE_QUANTA.GENOA_SP5(CHIPS)':
 'MGB_DATA19': CDS_PINID='MGB_DATA19';
NODE_NAME     J102 269
 '@T6G_MB_LIB.T6G(SCH_1):PAGE103_I22@PURE_QUANTA.SCONN288_DDR506112002KQ(CHIPS)':
 'DQ19_B': CDS_PINID='DQ19_B';
NET_NAME
'M_G_CPU1_SB_DQ<1>'
 '@T6G_MB_LIB.T6G(SCH_1):M_G_CPU1_SB_DQ'<1>:
 C_SIGNAL='@t6g_mb_lib.t6g(sch_1):m_g_cpu1_sb_dq(1)';
NODE_NAME     U26 CC3
 '@T6G_MB_LIB.T6G(SCH_1):PAGE43_I167@PURE_QUANTA.GENOA_SP5(CHIPS)':
 'MGB_DATA1': CDS_PINID='MGB_DATA1';
NODE_NAME     J102 102
 '@T6G_MB_LIB.T6G(SCH_1):PAGE103_I22@PURE_QUANTA.SCONN288_DDR506112002KQ(CHIPS)':
 'DQ1_B': CDS_PINID='DQ1_B';
NET_NAME
'M_G_CPU1_SB_DQ<20>'
 '@T6G_MB_LIB.T6G(SCH_1):M_G_CPU1_SB_DQ'<20>:
 C_SIGNAL='@t6g_mb_lib.t6g(sch_1):m_g_cpu1_sb_dq(20)';
NODE_NAME     U26 CV2
 '@T6G_MB_LIB.T6G(SCH_1):PAGE43_I167@PURE_QUANTA.GENOA_SP5(CHIPS)':
 'MGB_DATA20': CDS_PINID='MGB_DATA20';
NODE_NAME     J102 129
 '@T6G_MB_LIB.T6G(SCH_1):PAGE103_I22@PURE_QUANTA.SCONN288_DDR506112002KQ(CHIPS)':
 'DQ20_B': CDS_PINID='DQ20_B';
NET_NAME
'M_G_CPU1_SB_DQ<21>'
 '@T6G_MB_LIB.T6G(SCH_1):M_G_CPU1_SB_DQ'<21>:
 C_SIGNAL='@t6g_mb_lib.t6g(sch_1):m_g_cpu1_sb_dq(21)';
NODE_NAME     U26 CW3
 '@T6G_MB_LIB.T6G(SCH_1):PAGE43_I167@PURE_QUANTA.GENOA_SP5(CHIPS)':
 'MGB_DATA21': CDS_PINID='MGB_DATA21';
NODE_NAME     J102 131
 '@T6G_MB_LIB.T6G(SCH_1):PAGE103_I22@PURE_QUANTA.SCONN288_DDR506112002KQ(CHIPS)':
 'DQ21_B': CDS_PINID='DQ21_B';
NET_NAME
'M_G_CPU1_SB_DQ<22>'
 '@T6G_MB_LIB.T6G(SCH_1):M_G_CPU1_SB_DQ'<22>:
 C_SIGNAL='@t6g_mb_lib.t6g(sch_1):m_g_cpu1_sb_dq(22)';
NODE_NAME     U26 CW2
 '@T6G_MB_LIB.T6G(SCH_1):PAGE43_I167@PURE_QUANTA.GENOA_SP5(CHIPS)':
 'MGB_DATA22': CDS_PINID='MGB_DATA22';
NODE_NAME     J102 274
 '@T6G_MB_LIB.T6G(SCH_1):PAGE103_I22@PURE_QUANTA.SCONN288_DDR506112002KQ(CHIPS)':
 'DQ22_B': CDS_PINID='DQ22_B';
NET_NAME
'M_G_CPU1_SB_DQ<23>'
 '@T6G_MB_LIB.T6G(SCH_1):M_G_CPU1_SB_DQ'<23>:
 C_SIGNAL='@t6g_mb_lib.t6g(sch_1):m_g_cpu1_sb_dq(23)';
NODE_NAME     U26 CY4
 '@T6G_MB_LIB.T6G(SCH_1):PAGE43_I167@PURE_QUANTA.GENOA_SP5(CHIPS)':
 'MGB_DATA23': CDS_PINID='MGB_DATA23';
NODE_NAME     J102 276
 '@T6G_MB_LIB.T6G(SCH_1):PAGE103_I22@PURE_QUANTA.SCONN288_DDR506112002KQ(CHIPS)':
 'DQ23_B': CDS_PINID='DQ23_B';
NET_NAME
'M_G_CPU1_SB_DQ<24>'
 '@T6G_MB_LIB.T6G(SCH_1):M_G_CPU1_SB_DQ'<24>:
 C_SIGNAL='@t6g_mb_lib.t6g(sch_1):m_g_cpu1_sb_dq(24)';
NODE_NAME     U26 CY2
 '@T6G_MB_LIB.T6G(SCH_1):PAGE43_I167@PURE_QUANTA.GENOA_SP5(CHIPS)':
 'MGB_DATA24': CDS_PINID='MGB_DATA24';
NODE_NAME     J102 133
 '@T6G_MB_LIB.T6G(SCH_1):PAGE103_I22@PURE_QUANTA.SCONN288_DDR506112002KQ(CHIPS)':
 'DQ24_B': CDS_PINID='DQ24_B';
NET_NAME
'M_G_CPU1_SB_DQ<25>'
 '@T6G_MB_LIB.T6G(SCH_1):M_G_CPU1_SB_DQ'<25>:
 C_SIGNAL='@t6g_mb_lib.t6g(sch_1):m_g_cpu1_sb_dq(25)';
NODE_NAME     U26 DA3
 '@T6G_MB_LIB.T6G(SCH_1):PAGE43_I167@PURE_QUANTA.GENOA_SP5(CHIPS)':
 'MGB_DATA25': CDS_PINID='MGB_DATA25';
NODE_NAME     J102 135
 '@T6G_MB_LIB.T6G(SCH_1):PAGE103_I22@PURE_QUANTA.SCONN288_DDR506112002KQ(CHIPS)':
 'DQ25_B': CDS_PINID='DQ25_B';
NET_NAME
'M_G_CPU1_SB_DQ<26>'
 '@T6G_MB_LIB.T6G(SCH_1):M_G_CPU1_SB_DQ'<26>:
 C_SIGNAL='@t6g_mb_lib.t6g(sch_1):m_g_cpu1_sb_dq(26)';
NODE_NAME     U26 DA2
 '@T6G_MB_LIB.T6G(SCH_1):PAGE43_I167@PURE_QUANTA.GENOA_SP5(CHIPS)':
 'MGB_DATA26': CDS_PINID='MGB_DATA26';
NODE_NAME     J102 278
 '@T6G_MB_LIB.T6G(SCH_1):PAGE103_I22@PURE_QUANTA.SCONN288_DDR506112002KQ(CHIPS)':
 'DQ26_B': CDS_PINID='DQ26_B';
NET_NAME
'M_G_CPU1_SB_DQ<27>'
 '@T6G_MB_LIB.T6G(SCH_1):M_G_CPU1_SB_DQ'<27>:
 C_SIGNAL='@t6g_mb_lib.t6g(sch_1):m_g_cpu1_sb_dq(27)';
NODE_NAME     U26 DB4
 '@T6G_MB_LIB.T6G(SCH_1):PAGE43_I167@PURE_QUANTA.GENOA_SP5(CHIPS)':
 'MGB_DATA27': CDS_PINID='MGB_DATA27';
NODE_NAME     J102 280
 '@T6G_MB_LIB.T6G(SCH_1):PAGE103_I22@PURE_QUANTA.SCONN288_DDR506112002KQ(CHIPS)':
 'DQ27_B': CDS_PINID='DQ27_B';
NET_NAME
'M_G_CPU1_SB_DQ<28>'
 '@T6G_MB_LIB.T6G(SCH_1):M_G_CPU1_SB_DQ'<28>:
 C_SIGNAL='@t6g_mb_lib.t6g(sch_1):m_g_cpu1_sb_dq(28)';
NODE_NAME     U26 DD2
 '@T6G_MB_LIB.T6G(SCH_1):PAGE43_I167@PURE_QUANTA.GENOA_SP5(CHIPS)':
 'MGB_DATA28': CDS_PINID='MGB_DATA28';
NODE_NAME     J102 140
 '@T6G_MB_LIB.T6G(SCH_1):PAGE103_I22@PURE_QUANTA.SCONN288_DDR506112002KQ(CHIPS)':
 'DQ28_B': CDS_PINID='DQ28_B';
NET_NAME
'M_G_CPU1_SB_DQ<29>'
 '@T6G_MB_LIB.T6G(SCH_1):M_G_CPU1_SB_DQ'<29>:
 C_SIGNAL='@t6g_mb_lib.t6g(sch_1):m_g_cpu1_sb_dq(29)';
NODE_NAME     U26 DE3
 '@T6G_MB_LIB.T6G(SCH_1):PAGE43_I167@PURE_QUANTA.GENOA_SP5(CHIPS)':
 'MGB_DATA29': CDS_PINID='MGB_DATA29';
NODE_NAME     J102 142
 '@T6G_MB_LIB.T6G(SCH_1):PAGE103_I22@PURE_QUANTA.SCONN288_DDR506112002KQ(CHIPS)':
 'DQ29_B': CDS_PINID='DQ29_B';
NET_NAME
'M_G_CPU1_SB_DQ<2>'
 '@T6G_MB_LIB.T6G(SCH_1):M_G_CPU1_SB_DQ'<2>:
 C_SIGNAL='@t6g_mb_lib.t6g(sch_1):m_g_cpu1_sb_dq(2)';
NODE_NAME     U26 CC2
 '@T6G_MB_LIB.T6G(SCH_1):PAGE43_I167@PURE_QUANTA.GENOA_SP5(CHIPS)':
 'MGB_DATA2': CDS_PINID='MGB_DATA2';
NODE_NAME     J102 245
 '@T6G_MB_LIB.T6G(SCH_1):PAGE103_I22@PURE_QUANTA.SCONN288_DDR506112002KQ(CHIPS)':
 'DQ2_B': CDS_PINID='DQ2_B';
NET_NAME
'M_G_CPU1_SB_DQ<30>'
 '@T6G_MB_LIB.T6G(SCH_1):M_G_CPU1_SB_DQ'<30>:
 C_SIGNAL='@t6g_mb_lib.t6g(sch_1):m_g_cpu1_sb_dq(30)';
NODE_NAME     U26 DE2
 '@T6G_MB_LIB.T6G(SCH_1):PAGE43_I167@PURE_QUANTA.GENOA_SP5(CHIPS)':
 'MGB_DATA30': CDS_PINID='MGB_DATA30';
NODE_NAME     J102 285
 '@T6G_MB_LIB.T6G(SCH_1):PAGE103_I22@PURE_QUANTA.SCONN288_DDR506112002KQ(CHIPS)':
 'DQ30_B': CDS_PINID='DQ30_B';
NET_NAME
'M_G_CPU1_SB_DQ<31>'
 '@T6G_MB_LIB.T6G(SCH_1):M_G_CPU1_SB_DQ'<31>:
 C_SIGNAL='@t6g_mb_lib.t6g(sch_1):m_g_cpu1_sb_dq(31)';
NODE_NAME     U26 DF2
 '@T6G_MB_LIB.T6G(SCH_1):PAGE43_I167@PURE_QUANTA.GENOA_SP5(CHIPS)':
 'MGB_DATA31': CDS_PINID='MGB_DATA31';
NODE_NAME     J102 287
 '@T6G_MB_LIB.T6G(SCH_1):PAGE103_I22@PURE_QUANTA.SCONN288_DDR506112002KQ(CHIPS)':
 'DQ31_B': CDS_PINID='DQ31_B';
NET_NAME
'M_G_CPU1_SB_DQ<3>'
 '@T6G_MB_LIB.T6G(SCH_1):M_G_CPU1_SB_DQ'<3>:
 C_SIGNAL='@t6g_mb_lib.t6g(sch_1):m_g_cpu1_sb_dq(3)';
NODE_NAME     U26 CD4
 '@T6G_MB_LIB.T6G(SCH_1):PAGE43_I167@PURE_QUANTA.GENOA_SP5(CHIPS)':
 'MGB_DATA3': CDS_PINID='MGB_DATA3';
NODE_NAME     J102 247
 '@T6G_MB_LIB.T6G(SCH_1):PAGE103_I22@PURE_QUANTA.SCONN288_DDR506112002KQ(CHIPS)':
 'DQ3_B': CDS_PINID='DQ3_B';
NET_NAME
'M_G_CPU1_SB_DQ<4>'
 '@T6G_MB_LIB.T6G(SCH_1):M_G_CPU1_SB_DQ'<4>:
 C_SIGNAL='@t6g_mb_lib.t6g(sch_1):m_g_cpu1_sb_dq(4)';
NODE_NAME     U26 CF2
 '@T6G_MB_LIB.T6G(SCH_1):PAGE43_I167@PURE_QUANTA.GENOA_SP5(CHIPS)':
 'MGB_DATA4': CDS_PINID='MGB_DATA4';
NODE_NAME     J102 107
 '@T6G_MB_LIB.T6G(SCH_1):PAGE103_I22@PURE_QUANTA.SCONN288_DDR506112002KQ(CHIPS)':
 'DQ4_B': CDS_PINID='DQ4_B';
NET_NAME
'M_G_CPU1_SB_DQ<5>'
 '@T6G_MB_LIB.T6G(SCH_1):M_G_CPU1_SB_DQ'<5>:
 C_SIGNAL='@t6g_mb_lib.t6g(sch_1):m_g_cpu1_sb_dq(5)';
NODE_NAME     U26 CG3
 '@T6G_MB_LIB.T6G(SCH_1):PAGE43_I167@PURE_QUANTA.GENOA_SP5(CHIPS)':
 'MGB_DATA5': CDS_PINID='MGB_DATA5';
NODE_NAME     J102 109
 '@T6G_MB_LIB.T6G(SCH_1):PAGE103_I22@PURE_QUANTA.SCONN288_DDR506112002KQ(CHIPS)':
 'DQ5_B': CDS_PINID='DQ5_B';
NET_NAME
'M_G_CPU1_SB_DQ<6>'
 '@T6G_MB_LIB.T6G(SCH_1):M_G_CPU1_SB_DQ'<6>:
 C_SIGNAL='@t6g_mb_lib.t6g(sch_1):m_g_cpu1_sb_dq(6)';
NODE_NAME     U26 CG2
 '@T6G_MB_LIB.T6G(SCH_1):PAGE43_I167@PURE_QUANTA.GENOA_SP5(CHIPS)':
 'MGB_DATA6': CDS_PINID='MGB_DATA6';
NODE_NAME     J102 252
 '@T6G_MB_LIB.T6G(SCH_1):PAGE103_I22@PURE_QUANTA.SCONN288_DDR506112002KQ(CHIPS)':
 'DQ6_B': CDS_PINID='DQ6_B';
NET_NAME
'M_G_CPU1_SB_DQ<7>'
 '@T6G_MB_LIB.T6G(SCH_1):M_G_CPU1_SB_DQ'<7>:
 C_SIGNAL='@t6g_mb_lib.t6g(sch_1):m_g_cpu1_sb_dq(7)';
NODE_NAME     U26 CH4
 '@T6G_MB_LIB.T6G(SCH_1):PAGE43_I167@PURE_QUANTA.GENOA_SP5(CHIPS)':
 'MGB_DATA7': CDS_PINID='MGB_DATA7';
NODE_NAME     J102 254
 '@T6G_MB_LIB.T6G(SCH_1):PAGE103_I22@PURE_QUANTA.SCONN288_DDR506112002KQ(CHIPS)':
 'DQ7_B': CDS_PINID='DQ7_B';
NET_NAME
'M_G_CPU1_SB_DQ<8>'
 '@T6G_MB_LIB.T6G(SCH_1):M_G_CPU1_SB_DQ'<8>:
 C_SIGNAL='@t6g_mb_lib.t6g(sch_1):m_g_cpu1_sb_dq(8)';
NODE_NAME     U26 CH2
 '@T6G_MB_LIB.T6G(SCH_1):PAGE43_I167@PURE_QUANTA.GENOA_SP5(CHIPS)':
 'MGB_DATA8': CDS_PINID='MGB_DATA8';
NODE_NAME     J102 111
 '@T6G_MB_LIB.T6G(SCH_1):PAGE103_I22@PURE_QUANTA.SCONN288_DDR506112002KQ(CHIPS)':
 'DQ8_B': CDS_PINID='DQ8_B';
NET_NAME
'M_G_CPU1_SB_DQ<9>'
 '@T6G_MB_LIB.T6G(SCH_1):M_G_CPU1_SB_DQ'<9>:
 C_SIGNAL='@t6g_mb_lib.t6g(sch_1):m_g_cpu1_sb_dq(9)';
NODE_NAME     U26 CJ3
 '@T6G_MB_LIB.T6G(SCH_1):PAGE43_I167@PURE_QUANTA.GENOA_SP5(CHIPS)':
 'MGB_DATA9': CDS_PINID='MGB_DATA9';
NODE_NAME     J102 113
 '@T6G_MB_LIB.T6G(SCH_1):PAGE103_I22@PURE_QUANTA.SCONN288_DDR506112002KQ(CHIPS)':
 'DQ9_B': CDS_PINID='DQ9_B';
NET_NAME
'M_G_CPU1_SB_DQS_DN<0>'
 '@T6G_MB_LIB.T6G(SCH_1):M_G_CPU1_SB_DQS_DN'<0>:
 C_SIGNAL='@t6g_mb_lib.t6g(sch_1):m_g_cpu1_sb_dqs_dn(0)';
NODE_NAME     U26 CE2
 '@T6G_MB_LIB.T6G(SCH_1):PAGE43_I167@PURE_QUANTA.GENOA_SP5(CHIPS)':
 'MGB_DQS_L0': CDS_PINID='MGB_DQS_L0';
NODE_NAME     J102 105
 '@T6G_MB_LIB.T6G(SCH_1):PAGE103_I238@PURE_QUANTA.SCONN288_DDR506112002KQ(CHIPS)':
 'DQS0_B_C': CDS_PINID='DQS0_B_C';
NET_NAME
'M_G_CPU1_SB_DQS_DN<1>'
 '@T6G_MB_LIB.T6G(SCH_1):M_G_CPU1_SB_DQS_DN'<1>:
 C_SIGNAL='@t6g_mb_lib.t6g(sch_1):m_g_cpu1_sb_dqs_dn(1)';
NODE_NAME     U26 CL2
 '@T6G_MB_LIB.T6G(SCH_1):PAGE43_I167@PURE_QUANTA.GENOA_SP5(CHIPS)':
 'MGB_DQS_L1': CDS_PINID='MGB_DQS_L1';
NODE_NAME     J102 116
 '@T6G_MB_LIB.T6G(SCH_1):PAGE103_I238@PURE_QUANTA.SCONN288_DDR506112002KQ(CHIPS)':
 'DQS1_B_C': CDS_PINID='DQS1_B_C';
NET_NAME
'M_G_CPU1_SB_DQS_DN<2>'
 '@T6G_MB_LIB.T6G(SCH_1):M_G_CPU1_SB_DQS_DN'<2>:
 C_SIGNAL='@t6g_mb_lib.t6g(sch_1):m_g_cpu1_sb_dqs_dn(2)';
NODE_NAME     U26 CU2
 '@T6G_MB_LIB.T6G(SCH_1):PAGE43_I167@PURE_QUANTA.GENOA_SP5(CHIPS)':
 'MGB_DQS_L2': CDS_PINID='MGB_DQS_L2';
NODE_NAME     J102 127
 '@T6G_MB_LIB.T6G(SCH_1):PAGE103_I238@PURE_QUANTA.SCONN288_DDR506112002KQ(CHIPS)':
 'DQS2_B_C': CDS_PINID='DQS2_B_C';
NET_NAME
'M_G_CPU1_SB_DQS_DN<3>'
 '@T6G_MB_LIB.T6G(SCH_1):M_G_CPU1_SB_DQS_DN'<3>:
 C_SIGNAL='@t6g_mb_lib.t6g(sch_1):m_g_cpu1_sb_dqs_dn(3)';
NODE_NAME     U26 DC2
 '@T6G_MB_LIB.T6G(SCH_1):PAGE43_I167@PURE_QUANTA.GENOA_SP5(CHIPS)':
 'MGB_DQS_L3': CDS_PINID='MGB_DQS_L3';
NODE_NAME     J102 138
 '@T6G_MB_LIB.T6G(SCH_1):PAGE103_I238@PURE_QUANTA.SCONN288_DDR506112002KQ(CHIPS)':
 'DQS3_B_C': CDS_PINID='DQS3_B_C';
NET_NAME
'M_G_CPU1_SB_DQS_DN<4>'
 '@T6G_MB_LIB.T6G(SCH_1):M_G_CPU1_SB_DQS_DN'<4>:
 C_SIGNAL='@t6g_mb_lib.t6g(sch_1):m_g_cpu1_sb_dqs_dn(4)';
NODE_NAME     U26 BW3
 '@T6G_MB_LIB.T6G(SCH_1):PAGE43_I167@PURE_QUANTA.GENOA_SP5(CHIPS)':
 'MGB_DQS_L4': CDS_PINID='MGB_DQS_L4';
NODE_NAME     J102 238
 '@T6G_MB_LIB.T6G(SCH_1):PAGE103_I238@PURE_QUANTA.SCONN288_DDR506112002KQ(CHIPS)':
 'DQS4_B_C': CDS_PINID='DQS4_B_C';
NET_NAME
'M_G_CPU1_SB_DQS_DN<5>'
 '@T6G_MB_LIB.T6G(SCH_1):M_G_CPU1_SB_DQS_DN'<5>:
 C_SIGNAL='@t6g_mb_lib.t6g(sch_1):m_g_cpu1_sb_dqs_dn(5)';
NODE_NAME     U26 CE3
 '@T6G_MB_LIB.T6G(SCH_1):PAGE43_I167@PURE_QUANTA.GENOA_SP5(CHIPS)':
 'MGB_DQS_L5': CDS_PINID='MGB_DQS_L5';
NODE_NAME     J102 249
 '@T6G_MB_LIB.T6G(SCH_1):PAGE103_I238@PURE_QUANTA.SCONN288_DDR506112002KQ(CHIPS)':
 'DQS5_B_C||TDQS5_B_C': CDS_PINID='\dqs5_b_c||tdqs5_b_c\';
NET_NAME
'M_G_CPU1_SB_DQS_DN<6>'
 '@T6G_MB_LIB.T6G(SCH_1):M_G_CPU1_SB_DQS_DN'<6>:
 C_SIGNAL='@t6g_mb_lib.t6g(sch_1):m_g_cpu1_sb_dqs_dn(6)';
NODE_NAME     U26 CL3
 '@T6G_MB_LIB.T6G(SCH_1):PAGE43_I167@PURE_QUANTA.GENOA_SP5(CHIPS)':
 'MGB_DQS_L6': CDS_PINID='MGB_DQS_L6';
NODE_NAME     J102 260
 '@T6G_MB_LIB.T6G(SCH_1):PAGE103_I238@PURE_QUANTA.SCONN288_DDR506112002KQ(CHIPS)':
 'DQS6_B_C||TDQS6_B_C': CDS_PINID='\dqs6_b_c||tdqs6_b_c\';
NET_NAME
'M_G_CPU1_SB_DQS_DN<7>'
 '@T6G_MB_LIB.T6G(SCH_1):M_G_CPU1_SB_DQS_DN'<7>:
 C_SIGNAL='@t6g_mb_lib.t6g(sch_1):m_g_cpu1_sb_dqs_dn(7)';
NODE_NAME     U26 CU3
 '@T6G_MB_LIB.T6G(SCH_1):PAGE43_I167@PURE_QUANTA.GENOA_SP5(CHIPS)':
 'MGB_DQS_L7': CDS_PINID='MGB_DQS_L7';
NODE_NAME     J102 271
 '@T6G_MB_LIB.T6G(SCH_1):PAGE103_I238@PURE_QUANTA.SCONN288_DDR506112002KQ(CHIPS)':
 'DQS7_B_C||TDQS7_B_C': CDS_PINID='\dqs7_b_c||tdqs7_b_c\';
NET_NAME
'M_G_CPU1_SB_DQS_DN<8>'
 '@T6G_MB_LIB.T6G(SCH_1):M_G_CPU1_SB_DQS_DN'<8>:
 C_SIGNAL='@t6g_mb_lib.t6g(sch_1):m_g_cpu1_sb_dqs_dn(8)';
NODE_NAME     U26 DC3
 '@T6G_MB_LIB.T6G(SCH_1):PAGE43_I167@PURE_QUANTA.GENOA_SP5(CHIPS)':
 'MGB_DQS_L8': CDS_PINID='MGB_DQS_L8';
NODE_NAME     J102 282
 '@T6G_MB_LIB.T6G(SCH_1):PAGE103_I238@PURE_QUANTA.SCONN288_DDR506112002KQ(CHIPS)':
 'DQS8_B_C||TDQS8_B_C': CDS_PINID='\dqs8_b_c||tdqs8_b_c\';
NET_NAME
'M_G_CPU1_SB_DQS_DN<9>'
 '@T6G_MB_LIB.T6G(SCH_1):M_G_CPU1_SB_DQS_DN'<9>:
 C_SIGNAL='@t6g_mb_lib.t6g(sch_1):m_g_cpu1_sb_dqs_dn(9)';
NODE_NAME     U26 BW2
 '@T6G_MB_LIB.T6G(SCH_1):PAGE43_I167@PURE_QUANTA.GENOA_SP5(CHIPS)':
 'MGB_DQS_L9': CDS_PINID='MGB_DQS_L9';
NODE_NAME     J102 94
 '@T6G_MB_LIB.T6G(SCH_1):PAGE103_I238@PURE_QUANTA.SCONN288_DDR506112002KQ(CHIPS)':
 'DQS9_B_C||TDQS9_B_C': CDS_PINID='\dqs9_b_c||tdqs9_b_c\';
NET_NAME
'M_G_CPU1_SB_DQS_DP<0>'
 '@T6G_MB_LIB.T6G(SCH_1):M_G_CPU1_SB_DQS_DP'<0>:
 C_SIGNAL='@t6g_mb_lib.t6g(sch_1):m_g_cpu1_sb_dqs_dp(0)';
NODE_NAME     U26 CD2
 '@T6G_MB_LIB.T6G(SCH_1):PAGE43_I167@PURE_QUANTA.GENOA_SP5(CHIPS)':
 'MGB_DQS_H0': CDS_PINID='MGB_DQS_H0';
NODE_NAME     J102 104
 '@T6G_MB_LIB.T6G(SCH_1):PAGE103_I238@PURE_QUANTA.SCONN288_DDR506112002KQ(CHIPS)':
 'DQS0_B_T': CDS_PINID='DQS0_B_T';
NET_NAME
'M_G_CPU1_SB_DQS_DP<1>'
 '@T6G_MB_LIB.T6G(SCH_1):M_G_CPU1_SB_DQS_DP'<1>:
 C_SIGNAL='@t6g_mb_lib.t6g(sch_1):m_g_cpu1_sb_dqs_dp(1)';
NODE_NAME     U26 CK2
 '@T6G_MB_LIB.T6G(SCH_1):PAGE43_I167@PURE_QUANTA.GENOA_SP5(CHIPS)':
 'MGB_DQS_H1': CDS_PINID='MGB_DQS_H1';
NODE_NAME     J102 115
 '@T6G_MB_LIB.T6G(SCH_1):PAGE103_I238@PURE_QUANTA.SCONN288_DDR506112002KQ(CHIPS)':
 'DQS1_B_T': CDS_PINID='DQS1_B_T';
NET_NAME
'M_G_CPU1_SB_DQS_DP<2>'
 '@T6G_MB_LIB.T6G(SCH_1):M_G_CPU1_SB_DQS_DP'<2>:
 C_SIGNAL='@t6g_mb_lib.t6g(sch_1):m_g_cpu1_sb_dqs_dp(2)';
NODE_NAME     U26 CT2
 '@T6G_MB_LIB.T6G(SCH_1):PAGE43_I167@PURE_QUANTA.GENOA_SP5(CHIPS)':
 'MGB_DQS_H2': CDS_PINID='MGB_DQS_H2';
NODE_NAME     J102 126
 '@T6G_MB_LIB.T6G(SCH_1):PAGE103_I238@PURE_QUANTA.SCONN288_DDR506112002KQ(CHIPS)':
 'DQS2_B_T': CDS_PINID='DQS2_B_T';
NET_NAME
'M_G_CPU1_SB_DQS_DP<3>'
 '@T6G_MB_LIB.T6G(SCH_1):M_G_CPU1_SB_DQS_DP'<3>:
 C_SIGNAL='@t6g_mb_lib.t6g(sch_1):m_g_cpu1_sb_dqs_dp(3)';
NODE_NAME     U26 DB2
 '@T6G_MB_LIB.T6G(SCH_1):PAGE43_I167@PURE_QUANTA.GENOA_SP5(CHIPS)':
 'MGB_DQS_H3': CDS_PINID='MGB_DQS_H3';
NODE_NAME     J102 137
 '@T6G_MB_LIB.T6G(SCH_1):PAGE103_I238@PURE_QUANTA.SCONN288_DDR506112002KQ(CHIPS)':
 'DQS3_B_T': CDS_PINID='DQS3_B_T';
NET_NAME
'M_G_CPU1_SB_DQS_DP<4>'
 '@T6G_MB_LIB.T6G(SCH_1):M_G_CPU1_SB_DQS_DP'<4>:
 C_SIGNAL='@t6g_mb_lib.t6g(sch_1):m_g_cpu1_sb_dqs_dp(4)';
NODE_NAME     U26 BY4
 '@T6G_MB_LIB.T6G(SCH_1):PAGE43_I167@PURE_QUANTA.GENOA_SP5(CHIPS)':
 'MGB_DQS_H4': CDS_PINID='MGB_DQS_H4';
NODE_NAME     J102 239
 '@T6G_MB_LIB.T6G(SCH_1):PAGE103_I238@PURE_QUANTA.SCONN288_DDR506112002KQ(CHIPS)':
 'DQS4_B_T': CDS_PINID='DQS4_B_T';
NET_NAME
'M_G_CPU1_SB_DQS_DP<5>'
 '@T6G_MB_LIB.T6G(SCH_1):M_G_CPU1_SB_DQS_DP'<5>:
 C_SIGNAL='@t6g_mb_lib.t6g(sch_1):m_g_cpu1_sb_dqs_dp(5)';
NODE_NAME     U26 CF4
 '@T6G_MB_LIB.T6G(SCH_1):PAGE43_I167@PURE_QUANTA.GENOA_SP5(CHIPS)':
 'MGB_DQS_H5': CDS_PINID='MGB_DQS_H5';
NODE_NAME     J102 250
 '@T6G_MB_LIB.T6G(SCH_1):PAGE103_I238@PURE_QUANTA.SCONN288_DDR506112002KQ(CHIPS)':
 'DQS5_B_T||TDQS5_B_T': CDS_PINID='\dqs5_b_t||tdqs5_b_t\';
NET_NAME
'M_G_CPU1_SB_DQS_DP<6>'
 '@T6G_MB_LIB.T6G(SCH_1):M_G_CPU1_SB_DQS_DP'<6>:
 C_SIGNAL='@t6g_mb_lib.t6g(sch_1):m_g_cpu1_sb_dqs_dp(6)';
NODE_NAME     U26 CM4
 '@T6G_MB_LIB.T6G(SCH_1):PAGE43_I167@PURE_QUANTA.GENOA_SP5(CHIPS)':
 'MGB_DQS_H6': CDS_PINID='MGB_DQS_H6';
NODE_NAME     J102 261
 '@T6G_MB_LIB.T6G(SCH_1):PAGE103_I238@PURE_QUANTA.SCONN288_DDR506112002KQ(CHIPS)':
 'DQS6_B_T||TDQS6_B_T': CDS_PINID='\dqs6_b_t||tdqs6_b_t\';
NET_NAME
'M_G_CPU1_SB_DQS_DP<7>'
 '@T6G_MB_LIB.T6G(SCH_1):M_G_CPU1_SB_DQS_DP'<7>:
 C_SIGNAL='@t6g_mb_lib.t6g(sch_1):m_g_cpu1_sb_dqs_dp(7)';
NODE_NAME     U26 CV4
 '@T6G_MB_LIB.T6G(SCH_1):PAGE43_I167@PURE_QUANTA.GENOA_SP5(CHIPS)':
 'MGB_DQS_H7': CDS_PINID='MGB_DQS_H7';
NODE_NAME     J102 272
 '@T6G_MB_LIB.T6G(SCH_1):PAGE103_I238@PURE_QUANTA.SCONN288_DDR506112002KQ(CHIPS)':
 'DQS7_B_T||TDQS7_B_T': CDS_PINID='\dqs7_b_t||tdqs7_b_t\';
NET_NAME
'M_G_CPU1_SB_DQS_DP<8>'
 '@T6G_MB_LIB.T6G(SCH_1):M_G_CPU1_SB_DQS_DP'<8>:
 C_SIGNAL='@t6g_mb_lib.t6g(sch_1):m_g_cpu1_sb_dqs_dp(8)';
NODE_NAME     U26 DD4
 '@T6G_MB_LIB.T6G(SCH_1):PAGE43_I167@PURE_QUANTA.GENOA_SP5(CHIPS)':
 'MGB_DQS_H8': CDS_PINID='MGB_DQS_H8';
NODE_NAME     J102 283
 '@T6G_MB_LIB.T6G(SCH_1):PAGE103_I238@PURE_QUANTA.SCONN288_DDR506112002KQ(CHIPS)':
 'DQS8_B_T||TDQS8_B_T': CDS_PINID='\dqs8_b_t||tdqs8_b_t\';
NET_NAME
'M_G_CPU1_SB_DQS_DP<9>'
 '@T6G_MB_LIB.T6G(SCH_1):M_G_CPU1_SB_DQS_DP'<9>:
 C_SIGNAL='@t6g_mb_lib.t6g(sch_1):m_g_cpu1_sb_dqs_dp(9)';
NODE_NAME     U26 BV2
 '@T6G_MB_LIB.T6G(SCH_1):PAGE43_I167@PURE_QUANTA.GENOA_SP5(CHIPS)':
 'MGB_DQS_H9': CDS_PINID='MGB_DQS_H9';
NODE_NAME     J102 93
 '@T6G_MB_LIB.T6G(SCH_1):PAGE103_I238@PURE_QUANTA.SCONN288_DDR506112002KQ(CHIPS)':
 'DQS9_B_T||TDQS9_B_T||DBI4_B_N': CDS_PINID='\dqs9_b_t||tdqs9_b_t||dbi4_b_n\';
NET_NAME
'M_G_CPU1_SB_PAR'
 '@T6G_MB_LIB.T6G(SCH_1):M_G_CPU1_SB_PAR':
 C_SIGNAL='@t6g_mb_lib.t6g(sch_1):m_g_cpu1_sb_par';
NODE_NAME     U26 BL3
 '@T6G_MB_LIB.T6G(SCH_1):PAGE43_I167@PURE_QUANTA.GENOA_SP5(CHIPS)':
 'MGB_PAR': CDS_PINID='MGB_PAR';
NODE_NAME     J102 227
 '@T6G_MB_LIB.T6G(SCH_1):PAGE103_I22@PURE_QUANTA.SCONN288_DDR506112002KQ(CHIPS)':
 'PAR_B': CDS_PINID='PAR_B';
NET_NAME
'M_G_CPU1_SB_RSP<0>'
 '@T6G_MB_LIB.T6G(SCH_1):M_G_CPU1_SB_RSP'<0>:
 C_SIGNAL='@t6g_mb_lib.t6g(sch_1):m_g_cpu1_sb_rsp(0)';
NODE_NAME     U26 BP2
 '@T6G_MB_LIB.T6G(SCH_1):PAGE43_I167@PURE_QUANTA.GENOA_SP5(CHIPS)':
 'MGB0_RSP_L': CDS_PINID='MGB0_RSP_L';
NODE_NAME     J102 87
 '@T6G_MB_LIB.T6G(SCH_1):PAGE103_I22@PURE_QUANTA.SCONN288_DDR506112002KQ(CHIPS)':
 'LBS||RSP_B_N': CDS_PINID='\lbs||rsp_b_n\';
NET_NAME
'M_H_CPU0_ALERT_N'
 '@T6G_MB_LIB.T6G(SCH_1):M_H_CPU0_ALERT_N':
 C_SIGNAL='@t6g_mb_lib.t6g(sch_1):m_h_cpu0_alert_n';
NODE_NAME     R382 1
 '@T6G_MB_LIB.T6G(SCH_1):PAGE17_I314@PURE_QUANTA.Q_RES(CHIPS)':
 'A': CDS_PINID='A';
NODE_NAME     J69 62
 '@T6G_MB_LIB.T6G(SCH_1):PAGE92_I22@PURE_QUANTA.SCONN288_DDR506112002KQ(CHIPS)':
 'ALERT_N': CDS_PINID='ALERT_N';
NET_NAME
'M_H_CPU0_ALERT_R_N'
 '@T6G_MB_LIB.T6G(SCH_1):M_H_CPU0_ALERT_R_N':
 C_SIGNAL='@t6g_mb_lib.t6g(sch_1):m_h_cpu0_alert_r_n';
NODE_NAME     U25 AT14
 '@T6G_MB_LIB.T6G(SCH_1):PAGE17_I159@PURE_QUANTA.GENOA_SP5(CHIPS)':
 'MH_ALERT_L': CDS_PINID='MH_ALERT_L';
NODE_NAME     R382 2
 '@T6G_MB_LIB.T6G(SCH_1):PAGE17_I314@PURE_QUANTA.Q_RES(CHIPS)':
 'B': CDS_PINID='B';
NET_NAME
'M_H_CPU0_CLK_DN<0>'
 '@T6G_MB_LIB.T6G(SCH_1):M_H_CPU0_CLK_DN'<0>:
 C_SIGNAL='@t6g_mb_lib.t6g(sch_1):m_h_cpu0_clk_dn(0)';
NODE_NAME     U25 BD13
 '@T6G_MB_LIB.T6G(SCH_1):PAGE17_I159@PURE_QUANTA.GENOA_SP5(CHIPS)':
 'MH0_CLK_L': CDS_PINID='MH0_CLK_L';
NODE_NAME     J69 218
 '@T6G_MB_LIB.T6G(SCH_1):PAGE92_I22@PURE_QUANTA.SCONN288_DDR506112002KQ(CHIPS)':
 'CK_C': CDS_PINID='CK_C';
NET_NAME
'M_H_CPU0_CLK_DP<0>'
 '@T6G_MB_LIB.T6G(SCH_1):M_H_CPU0_CLK_DP'<0>:
 C_SIGNAL='@t6g_mb_lib.t6g(sch_1):m_h_cpu0_clk_dp(0)';
NODE_NAME     U25 BC12
 '@T6G_MB_LIB.T6G(SCH_1):PAGE17_I159@PURE_QUANTA.GENOA_SP5(CHIPS)':
 'MH0_CLK_H': CDS_PINID='MH0_CLK_H';
NODE_NAME     J69 217
 '@T6G_MB_LIB.T6G(SCH_1):PAGE92_I22@PURE_QUANTA.SCONN288_DDR506112002KQ(CHIPS)':
 'CK_T': CDS_PINID='CK_T';
NET_NAME
'M_H_CPU0_RESET_N'
 '@T6G_MB_LIB.T6G(SCH_1):M_H_CPU0_RESET_N':
 C_SIGNAL='@t6g_mb_lib.t6g(sch_1):m_h_cpu0_reset_n';
NODE_NAME     U25 AU14
 '@T6G_MB_LIB.T6G(SCH_1):PAGE17_I159@PURE_QUANTA.GENOA_SP5(CHIPS)':
 'MH_RESET_L': CDS_PINID='MH_RESET_L';
NODE_NAME     J69 207
 '@T6G_MB_LIB.T6G(SCH_1):PAGE92_I22@PURE_QUANTA.SCONN288_DDR506112002KQ(CHIPS)':
 'RESET_N': CDS_PINID='RESET_N';
NET_NAME
'M_H_CPU0_SA_CA<0>'
 '@T6G_MB_LIB.T6G(SCH_1):M_H_CPU0_SA_CA'<0>:
 C_SIGNAL='@t6g_mb_lib.t6g(sch_1):m_h_cpu0_sa_ca(0)';
NODE_NAME     U25 AW12
 '@T6G_MB_LIB.T6G(SCH_1):PAGE17_I159@PURE_QUANTA.GENOA_SP5(CHIPS)':
 'MHA_CA0': CDS_PINID='MHA_CA0';
NODE_NAME     J69 66
 '@T6G_MB_LIB.T6G(SCH_1):PAGE92_I22@PURE_QUANTA.SCONN288_DDR506112002KQ(CHIPS)':
 'CA0_A': CDS_PINID='CA0_A';
NET_NAME
'M_H_CPU0_SA_CA<1>'
 '@T6G_MB_LIB.T6G(SCH_1):M_H_CPU0_SA_CA'<1>:
 C_SIGNAL='@t6g_mb_lib.t6g(sch_1):m_h_cpu0_sa_ca(1)';
NODE_NAME     U25 AY13
 '@T6G_MB_LIB.T6G(SCH_1):PAGE17_I159@PURE_QUANTA.GENOA_SP5(CHIPS)':
 'MHA_CA1': CDS_PINID='MHA_CA1';
NODE_NAME     J69 211
 '@T6G_MB_LIB.T6G(SCH_1):PAGE92_I22@PURE_QUANTA.SCONN288_DDR506112002KQ(CHIPS)':
 'CA1_A': CDS_PINID='CA1_A';
NET_NAME
'M_H_CPU0_SA_CA<2>'
 '@T6G_MB_LIB.T6G(SCH_1):M_H_CPU0_SA_CA'<2>:
 C_SIGNAL='@t6g_mb_lib.t6g(sch_1):m_h_cpu0_sa_ca(2)';
NODE_NAME     U25 AY14
 '@T6G_MB_LIB.T6G(SCH_1):PAGE17_I159@PURE_QUANTA.GENOA_SP5(CHIPS)':
 'MHA_CA2': CDS_PINID='MHA_CA2';
NODE_NAME     J69 68
 '@T6G_MB_LIB.T6G(SCH_1):PAGE92_I22@PURE_QUANTA.SCONN288_DDR506112002KQ(CHIPS)':
 'CA2_A': CDS_PINID='CA2_A';
NET_NAME
'M_H_CPU0_SA_CA<3>'
 '@T6G_MB_LIB.T6G(SCH_1):M_H_CPU0_SA_CA'<3>:
 C_SIGNAL='@t6g_mb_lib.t6g(sch_1):m_h_cpu0_sa_ca(3)';
NODE_NAME     U25 BA14
 '@T6G_MB_LIB.T6G(SCH_1):PAGE17_I159@PURE_QUANTA.GENOA_SP5(CHIPS)':
 'MHA_CA3': CDS_PINID='MHA_CA3';
NODE_NAME     J69 213
 '@T6G_MB_LIB.T6G(SCH_1):PAGE92_I22@PURE_QUANTA.SCONN288_DDR506112002KQ(CHIPS)':
 'CA3_A': CDS_PINID='CA3_A';
NET_NAME
'M_H_CPU0_SA_CA<4>'
 '@T6G_MB_LIB.T6G(SCH_1):M_H_CPU0_SA_CA'<4>:
 C_SIGNAL='@t6g_mb_lib.t6g(sch_1):m_h_cpu0_sa_ca(4)';
NODE_NAME     U25 BA12
 '@T6G_MB_LIB.T6G(SCH_1):PAGE17_I159@PURE_QUANTA.GENOA_SP5(CHIPS)':
 'MHA_CA4': CDS_PINID='MHA_CA4';
NODE_NAME     J69 70
 '@T6G_MB_LIB.T6G(SCH_1):PAGE92_I22@PURE_QUANTA.SCONN288_DDR506112002KQ(CHIPS)':
 'CA4_A': CDS_PINID='CA4_A';
NET_NAME
'M_H_CPU0_SA_CA<5>'
 '@T6G_MB_LIB.T6G(SCH_1):M_H_CPU0_SA_CA'<5>:
 C_SIGNAL='@t6g_mb_lib.t6g(sch_1):m_h_cpu0_sa_ca(5)';
NODE_NAME     U25 BB13
 '@T6G_MB_LIB.T6G(SCH_1):PAGE17_I159@PURE_QUANTA.GENOA_SP5(CHIPS)':
 'MHA_CA5': CDS_PINID='MHA_CA5';
NODE_NAME     J69 215
 '@T6G_MB_LIB.T6G(SCH_1):PAGE92_I22@PURE_QUANTA.SCONN288_DDR506112002KQ(CHIPS)':
 'CA5_A': CDS_PINID='CA5_A';
NET_NAME
'M_H_CPU0_SA_CA<6>'
 '@T6G_MB_LIB.T6G(SCH_1):M_H_CPU0_SA_CA'<6>:
 C_SIGNAL='@t6g_mb_lib.t6g(sch_1):m_h_cpu0_sa_ca(6)';
NODE_NAME     U25 BB14
 '@T6G_MB_LIB.T6G(SCH_1):PAGE17_I159@PURE_QUANTA.GENOA_SP5(CHIPS)':
 'MHA_CA6': CDS_PINID='MHA_CA6';
NODE_NAME     J69 72
 '@T6G_MB_LIB.T6G(SCH_1):PAGE92_I22@PURE_QUANTA.SCONN288_DDR506112002KQ(CHIPS)':
 'CA6_A': CDS_PINID='CA6_A';
NET_NAME
'M_H_CPU0_SA_CB<0>'
 '@T6G_MB_LIB.T6G(SCH_1):M_H_CPU0_SA_CB'<0>:
 C_SIGNAL='@t6g_mb_lib.t6g(sch_1):m_h_cpu0_sa_cb(0)';
NODE_NAME     U25 AJ12
 '@T6G_MB_LIB.T6G(SCH_1):PAGE17_I159@PURE_QUANTA.GENOA_SP5(CHIPS)':
 'MHA_CHECK0': CDS_PINID='MHA_CHECK0';
NODE_NAME     J69 51
 '@T6G_MB_LIB.T6G(SCH_1):PAGE92_I22@PURE_QUANTA.SCONN288_DDR506112002KQ(CHIPS)':
 'CB0_A': CDS_PINID='CB0_A';
NET_NAME
'M_H_CPU0_SA_CB<1>'
 '@T6G_MB_LIB.T6G(SCH_1):M_H_CPU0_SA_CB'<1>:
 C_SIGNAL='@t6g_mb_lib.t6g(sch_1):m_h_cpu0_sa_cb(1)';
NODE_NAME     U25 AK14
 '@T6G_MB_LIB.T6G(SCH_1):PAGE17_I159@PURE_QUANTA.GENOA_SP5(CHIPS)':
 'MHA_CHECK1': CDS_PINID='MHA_CHECK1';
NODE_NAME     J69 53
 '@T6G_MB_LIB.T6G(SCH_1):PAGE92_I22@PURE_QUANTA.SCONN288_DDR506112002KQ(CHIPS)':
 'CB1_A': CDS_PINID='CB1_A';
NET_NAME
'M_H_CPU0_SA_CB<2>'
 '@T6G_MB_LIB.T6G(SCH_1):M_H_CPU0_SA_CB'<2>:
 C_SIGNAL='@t6g_mb_lib.t6g(sch_1):m_h_cpu0_sa_cb(2)';
NODE_NAME     U25 AK13
 '@T6G_MB_LIB.T6G(SCH_1):PAGE17_I159@PURE_QUANTA.GENOA_SP5(CHIPS)':
 'MHA_CHECK2': CDS_PINID='MHA_CHECK2';
NODE_NAME     J69 196
 '@T6G_MB_LIB.T6G(SCH_1):PAGE92_I22@PURE_QUANTA.SCONN288_DDR506112002KQ(CHIPS)':
 'CB2_A': CDS_PINID='CB2_A';
NET_NAME
'M_H_CPU0_SA_CB<3>'
 '@T6G_MB_LIB.T6G(SCH_1):M_H_CPU0_SA_CB'<3>:
 C_SIGNAL='@t6g_mb_lib.t6g(sch_1):m_h_cpu0_sa_cb(3)';
NODE_NAME     U25 AL14
 '@T6G_MB_LIB.T6G(SCH_1):PAGE17_I159@PURE_QUANTA.GENOA_SP5(CHIPS)':
 'MHA_CHECK3': CDS_PINID='MHA_CHECK3';
NODE_NAME     J69 198
 '@T6G_MB_LIB.T6G(SCH_1):PAGE92_I22@PURE_QUANTA.SCONN288_DDR506112002KQ(CHIPS)':
 'CB3_A': CDS_PINID='CB3_A';
NET_NAME
'M_H_CPU0_SA_CB<4>'
 '@T6G_MB_LIB.T6G(SCH_1):M_H_CPU0_SA_CB'<4>:
 C_SIGNAL='@t6g_mb_lib.t6g(sch_1):m_h_cpu0_sa_cb(4)';
NODE_NAME     U25 AN12
 '@T6G_MB_LIB.T6G(SCH_1):PAGE17_I159@PURE_QUANTA.GENOA_SP5(CHIPS)':
 'MHA_CHECK4': CDS_PINID='MHA_CHECK4';
NODE_NAME     J69 58
 '@T6G_MB_LIB.T6G(SCH_1):PAGE92_I22@PURE_QUANTA.SCONN288_DDR506112002KQ(CHIPS)':
 'CB4_A': CDS_PINID='CB4_A';
NET_NAME
'M_H_CPU0_SA_CB<5>'
 '@T6G_MB_LIB.T6G(SCH_1):M_H_CPU0_SA_CB'<5>:
 C_SIGNAL='@t6g_mb_lib.t6g(sch_1):m_h_cpu0_sa_cb(5)';
NODE_NAME     U25 AP14
 '@T6G_MB_LIB.T6G(SCH_1):PAGE17_I159@PURE_QUANTA.GENOA_SP5(CHIPS)':
 'MHA_CHECK5': CDS_PINID='MHA_CHECK5';
NODE_NAME     J69 60
 '@T6G_MB_LIB.T6G(SCH_1):PAGE92_I22@PURE_QUANTA.SCONN288_DDR506112002KQ(CHIPS)':
 'CB5_A': CDS_PINID='CB5_A';
NET_NAME
'M_H_CPU0_SA_CB<6>'
 '@T6G_MB_LIB.T6G(SCH_1):M_H_CPU0_SA_CB'<6>:
 C_SIGNAL='@t6g_mb_lib.t6g(sch_1):m_h_cpu0_sa_cb(6)';
NODE_NAME     U25 AP13
 '@T6G_MB_LIB.T6G(SCH_1):PAGE17_I159@PURE_QUANTA.GENOA_SP5(CHIPS)':
 'MHA_CHECK6': CDS_PINID='MHA_CHECK6';
NODE_NAME     J69 203
 '@T6G_MB_LIB.T6G(SCH_1):PAGE92_I22@PURE_QUANTA.SCONN288_DDR506112002KQ(CHIPS)':
 'CB6_A': CDS_PINID='CB6_A';
NET_NAME
'M_H_CPU0_SA_CB<7>'
 '@T6G_MB_LIB.T6G(SCH_1):M_H_CPU0_SA_CB'<7>:
 C_SIGNAL='@t6g_mb_lib.t6g(sch_1):m_h_cpu0_sa_cb(7)';
NODE_NAME     U25 AR14
 '@T6G_MB_LIB.T6G(SCH_1):PAGE17_I159@PURE_QUANTA.GENOA_SP5(CHIPS)':
 'MHA_CHECK7': CDS_PINID='MHA_CHECK7';
NODE_NAME     J69 205
 '@T6G_MB_LIB.T6G(SCH_1):PAGE92_I22@PURE_QUANTA.SCONN288_DDR506112002KQ(CHIPS)':
 'CB7_A': CDS_PINID='CB7_A';
NET_NAME
'M_H_CPU0_SA_CS_N<0>'
 '@T6G_MB_LIB.T6G(SCH_1):M_H_CPU0_SA_CS_N'<0>:
 C_SIGNAL='@t6g_mb_lib.t6g(sch_1):m_h_cpu0_sa_cs_n(0)';
NODE_NAME     U25 AU12
 '@T6G_MB_LIB.T6G(SCH_1):PAGE17_I159@PURE_QUANTA.GENOA_SP5(CHIPS)':
 'MHA0_CS_L0': CDS_PINID='MHA0_CS_L0';
NODE_NAME     J69 64
 '@T6G_MB_LIB.T6G(SCH_1):PAGE92_I22@PURE_QUANTA.SCONN288_DDR506112002KQ(CHIPS)':
 'CS0_A_N': CDS_PINID='CS0_A_N';
NET_NAME
'M_H_CPU0_SA_CS_N<1>'
 '@T6G_MB_LIB.T6G(SCH_1):M_H_CPU0_SA_CS_N'<1>:
 C_SIGNAL='@t6g_mb_lib.t6g(sch_1):m_h_cpu0_sa_cs_n(1)';
NODE_NAME     U25 AV14
 '@T6G_MB_LIB.T6G(SCH_1):PAGE17_I159@PURE_QUANTA.GENOA_SP5(CHIPS)':
 'MHA0_CS_L1': CDS_PINID='MHA0_CS_L1';
NODE_NAME     J69 209
 '@T6G_MB_LIB.T6G(SCH_1):PAGE92_I22@PURE_QUANTA.SCONN288_DDR506112002KQ(CHIPS)':
 'CS1_A_N': CDS_PINID='CS1_A_N';
NET_NAME
'M_H_CPU0_SA_DQ<0>'
 '@T6G_MB_LIB.T6G(SCH_1):M_H_CPU0_SA_DQ'<0>:
 C_SIGNAL='@t6g_mb_lib.t6g(sch_1):m_h_cpu0_sa_dq(0)';
NODE_NAME     U25 E12
 '@T6G_MB_LIB.T6G(SCH_1):PAGE17_I159@PURE_QUANTA.GENOA_SP5(CHIPS)':
 'MHA_DATA0': CDS_PINID='MHA_DATA0';
NODE_NAME     J69 7
 '@T6G_MB_LIB.T6G(SCH_1):PAGE92_I22@PURE_QUANTA.SCONN288_DDR506112002KQ(CHIPS)':
 'DQ0_A': CDS_PINID='DQ0_A';
NET_NAME
'M_H_CPU0_SA_DQ<10>'
 '@T6G_MB_LIB.T6G(SCH_1):M_H_CPU0_SA_DQ'<10>:
 C_SIGNAL='@t6g_mb_lib.t6g(sch_1):m_h_cpu0_sa_dq(10)';
NODE_NAME     U25 M13
 '@T6G_MB_LIB.T6G(SCH_1):PAGE17_I159@PURE_QUANTA.GENOA_SP5(CHIPS)':
 'MHA_DATA10': CDS_PINID='MHA_DATA10';
NODE_NAME     J69 163
 '@T6G_MB_LIB.T6G(SCH_1):PAGE92_I22@PURE_QUANTA.SCONN288_DDR506112002KQ(CHIPS)':
 'DQ10_A': CDS_PINID='DQ10_A';
NET_NAME
'M_H_CPU0_SA_DQ<11>'
 '@T6G_MB_LIB.T6G(SCH_1):M_H_CPU0_SA_DQ'<11>:
 C_SIGNAL='@t6g_mb_lib.t6g(sch_1):m_h_cpu0_sa_dq(11)';
NODE_NAME     U25 N14
 '@T6G_MB_LIB.T6G(SCH_1):PAGE17_I159@PURE_QUANTA.GENOA_SP5(CHIPS)':
 'MHA_DATA11': CDS_PINID='MHA_DATA11';
NODE_NAME     J69 165
 '@T6G_MB_LIB.T6G(SCH_1):PAGE92_I22@PURE_QUANTA.SCONN288_DDR506112002KQ(CHIPS)':
 'DQ11_A': CDS_PINID='DQ11_A';
NET_NAME
'M_H_CPU0_SA_DQ<12>'
 '@T6G_MB_LIB.T6G(SCH_1):M_H_CPU0_SA_DQ'<12>:
 C_SIGNAL='@t6g_mb_lib.t6g(sch_1):m_h_cpu0_sa_dq(12)';
NODE_NAME     U25 R12
 '@T6G_MB_LIB.T6G(SCH_1):PAGE17_I159@PURE_QUANTA.GENOA_SP5(CHIPS)':
 'MHA_DATA12': CDS_PINID='MHA_DATA12';
NODE_NAME     J69 25
 '@T6G_MB_LIB.T6G(SCH_1):PAGE92_I22@PURE_QUANTA.SCONN288_DDR506112002KQ(CHIPS)':
 'DQ12_A': CDS_PINID='DQ12_A';
NET_NAME
'M_H_CPU0_SA_DQ<13>'
 '@T6G_MB_LIB.T6G(SCH_1):M_H_CPU0_SA_DQ'<13>:
 C_SIGNAL='@t6g_mb_lib.t6g(sch_1):m_h_cpu0_sa_dq(13)';
NODE_NAME     U25 T14
 '@T6G_MB_LIB.T6G(SCH_1):PAGE17_I159@PURE_QUANTA.GENOA_SP5(CHIPS)':
 'MHA_DATA13': CDS_PINID='MHA_DATA13';
NODE_NAME     J69 27
 '@T6G_MB_LIB.T6G(SCH_1):PAGE92_I22@PURE_QUANTA.SCONN288_DDR506112002KQ(CHIPS)':
 'DQ13_A': CDS_PINID='DQ13_A';
NET_NAME
'M_H_CPU0_SA_DQ<14>'
 '@T6G_MB_LIB.T6G(SCH_1):M_H_CPU0_SA_DQ'<14>:
 C_SIGNAL='@t6g_mb_lib.t6g(sch_1):m_h_cpu0_sa_dq(14)';
NODE_NAME     U25 T13
 '@T6G_MB_LIB.T6G(SCH_1):PAGE17_I159@PURE_QUANTA.GENOA_SP5(CHIPS)':
 'MHA_DATA14': CDS_PINID='MHA_DATA14';
NODE_NAME     J69 170
 '@T6G_MB_LIB.T6G(SCH_1):PAGE92_I22@PURE_QUANTA.SCONN288_DDR506112002KQ(CHIPS)':
 'DQ14_A': CDS_PINID='DQ14_A';
NET_NAME
'M_H_CPU0_SA_DQ<15>'
 '@T6G_MB_LIB.T6G(SCH_1):M_H_CPU0_SA_DQ'<15>:
 C_SIGNAL='@t6g_mb_lib.t6g(sch_1):m_h_cpu0_sa_dq(15)';
NODE_NAME     U25 U14
 '@T6G_MB_LIB.T6G(SCH_1):PAGE17_I159@PURE_QUANTA.GENOA_SP5(CHIPS)':
 'MHA_DATA15': CDS_PINID='MHA_DATA15';
NODE_NAME     J69 172
 '@T6G_MB_LIB.T6G(SCH_1):PAGE92_I22@PURE_QUANTA.SCONN288_DDR506112002KQ(CHIPS)':
 'DQ15_A': CDS_PINID='DQ15_A';
NET_NAME
'M_H_CPU0_SA_DQ<16>'
 '@T6G_MB_LIB.T6G(SCH_1):M_H_CPU0_SA_DQ'<16>:
 C_SIGNAL='@t6g_mb_lib.t6g(sch_1):m_h_cpu0_sa_dq(16)';
NODE_NAME     U25 U12
 '@T6G_MB_LIB.T6G(SCH_1):PAGE17_I159@PURE_QUANTA.GENOA_SP5(CHIPS)':
 'MHA_DATA16': CDS_PINID='MHA_DATA16';
NODE_NAME     J69 29
 '@T6G_MB_LIB.T6G(SCH_1):PAGE92_I22@PURE_QUANTA.SCONN288_DDR506112002KQ(CHIPS)':
 'DQ16_A': CDS_PINID='DQ16_A';
NET_NAME
'M_H_CPU0_SA_DQ<17>'
 '@T6G_MB_LIB.T6G(SCH_1):M_H_CPU0_SA_DQ'<17>:
 C_SIGNAL='@t6g_mb_lib.t6g(sch_1):m_h_cpu0_sa_dq(17)';
NODE_NAME     U25 V14
 '@T6G_MB_LIB.T6G(SCH_1):PAGE17_I159@PURE_QUANTA.GENOA_SP5(CHIPS)':
 'MHA_DATA17': CDS_PINID='MHA_DATA17';
NODE_NAME     J69 31
 '@T6G_MB_LIB.T6G(SCH_1):PAGE92_I22@PURE_QUANTA.SCONN288_DDR506112002KQ(CHIPS)':
 'DQ17_A': CDS_PINID='DQ17_A';
NET_NAME
'M_H_CPU0_SA_DQ<18>'
 '@T6G_MB_LIB.T6G(SCH_1):M_H_CPU0_SA_DQ'<18>:
 C_SIGNAL='@t6g_mb_lib.t6g(sch_1):m_h_cpu0_sa_dq(18)';
NODE_NAME     U25 V13
 '@T6G_MB_LIB.T6G(SCH_1):PAGE17_I159@PURE_QUANTA.GENOA_SP5(CHIPS)':
 'MHA_DATA18': CDS_PINID='MHA_DATA18';
NODE_NAME     J69 174
 '@T6G_MB_LIB.T6G(SCH_1):PAGE92_I22@PURE_QUANTA.SCONN288_DDR506112002KQ(CHIPS)':
 'DQ18_A': CDS_PINID='DQ18_A';
NET_NAME
'M_H_CPU0_SA_DQ<19>'
 '@T6G_MB_LIB.T6G(SCH_1):M_H_CPU0_SA_DQ'<19>:
 C_SIGNAL='@t6g_mb_lib.t6g(sch_1):m_h_cpu0_sa_dq(19)';
NODE_NAME     U25 W14
 '@T6G_MB_LIB.T6G(SCH_1):PAGE17_I159@PURE_QUANTA.GENOA_SP5(CHIPS)':
 'MHA_DATA19': CDS_PINID='MHA_DATA19';
NODE_NAME     J69 176
 '@T6G_MB_LIB.T6G(SCH_1):PAGE92_I22@PURE_QUANTA.SCONN288_DDR506112002KQ(CHIPS)':
 'DQ19_A': CDS_PINID='DQ19_A';
NET_NAME
'M_H_CPU0_SA_DQ<1>'
 '@T6G_MB_LIB.T6G(SCH_1):M_H_CPU0_SA_DQ'<1>:
 C_SIGNAL='@t6g_mb_lib.t6g(sch_1):m_h_cpu0_sa_dq(1)';
NODE_NAME     U25 F14
 '@T6G_MB_LIB.T6G(SCH_1):PAGE17_I159@PURE_QUANTA.GENOA_SP5(CHIPS)':
 'MHA_DATA1': CDS_PINID='MHA_DATA1';
NODE_NAME     J69 9
 '@T6G_MB_LIB.T6G(SCH_1):PAGE92_I22@PURE_QUANTA.SCONN288_DDR506112002KQ(CHIPS)':
 'DQ1_A': CDS_PINID='DQ1_A';
NET_NAME
'M_H_CPU0_SA_DQ<20>'
 '@T6G_MB_LIB.T6G(SCH_1):M_H_CPU0_SA_DQ'<20>:
 C_SIGNAL='@t6g_mb_lib.t6g(sch_1):m_h_cpu0_sa_dq(20)';
NODE_NAME     U25 AA12
 '@T6G_MB_LIB.T6G(SCH_1):PAGE17_I159@PURE_QUANTA.GENOA_SP5(CHIPS)':
 'MHA_DATA20': CDS_PINID='MHA_DATA20';
NODE_NAME     J69 36
 '@T6G_MB_LIB.T6G(SCH_1):PAGE92_I22@PURE_QUANTA.SCONN288_DDR506112002KQ(CHIPS)':
 'DQ20_A': CDS_PINID='DQ20_A';
NET_NAME
'M_H_CPU0_SA_DQ<21>'
 '@T6G_MB_LIB.T6G(SCH_1):M_H_CPU0_SA_DQ'<21>:
 C_SIGNAL='@t6g_mb_lib.t6g(sch_1):m_h_cpu0_sa_dq(21)';
NODE_NAME     U25 AB14
 '@T6G_MB_LIB.T6G(SCH_1):PAGE17_I159@PURE_QUANTA.GENOA_SP5(CHIPS)':
 'MHA_DATA21': CDS_PINID='MHA_DATA21';
NODE_NAME     J69 38
 '@T6G_MB_LIB.T6G(SCH_1):PAGE92_I22@PURE_QUANTA.SCONN288_DDR506112002KQ(CHIPS)':
 'DQ21_A': CDS_PINID='DQ21_A';
NET_NAME
'M_H_CPU0_SA_DQ<22>'
 '@T6G_MB_LIB.T6G(SCH_1):M_H_CPU0_SA_DQ'<22>:
 C_SIGNAL='@t6g_mb_lib.t6g(sch_1):m_h_cpu0_sa_dq(22)';
NODE_NAME     U25 AB13
 '@T6G_MB_LIB.T6G(SCH_1):PAGE17_I159@PURE_QUANTA.GENOA_SP5(CHIPS)':
 'MHA_DATA22': CDS_PINID='MHA_DATA22';
NODE_NAME     J69 181
 '@T6G_MB_LIB.T6G(SCH_1):PAGE92_I22@PURE_QUANTA.SCONN288_DDR506112002KQ(CHIPS)':
 'DQ22_A': CDS_PINID='DQ22_A';
NET_NAME
'M_H_CPU0_SA_DQ<23>'
 '@T6G_MB_LIB.T6G(SCH_1):M_H_CPU0_SA_DQ'<23>:
 C_SIGNAL='@t6g_mb_lib.t6g(sch_1):m_h_cpu0_sa_dq(23)';
NODE_NAME     U25 AC14
 '@T6G_MB_LIB.T6G(SCH_1):PAGE17_I159@PURE_QUANTA.GENOA_SP5(CHIPS)':
 'MHA_DATA23': CDS_PINID='MHA_DATA23';
NODE_NAME     J69 183
 '@T6G_MB_LIB.T6G(SCH_1):PAGE92_I22@PURE_QUANTA.SCONN288_DDR506112002KQ(CHIPS)':
 'DQ23_A': CDS_PINID='DQ23_A';
NET_NAME
'M_H_CPU0_SA_DQ<24>'
 '@T6G_MB_LIB.T6G(SCH_1):M_H_CPU0_SA_DQ'<24>:
 C_SIGNAL='@t6g_mb_lib.t6g(sch_1):m_h_cpu0_sa_dq(24)';
NODE_NAME     U25 AC12
 '@T6G_MB_LIB.T6G(SCH_1):PAGE17_I159@PURE_QUANTA.GENOA_SP5(CHIPS)':
 'MHA_DATA24': CDS_PINID='MHA_DATA24';
NODE_NAME     J69 40
 '@T6G_MB_LIB.T6G(SCH_1):PAGE92_I22@PURE_QUANTA.SCONN288_DDR506112002KQ(CHIPS)':
 'DQ24_A': CDS_PINID='DQ24_A';
NET_NAME
'M_H_CPU0_SA_DQ<25>'
 '@T6G_MB_LIB.T6G(SCH_1):M_H_CPU0_SA_DQ'<25>:
 C_SIGNAL='@t6g_mb_lib.t6g(sch_1):m_h_cpu0_sa_dq(25)';
NODE_NAME     U25 AD14
 '@T6G_MB_LIB.T6G(SCH_1):PAGE17_I159@PURE_QUANTA.GENOA_SP5(CHIPS)':
 'MHA_DATA25': CDS_PINID='MHA_DATA25';
NODE_NAME     J69 42
 '@T6G_MB_LIB.T6G(SCH_1):PAGE92_I22@PURE_QUANTA.SCONN288_DDR506112002KQ(CHIPS)':
 'DQ25_A': CDS_PINID='DQ25_A';
NET_NAME
'M_H_CPU0_SA_DQ<26>'
 '@T6G_MB_LIB.T6G(SCH_1):M_H_CPU0_SA_DQ'<26>:
 C_SIGNAL='@t6g_mb_lib.t6g(sch_1):m_h_cpu0_sa_dq(26)';
NODE_NAME     U25 AD13
 '@T6G_MB_LIB.T6G(SCH_1):PAGE17_I159@PURE_QUANTA.GENOA_SP5(CHIPS)':
 'MHA_DATA26': CDS_PINID='MHA_DATA26';
NODE_NAME     J69 185
 '@T6G_MB_LIB.T6G(SCH_1):PAGE92_I22@PURE_QUANTA.SCONN288_DDR506112002KQ(CHIPS)':
 'DQ26_A': CDS_PINID='DQ26_A';
NET_NAME
'M_H_CPU0_SA_DQ<27>'
 '@T6G_MB_LIB.T6G(SCH_1):M_H_CPU0_SA_DQ'<27>:
 C_SIGNAL='@t6g_mb_lib.t6g(sch_1):m_h_cpu0_sa_dq(27)';
NODE_NAME     U25 AE14
 '@T6G_MB_LIB.T6G(SCH_1):PAGE17_I159@PURE_QUANTA.GENOA_SP5(CHIPS)':
 'MHA_DATA27': CDS_PINID='MHA_DATA27';
NODE_NAME     J69 187
 '@T6G_MB_LIB.T6G(SCH_1):PAGE92_I22@PURE_QUANTA.SCONN288_DDR506112002KQ(CHIPS)':
 'DQ27_A': CDS_PINID='DQ27_A';
NET_NAME
'M_H_CPU0_SA_DQ<28>'
 '@T6G_MB_LIB.T6G(SCH_1):M_H_CPU0_SA_DQ'<28>:
 C_SIGNAL='@t6g_mb_lib.t6g(sch_1):m_h_cpu0_sa_dq(28)';
NODE_NAME     U25 AG12
 '@T6G_MB_LIB.T6G(SCH_1):PAGE17_I159@PURE_QUANTA.GENOA_SP5(CHIPS)':
 'MHA_DATA28': CDS_PINID='MHA_DATA28';
NODE_NAME     J69 47
 '@T6G_MB_LIB.T6G(SCH_1):PAGE92_I22@PURE_QUANTA.SCONN288_DDR506112002KQ(CHIPS)':
 'DQ28_A': CDS_PINID='DQ28_A';
NET_NAME
'M_H_CPU0_SA_DQ<29>'
 '@T6G_MB_LIB.T6G(SCH_1):M_H_CPU0_SA_DQ'<29>:
 C_SIGNAL='@t6g_mb_lib.t6g(sch_1):m_h_cpu0_sa_dq(29)';
NODE_NAME     U25 AH14
 '@T6G_MB_LIB.T6G(SCH_1):PAGE17_I159@PURE_QUANTA.GENOA_SP5(CHIPS)':
 'MHA_DATA29': CDS_PINID='MHA_DATA29';
NODE_NAME     J69 49
 '@T6G_MB_LIB.T6G(SCH_1):PAGE92_I22@PURE_QUANTA.SCONN288_DDR506112002KQ(CHIPS)':
 'DQ29_A': CDS_PINID='DQ29_A';
NET_NAME
'M_H_CPU0_SA_DQ<2>'
 '@T6G_MB_LIB.T6G(SCH_1):M_H_CPU0_SA_DQ'<2>:
 C_SIGNAL='@t6g_mb_lib.t6g(sch_1):m_h_cpu0_sa_dq(2)';
NODE_NAME     U25 F13
 '@T6G_MB_LIB.T6G(SCH_1):PAGE17_I159@PURE_QUANTA.GENOA_SP5(CHIPS)':
 'MHA_DATA2': CDS_PINID='MHA_DATA2';
NODE_NAME     J69 152
 '@T6G_MB_LIB.T6G(SCH_1):PAGE92_I22@PURE_QUANTA.SCONN288_DDR506112002KQ(CHIPS)':
 'DQ2_A': CDS_PINID='DQ2_A';
NET_NAME
'M_H_CPU0_SA_DQ<30>'
 '@T6G_MB_LIB.T6G(SCH_1):M_H_CPU0_SA_DQ'<30>:
 C_SIGNAL='@t6g_mb_lib.t6g(sch_1):m_h_cpu0_sa_dq(30)';
NODE_NAME     U25 AH13
 '@T6G_MB_LIB.T6G(SCH_1):PAGE17_I159@PURE_QUANTA.GENOA_SP5(CHIPS)':
 'MHA_DATA30': CDS_PINID='MHA_DATA30';
NODE_NAME     J69 192
 '@T6G_MB_LIB.T6G(SCH_1):PAGE92_I22@PURE_QUANTA.SCONN288_DDR506112002KQ(CHIPS)':
 'DQ30_A': CDS_PINID='DQ30_A';
NET_NAME
'M_H_CPU0_SA_DQ<31>'
 '@T6G_MB_LIB.T6G(SCH_1):M_H_CPU0_SA_DQ'<31>:
 C_SIGNAL='@t6g_mb_lib.t6g(sch_1):m_h_cpu0_sa_dq(31)';
NODE_NAME     U25 AJ14
 '@T6G_MB_LIB.T6G(SCH_1):PAGE17_I159@PURE_QUANTA.GENOA_SP5(CHIPS)':
 'MHA_DATA31': CDS_PINID='MHA_DATA31';
NODE_NAME     J69 194
 '@T6G_MB_LIB.T6G(SCH_1):PAGE92_I22@PURE_QUANTA.SCONN288_DDR506112002KQ(CHIPS)':
 'DQ31_A': CDS_PINID='DQ31_A';
NET_NAME
'M_H_CPU0_SA_DQ<3>'
 '@T6G_MB_LIB.T6G(SCH_1):M_H_CPU0_SA_DQ'<3>:
 C_SIGNAL='@t6g_mb_lib.t6g(sch_1):m_h_cpu0_sa_dq(3)';
NODE_NAME     U25 G14
 '@T6G_MB_LIB.T6G(SCH_1):PAGE17_I159@PURE_QUANTA.GENOA_SP5(CHIPS)':
 'MHA_DATA3': CDS_PINID='MHA_DATA3';
NODE_NAME     J69 154
 '@T6G_MB_LIB.T6G(SCH_1):PAGE92_I22@PURE_QUANTA.SCONN288_DDR506112002KQ(CHIPS)':
 'DQ3_A': CDS_PINID='DQ3_A';
NET_NAME
'M_H_CPU0_SA_DQ<4>'
 '@T6G_MB_LIB.T6G(SCH_1):M_H_CPU0_SA_DQ'<4>:
 C_SIGNAL='@t6g_mb_lib.t6g(sch_1):m_h_cpu0_sa_dq(4)';
NODE_NAME     U25 J12
 '@T6G_MB_LIB.T6G(SCH_1):PAGE17_I159@PURE_QUANTA.GENOA_SP5(CHIPS)':
 'MHA_DATA4': CDS_PINID='MHA_DATA4';
NODE_NAME     J69 14
 '@T6G_MB_LIB.T6G(SCH_1):PAGE92_I22@PURE_QUANTA.SCONN288_DDR506112002KQ(CHIPS)':
 'DQ4_A': CDS_PINID='DQ4_A';
NET_NAME
'M_H_CPU0_SA_DQ<5>'
 '@T6G_MB_LIB.T6G(SCH_1):M_H_CPU0_SA_DQ'<5>:
 C_SIGNAL='@t6g_mb_lib.t6g(sch_1):m_h_cpu0_sa_dq(5)';
NODE_NAME     U25 K14
 '@T6G_MB_LIB.T6G(SCH_1):PAGE17_I159@PURE_QUANTA.GENOA_SP5(CHIPS)':
 'MHA_DATA5': CDS_PINID='MHA_DATA5';
NODE_NAME     J69 16
 '@T6G_MB_LIB.T6G(SCH_1):PAGE92_I22@PURE_QUANTA.SCONN288_DDR506112002KQ(CHIPS)':
 'DQ5_A': CDS_PINID='DQ5_A';
NET_NAME
'M_H_CPU0_SA_DQ<6>'
 '@T6G_MB_LIB.T6G(SCH_1):M_H_CPU0_SA_DQ'<6>:
 C_SIGNAL='@t6g_mb_lib.t6g(sch_1):m_h_cpu0_sa_dq(6)';
NODE_NAME     U25 K13
 '@T6G_MB_LIB.T6G(SCH_1):PAGE17_I159@PURE_QUANTA.GENOA_SP5(CHIPS)':
 'MHA_DATA6': CDS_PINID='MHA_DATA6';
NODE_NAME     J69 159
 '@T6G_MB_LIB.T6G(SCH_1):PAGE92_I22@PURE_QUANTA.SCONN288_DDR506112002KQ(CHIPS)':
 'DQ6_A': CDS_PINID='DQ6_A';
NET_NAME
'M_H_CPU0_SA_DQ<7>'
 '@T6G_MB_LIB.T6G(SCH_1):M_H_CPU0_SA_DQ'<7>:
 C_SIGNAL='@t6g_mb_lib.t6g(sch_1):m_h_cpu0_sa_dq(7)';
NODE_NAME     U25 L14
 '@T6G_MB_LIB.T6G(SCH_1):PAGE17_I159@PURE_QUANTA.GENOA_SP5(CHIPS)':
 'MHA_DATA7': CDS_PINID='MHA_DATA7';
NODE_NAME     J69 161
 '@T6G_MB_LIB.T6G(SCH_1):PAGE92_I22@PURE_QUANTA.SCONN288_DDR506112002KQ(CHIPS)':
 'DQ7_A': CDS_PINID='DQ7_A';
NET_NAME
'M_H_CPU0_SA_DQ<8>'
 '@T6G_MB_LIB.T6G(SCH_1):M_H_CPU0_SA_DQ'<8>:
 C_SIGNAL='@t6g_mb_lib.t6g(sch_1):m_h_cpu0_sa_dq(8)';
NODE_NAME     U25 L12
 '@T6G_MB_LIB.T6G(SCH_1):PAGE17_I159@PURE_QUANTA.GENOA_SP5(CHIPS)':
 'MHA_DATA8': CDS_PINID='MHA_DATA8';
NODE_NAME     J69 18
 '@T6G_MB_LIB.T6G(SCH_1):PAGE92_I22@PURE_QUANTA.SCONN288_DDR506112002KQ(CHIPS)':
 'DQ8_A': CDS_PINID='DQ8_A';
NET_NAME
'M_H_CPU0_SA_DQ<9>'
 '@T6G_MB_LIB.T6G(SCH_1):M_H_CPU0_SA_DQ'<9>:
 C_SIGNAL='@t6g_mb_lib.t6g(sch_1):m_h_cpu0_sa_dq(9)';
NODE_NAME     U25 M14
 '@T6G_MB_LIB.T6G(SCH_1):PAGE17_I159@PURE_QUANTA.GENOA_SP5(CHIPS)':
 'MHA_DATA9': CDS_PINID='MHA_DATA9';
NODE_NAME     J69 20
 '@T6G_MB_LIB.T6G(SCH_1):PAGE92_I22@PURE_QUANTA.SCONN288_DDR506112002KQ(CHIPS)':
 'DQ9_A': CDS_PINID='DQ9_A';
NET_NAME
'M_H_CPU0_SA_DQS_DN<0>'
 '@T6G_MB_LIB.T6G(SCH_1):M_H_CPU0_SA_DQS_DN'<0>:
 C_SIGNAL='@t6g_mb_lib.t6g(sch_1):m_h_cpu0_sa_dqs_dn(0)';
NODE_NAME     U25 H13
 '@T6G_MB_LIB.T6G(SCH_1):PAGE17_I159@PURE_QUANTA.GENOA_SP5(CHIPS)':
 'MHA_DQS_L0': CDS_PINID='MHA_DQS_L0';
NODE_NAME     J69 12
 '@T6G_MB_LIB.T6G(SCH_1):PAGE92_I237@PURE_QUANTA.SCONN288_DDR506112002KQ(CHIPS)':
 'DQS0_A_C': CDS_PINID='DQS0_A_C';
NET_NAME
'M_H_CPU0_SA_DQS_DN<1>'
 '@T6G_MB_LIB.T6G(SCH_1):M_H_CPU0_SA_DQS_DN'<1>:
 C_SIGNAL='@t6g_mb_lib.t6g(sch_1):m_h_cpu0_sa_dqs_dn(1)';
NODE_NAME     U25 P13
 '@T6G_MB_LIB.T6G(SCH_1):PAGE17_I159@PURE_QUANTA.GENOA_SP5(CHIPS)':
 'MHA_DQS_L1': CDS_PINID='MHA_DQS_L1';
NODE_NAME     J69 23
 '@T6G_MB_LIB.T6G(SCH_1):PAGE92_I237@PURE_QUANTA.SCONN288_DDR506112002KQ(CHIPS)':
 'DQS1_A_C': CDS_PINID='DQS1_A_C';
NET_NAME
'M_H_CPU0_SA_DQS_DN<2>'
 '@T6G_MB_LIB.T6G(SCH_1):M_H_CPU0_SA_DQS_DN'<2>:
 C_SIGNAL='@t6g_mb_lib.t6g(sch_1):m_h_cpu0_sa_dqs_dn(2)';
NODE_NAME     U25 Y13
 '@T6G_MB_LIB.T6G(SCH_1):PAGE17_I159@PURE_QUANTA.GENOA_SP5(CHIPS)':
 'MHA_DQS_L2': CDS_PINID='MHA_DQS_L2';
NODE_NAME     J69 34
 '@T6G_MB_LIB.T6G(SCH_1):PAGE92_I237@PURE_QUANTA.SCONN288_DDR506112002KQ(CHIPS)':
 'DQS2_A_C': CDS_PINID='DQS2_A_C';
NET_NAME
'M_H_CPU0_SA_DQS_DN<3>'
 '@T6G_MB_LIB.T6G(SCH_1):M_H_CPU0_SA_DQS_DN'<3>:
 C_SIGNAL='@t6g_mb_lib.t6g(sch_1):m_h_cpu0_sa_dqs_dn(3)';
NODE_NAME     U25 AF13
 '@T6G_MB_LIB.T6G(SCH_1):PAGE17_I159@PURE_QUANTA.GENOA_SP5(CHIPS)':
 'MHA_DQS_L3': CDS_PINID='MHA_DQS_L3';
NODE_NAME     J69 45
 '@T6G_MB_LIB.T6G(SCH_1):PAGE92_I237@PURE_QUANTA.SCONN288_DDR506112002KQ(CHIPS)':
 'DQS3_A_C': CDS_PINID='DQS3_A_C';
NET_NAME
'M_H_CPU0_SA_DQS_DN<4>'
 '@T6G_MB_LIB.T6G(SCH_1):M_H_CPU0_SA_DQS_DN'<4>:
 C_SIGNAL='@t6g_mb_lib.t6g(sch_1):m_h_cpu0_sa_dqs_dn(4)';
NODE_NAME     U25 AM13
 '@T6G_MB_LIB.T6G(SCH_1):PAGE17_I159@PURE_QUANTA.GENOA_SP5(CHIPS)':
 'MHA_DQS_L4': CDS_PINID='MHA_DQS_L4';
NODE_NAME     J69 56
 '@T6G_MB_LIB.T6G(SCH_1):PAGE92_I237@PURE_QUANTA.SCONN288_DDR506112002KQ(CHIPS)':
 'DQS4_A_C': CDS_PINID='DQS4_A_C';
NET_NAME
'M_H_CPU0_SA_DQS_DN<5>'
 '@T6G_MB_LIB.T6G(SCH_1):M_H_CPU0_SA_DQS_DN'<5>:
 C_SIGNAL='@t6g_mb_lib.t6g(sch_1):m_h_cpu0_sa_dqs_dn(5)';
NODE_NAME     U25 H14
 '@T6G_MB_LIB.T6G(SCH_1):PAGE17_I159@PURE_QUANTA.GENOA_SP5(CHIPS)':
 'MHA_DQS_L5': CDS_PINID='MHA_DQS_L5';
NODE_NAME     J69 156
 '@T6G_MB_LIB.T6G(SCH_1):PAGE92_I237@PURE_QUANTA.SCONN288_DDR506112002KQ(CHIPS)':
 'DQS5_A_C||TDQS5_A_C||DQS5_A_T||TDQS5_A_T': CDS_PINID='\dqs5_a_c||tdqs5_a_c||dqs5_a_t||tdqs5_a_t\';
NET_NAME
'M_H_CPU0_SA_DQS_DN<6>'
 '@T6G_MB_LIB.T6G(SCH_1):M_H_CPU0_SA_DQS_DN'<6>:
 C_SIGNAL='@t6g_mb_lib.t6g(sch_1):m_h_cpu0_sa_dqs_dn(6)';
NODE_NAME     U25 P14
 '@T6G_MB_LIB.T6G(SCH_1):PAGE17_I159@PURE_QUANTA.GENOA_SP5(CHIPS)':
 'MHA_DQS_L6': CDS_PINID='MHA_DQS_L6';
NODE_NAME     J69 167
 '@T6G_MB_LIB.T6G(SCH_1):PAGE92_I237@PURE_QUANTA.SCONN288_DDR506112002KQ(CHIPS)':
 'DQS6_A_C||TDQS6_A_C||DQS6_A_T||TDQS6_A_T': CDS_PINID='\dqs6_a_c||tdqs6_a_c||dqs6_a_t||tdqs6_a_t\';
NET_NAME
'M_H_CPU0_SA_DQS_DN<7>'
 '@T6G_MB_LIB.T6G(SCH_1):M_H_CPU0_SA_DQS_DN'<7>:
 C_SIGNAL='@t6g_mb_lib.t6g(sch_1):m_h_cpu0_sa_dqs_dn(7)';
NODE_NAME     U25 Y14
 '@T6G_MB_LIB.T6G(SCH_1):PAGE17_I159@PURE_QUANTA.GENOA_SP5(CHIPS)':
 'MHA_DQS_L7': CDS_PINID='MHA_DQS_L7';
NODE_NAME     J69 178
 '@T6G_MB_LIB.T6G(SCH_1):PAGE92_I237@PURE_QUANTA.SCONN288_DDR506112002KQ(CHIPS)':
 'DQS7_A_C||TDQS7_A_C': CDS_PINID='\dqs7_a_c||tdqs7_a_c\';
NET_NAME
'M_H_CPU0_SA_DQS_DN<8>'
 '@T6G_MB_LIB.T6G(SCH_1):M_H_CPU0_SA_DQS_DN'<8>:
 C_SIGNAL='@t6g_mb_lib.t6g(sch_1):m_h_cpu0_sa_dqs_dn(8)';
NODE_NAME     U25 AF14
 '@T6G_MB_LIB.T6G(SCH_1):PAGE17_I159@PURE_QUANTA.GENOA_SP5(CHIPS)':
 'MHA_DQS_L8': CDS_PINID='MHA_DQS_L8';
NODE_NAME     J69 189
 '@T6G_MB_LIB.T6G(SCH_1):PAGE92_I237@PURE_QUANTA.SCONN288_DDR506112002KQ(CHIPS)':
 'DQS8_A_C||TDQS8_A_C': CDS_PINID='\dqs8_a_c||tdqs8_a_c\';
NET_NAME
'M_H_CPU0_SA_DQS_DN<9>'
 '@T6G_MB_LIB.T6G(SCH_1):M_H_CPU0_SA_DQS_DN'<9>:
 C_SIGNAL='@t6g_mb_lib.t6g(sch_1):m_h_cpu0_sa_dqs_dn(9)';
NODE_NAME     U25 AM14
 '@T6G_MB_LIB.T6G(SCH_1):PAGE17_I159@PURE_QUANTA.GENOA_SP5(CHIPS)':
 'MHA_DQS_L9': CDS_PINID='MHA_DQS_L9';
NODE_NAME     J69 200
 '@T6G_MB_LIB.T6G(SCH_1):PAGE92_I237@PURE_QUANTA.SCONN288_DDR506112002KQ(CHIPS)':
 'DQS9_A_C||TDQS9_A_C': CDS_PINID='\dqs9_a_c||tdqs9_a_c\';
NET_NAME
'M_H_CPU0_SA_DQS_DP<0>'
 '@T6G_MB_LIB.T6G(SCH_1):M_H_CPU0_SA_DQS_DP'<0>:
 C_SIGNAL='@t6g_mb_lib.t6g(sch_1):m_h_cpu0_sa_dqs_dp(0)';
NODE_NAME     U25 G12
 '@T6G_MB_LIB.T6G(SCH_1):PAGE17_I159@PURE_QUANTA.GENOA_SP5(CHIPS)':
 'MHA_DQS_H0': CDS_PINID='MHA_DQS_H0';
NODE_NAME     J69 11
 '@T6G_MB_LIB.T6G(SCH_1):PAGE92_I237@PURE_QUANTA.SCONN288_DDR506112002KQ(CHIPS)':
 'DQS0_A_T': CDS_PINID='DQS0_A_T';
NET_NAME
'M_H_CPU0_SA_DQS_DP<1>'
 '@T6G_MB_LIB.T6G(SCH_1):M_H_CPU0_SA_DQS_DP'<1>:
 C_SIGNAL='@t6g_mb_lib.t6g(sch_1):m_h_cpu0_sa_dqs_dp(1)';
NODE_NAME     U25 N12
 '@T6G_MB_LIB.T6G(SCH_1):PAGE17_I159@PURE_QUANTA.GENOA_SP5(CHIPS)':
 'MHA_DQS_H1': CDS_PINID='MHA_DQS_H1';
NODE_NAME     J69 22
 '@T6G_MB_LIB.T6G(SCH_1):PAGE92_I237@PURE_QUANTA.SCONN288_DDR506112002KQ(CHIPS)':
 'DQS1_A_T': CDS_PINID='DQS1_A_T';
NET_NAME
'M_H_CPU0_SA_DQS_DP<2>'
 '@T6G_MB_LIB.T6G(SCH_1):M_H_CPU0_SA_DQS_DP'<2>:
 C_SIGNAL='@t6g_mb_lib.t6g(sch_1):m_h_cpu0_sa_dqs_dp(2)';
NODE_NAME     U25 W12
 '@T6G_MB_LIB.T6G(SCH_1):PAGE17_I159@PURE_QUANTA.GENOA_SP5(CHIPS)':
 'MHA_DQS_H2': CDS_PINID='MHA_DQS_H2';
NODE_NAME     J69 33
 '@T6G_MB_LIB.T6G(SCH_1):PAGE92_I237@PURE_QUANTA.SCONN288_DDR506112002KQ(CHIPS)':
 'DQS2_A_T': CDS_PINID='DQS2_A_T';
NET_NAME
'M_H_CPU0_SA_DQS_DP<3>'
 '@T6G_MB_LIB.T6G(SCH_1):M_H_CPU0_SA_DQS_DP'<3>:
 C_SIGNAL='@t6g_mb_lib.t6g(sch_1):m_h_cpu0_sa_dqs_dp(3)';
NODE_NAME     U25 AE12
 '@T6G_MB_LIB.T6G(SCH_1):PAGE17_I159@PURE_QUANTA.GENOA_SP5(CHIPS)':
 'MHA_DQS_H3': CDS_PINID='MHA_DQS_H3';
NODE_NAME     J69 44
 '@T6G_MB_LIB.T6G(SCH_1):PAGE92_I237@PURE_QUANTA.SCONN288_DDR506112002KQ(CHIPS)':
 'DQS3_A_T': CDS_PINID='DQS3_A_T';
NET_NAME
'M_H_CPU0_SA_DQS_DP<4>'
 '@T6G_MB_LIB.T6G(SCH_1):M_H_CPU0_SA_DQS_DP'<4>:
 C_SIGNAL='@t6g_mb_lib.t6g(sch_1):m_h_cpu0_sa_dqs_dp(4)';
NODE_NAME     U25 AL12
 '@T6G_MB_LIB.T6G(SCH_1):PAGE17_I159@PURE_QUANTA.GENOA_SP5(CHIPS)':
 'MHA_DQS_H4': CDS_PINID='MHA_DQS_H4';
NODE_NAME     J69 55
 '@T6G_MB_LIB.T6G(SCH_1):PAGE92_I237@PURE_QUANTA.SCONN288_DDR506112002KQ(CHIPS)':
 'DQS4_A_T': CDS_PINID='DQS4_A_T';
NET_NAME
'M_H_CPU0_SA_DQS_DP<5>'
 '@T6G_MB_LIB.T6G(SCH_1):M_H_CPU0_SA_DQS_DP'<5>:
 C_SIGNAL='@t6g_mb_lib.t6g(sch_1):m_h_cpu0_sa_dqs_dp(5)';
NODE_NAME     U25 J14
 '@T6G_MB_LIB.T6G(SCH_1):PAGE17_I159@PURE_QUANTA.GENOA_SP5(CHIPS)':
 'MHA_DQS_H5': CDS_PINID='MHA_DQS_H5';
NODE_NAME     J69 157
 '@T6G_MB_LIB.T6G(SCH_1):PAGE92_I237@PURE_QUANTA.SCONN288_DDR506112002KQ(CHIPS)':
 'DQS5_A_T||TDQS5_A_T': CDS_PINID='\dqs5_a_t||tdqs5_a_t\';
NET_NAME
'M_H_CPU0_SA_DQS_DP<6>'
 '@T6G_MB_LIB.T6G(SCH_1):M_H_CPU0_SA_DQS_DP'<6>:
 C_SIGNAL='@t6g_mb_lib.t6g(sch_1):m_h_cpu0_sa_dqs_dp(6)';
NODE_NAME     U25 R14
 '@T6G_MB_LIB.T6G(SCH_1):PAGE17_I159@PURE_QUANTA.GENOA_SP5(CHIPS)':
 'MHA_DQS_H6': CDS_PINID='MHA_DQS_H6';
NODE_NAME     J69 168
 '@T6G_MB_LIB.T6G(SCH_1):PAGE92_I237@PURE_QUANTA.SCONN288_DDR506112002KQ(CHIPS)':
 'DQS6_A_T||TDQS6_A_T': CDS_PINID='\dqs6_a_t||tdqs6_a_t\';
NET_NAME
'M_H_CPU0_SA_DQS_DP<7>'
 '@T6G_MB_LIB.T6G(SCH_1):M_H_CPU0_SA_DQS_DP'<7>:
 C_SIGNAL='@t6g_mb_lib.t6g(sch_1):m_h_cpu0_sa_dqs_dp(7)';
NODE_NAME     U25 AA14
 '@T6G_MB_LIB.T6G(SCH_1):PAGE17_I159@PURE_QUANTA.GENOA_SP5(CHIPS)':
 'MHA_DQS_H7': CDS_PINID='MHA_DQS_H7';
NODE_NAME     J69 179
 '@T6G_MB_LIB.T6G(SCH_1):PAGE92_I237@PURE_QUANTA.SCONN288_DDR506112002KQ(CHIPS)':
 'DQS7_A_T||TDQS7_A_T': CDS_PINID='\dqs7_a_t||tdqs7_a_t\';
NET_NAME
'M_H_CPU0_SA_DQS_DP<8>'
 '@T6G_MB_LIB.T6G(SCH_1):M_H_CPU0_SA_DQS_DP'<8>:
 C_SIGNAL='@t6g_mb_lib.t6g(sch_1):m_h_cpu0_sa_dqs_dp(8)';
NODE_NAME     U25 AG14
 '@T6G_MB_LIB.T6G(SCH_1):PAGE17_I159@PURE_QUANTA.GENOA_SP5(CHIPS)':
 'MHA_DQS_H8': CDS_PINID='MHA_DQS_H8';
NODE_NAME     J69 190
 '@T6G_MB_LIB.T6G(SCH_1):PAGE92_I237@PURE_QUANTA.SCONN288_DDR506112002KQ(CHIPS)':
 'DQS8_A_T||TDQS8_A_T': CDS_PINID='\dqs8_a_t||tdqs8_a_t\';
NET_NAME
'M_H_CPU0_SA_DQS_DP<9>'
 '@T6G_MB_LIB.T6G(SCH_1):M_H_CPU0_SA_DQS_DP'<9>:
 C_SIGNAL='@t6g_mb_lib.t6g(sch_1):m_h_cpu0_sa_dqs_dp(9)';
NODE_NAME     U25 AN14
 '@T6G_MB_LIB.T6G(SCH_1):PAGE17_I159@PURE_QUANTA.GENOA_SP5(CHIPS)':
 'MHA_DQS_H9': CDS_PINID='MHA_DQS_H9';
NODE_NAME     J69 201
 '@T6G_MB_LIB.T6G(SCH_1):PAGE92_I237@PURE_QUANTA.SCONN288_DDR506112002KQ(CHIPS)':
 'DQS9_A_T||TDQS9_A_T': CDS_PINID='\dqs9_a_t||tdqs9_a_t\';
NET_NAME
'M_H_CPU0_SA_PAR'
 '@T6G_MB_LIB.T6G(SCH_1):M_H_CPU0_SA_PAR':
 C_SIGNAL='@t6g_mb_lib.t6g(sch_1):m_h_cpu0_sa_par';
NODE_NAME     U25 BC14
 '@T6G_MB_LIB.T6G(SCH_1):PAGE17_I159@PURE_QUANTA.GENOA_SP5(CHIPS)':
 'MHA_PAR': CDS_PINID='MHA_PAR';
NODE_NAME     J69 74
 '@T6G_MB_LIB.T6G(SCH_1):PAGE92_I22@PURE_QUANTA.SCONN288_DDR506112002KQ(CHIPS)':
 'PAR_A': CDS_PINID='PAR_A';
NET_NAME
'M_H_CPU0_SA_RSP<0>'
 '@T6G_MB_LIB.T6G(SCH_1):M_H_CPU0_SA_RSP'<0>:
 C_SIGNAL='@t6g_mb_lib.t6g(sch_1):m_h_cpu0_sa_rsp(0)';
NODE_NAME     U25 BN14
 '@T6G_MB_LIB.T6G(SCH_1):PAGE17_I159@PURE_QUANTA.GENOA_SP5(CHIPS)':
 'MHA0_RSP_L': CDS_PINID='MHA0_RSP_L';
NODE_NAME     J69 86
 '@T6G_MB_LIB.T6G(SCH_1):PAGE92_I22@PURE_QUANTA.SCONN288_DDR506112002KQ(CHIPS)':
 'LBD||RSP_A_N': CDS_PINID='\lbd||rsp_a_n\';
NET_NAME
'M_H_CPU0_SB_CA<0>'
 '@T6G_MB_LIB.T6G(SCH_1):M_H_CPU0_SB_CA'<0>:
 C_SIGNAL='@t6g_mb_lib.t6g(sch_1):m_h_cpu0_sb_ca(0)';
NODE_NAME     U25 BG14
 '@T6G_MB_LIB.T6G(SCH_1):PAGE17_I159@PURE_QUANTA.GENOA_SP5(CHIPS)':
 'MHB_CA0': CDS_PINID='MHB_CA0';
NODE_NAME     J69 76
 '@T6G_MB_LIB.T6G(SCH_1):PAGE92_I22@PURE_QUANTA.SCONN288_DDR506112002KQ(CHIPS)':
 'CA0_B': CDS_PINID='CA0_B';
NET_NAME
'M_H_CPU0_SB_CA<1>'
 '@T6G_MB_LIB.T6G(SCH_1):M_H_CPU0_SB_CA'<1>:
 C_SIGNAL='@t6g_mb_lib.t6g(sch_1):m_h_cpu0_sb_ca(1)';
NODE_NAME     U25 BH14
 '@T6G_MB_LIB.T6G(SCH_1):PAGE17_I159@PURE_QUANTA.GENOA_SP5(CHIPS)':
 'MHB_CA1': CDS_PINID='MHB_CA1';
NODE_NAME     J69 221
 '@T6G_MB_LIB.T6G(SCH_1):PAGE92_I22@PURE_QUANTA.SCONN288_DDR506112002KQ(CHIPS)':
 'CA1_B': CDS_PINID='CA1_B';
NET_NAME
'M_H_CPU0_SB_CA<2>'
 '@T6G_MB_LIB.T6G(SCH_1):M_H_CPU0_SB_CA'<2>:
 C_SIGNAL='@t6g_mb_lib.t6g(sch_1):m_h_cpu0_sb_ca(2)';
NODE_NAME     U25 BH13
 '@T6G_MB_LIB.T6G(SCH_1):PAGE17_I159@PURE_QUANTA.GENOA_SP5(CHIPS)':
 'MHB_CA2': CDS_PINID='MHB_CA2';
NODE_NAME     J69 78
 '@T6G_MB_LIB.T6G(SCH_1):PAGE92_I22@PURE_QUANTA.SCONN288_DDR506112002KQ(CHIPS)':
 'CA2_B': CDS_PINID='CA2_B';
NET_NAME
'M_H_CPU0_SB_CA<3>'
 '@T6G_MB_LIB.T6G(SCH_1):M_H_CPU0_SB_CA'<3>:
 C_SIGNAL='@t6g_mb_lib.t6g(sch_1):m_h_cpu0_sb_ca(3)';
NODE_NAME     U25 BJ12
 '@T6G_MB_LIB.T6G(SCH_1):PAGE17_I159@PURE_QUANTA.GENOA_SP5(CHIPS)':
 'MHB_CA3': CDS_PINID='MHB_CA3';
NODE_NAME     J69 223
 '@T6G_MB_LIB.T6G(SCH_1):PAGE92_I22@PURE_QUANTA.SCONN288_DDR506112002KQ(CHIPS)':
 'CA3_B': CDS_PINID='CA3_B';
NET_NAME
'M_H_CPU0_SB_CA<4>'
 '@T6G_MB_LIB.T6G(SCH_1):M_H_CPU0_SB_CA'<4>:
 C_SIGNAL='@t6g_mb_lib.t6g(sch_1):m_h_cpu0_sb_ca(4)';
NODE_NAME     U25 BJ14
 '@T6G_MB_LIB.T6G(SCH_1):PAGE17_I159@PURE_QUANTA.GENOA_SP5(CHIPS)':
 'MHB_CA4': CDS_PINID='MHB_CA4';
NODE_NAME     J69 80
 '@T6G_MB_LIB.T6G(SCH_1):PAGE92_I22@PURE_QUANTA.SCONN288_DDR506112002KQ(CHIPS)':
 'CA4_B': CDS_PINID='CA4_B';
NET_NAME
'M_H_CPU0_SB_CA<5>'
 '@T6G_MB_LIB.T6G(SCH_1):M_H_CPU0_SB_CA'<5>:
 C_SIGNAL='@t6g_mb_lib.t6g(sch_1):m_h_cpu0_sb_ca(5)';
NODE_NAME     U25 BK14
 '@T6G_MB_LIB.T6G(SCH_1):PAGE17_I159@PURE_QUANTA.GENOA_SP5(CHIPS)':
 'MHB_CA5': CDS_PINID='MHB_CA5';
NODE_NAME     J69 225
 '@T6G_MB_LIB.T6G(SCH_1):PAGE92_I22@PURE_QUANTA.SCONN288_DDR506112002KQ(CHIPS)':
 'CA5_B': CDS_PINID='CA5_B';
NET_NAME
'M_H_CPU0_SB_CA<6>'
 '@T6G_MB_LIB.T6G(SCH_1):M_H_CPU0_SB_CA'<6>:
 C_SIGNAL='@t6g_mb_lib.t6g(sch_1):m_h_cpu0_sb_ca(6)';
NODE_NAME     U25 BK13
 '@T6G_MB_LIB.T6G(SCH_1):PAGE17_I159@PURE_QUANTA.GENOA_SP5(CHIPS)':
 'MHB_CA6': CDS_PINID='MHB_CA6';
NODE_NAME     J69 82
 '@T6G_MB_LIB.T6G(SCH_1):PAGE92_I22@PURE_QUANTA.SCONN288_DDR506112002KQ(CHIPS)':
 'CA6_B': CDS_PINID='CA6_B';
NET_NAME
'M_H_CPU0_SB_CB<0>'
 '@T6G_MB_LIB.T6G(SCH_1):M_H_CPU0_SB_CB'<0>:
 C_SIGNAL='@t6g_mb_lib.t6g(sch_1):m_h_cpu0_sb_cb(0)';
NODE_NAME     U25 BY13
 '@T6G_MB_LIB.T6G(SCH_1):PAGE17_I159@PURE_QUANTA.GENOA_SP5(CHIPS)':
 'MHB_CHECK0': CDS_PINID='MHB_CHECK0';
NODE_NAME     J69 96
 '@T6G_MB_LIB.T6G(SCH_1):PAGE92_I22@PURE_QUANTA.SCONN288_DDR506112002KQ(CHIPS)':
 'CB0_B': CDS_PINID='CB0_B';
NET_NAME
'M_H_CPU0_SB_CB<1>'
 '@T6G_MB_LIB.T6G(SCH_1):M_H_CPU0_SB_CB'<1>:
 C_SIGNAL='@t6g_mb_lib.t6g(sch_1):m_h_cpu0_sb_cb(1)';
NODE_NAME     U25 CA14
 '@T6G_MB_LIB.T6G(SCH_1):PAGE17_I159@PURE_QUANTA.GENOA_SP5(CHIPS)':
 'MHB_CHECK1': CDS_PINID='MHB_CHECK1';
NODE_NAME     J69 98
 '@T6G_MB_LIB.T6G(SCH_1):PAGE92_I22@PURE_QUANTA.SCONN288_DDR506112002KQ(CHIPS)':
 'CB1_B': CDS_PINID='CB1_B';
NET_NAME
'M_H_CPU0_SB_CB<2>'
 '@T6G_MB_LIB.T6G(SCH_1):M_H_CPU0_SB_CB'<2>:
 C_SIGNAL='@t6g_mb_lib.t6g(sch_1):m_h_cpu0_sb_cb(2)';
NODE_NAME     U25 CA12
 '@T6G_MB_LIB.T6G(SCH_1):PAGE17_I159@PURE_QUANTA.GENOA_SP5(CHIPS)':
 'MHB_CHECK2': CDS_PINID='MHB_CHECK2';
NODE_NAME     J69 241
 '@T6G_MB_LIB.T6G(SCH_1):PAGE92_I22@PURE_QUANTA.SCONN288_DDR506112002KQ(CHIPS)':
 'CB2_B': CDS_PINID='CB2_B';
NET_NAME
'M_H_CPU0_SB_CB<3>'
 '@T6G_MB_LIB.T6G(SCH_1):M_H_CPU0_SB_CB'<3>:
 C_SIGNAL='@t6g_mb_lib.t6g(sch_1):m_h_cpu0_sb_cb(3)';
NODE_NAME     U25 CB14
 '@T6G_MB_LIB.T6G(SCH_1):PAGE17_I159@PURE_QUANTA.GENOA_SP5(CHIPS)':
 'MHB_CHECK3': CDS_PINID='MHB_CHECK3';
NODE_NAME     J69 243
 '@T6G_MB_LIB.T6G(SCH_1):PAGE92_I22@PURE_QUANTA.SCONN288_DDR506112002KQ(CHIPS)':
 'CB3_B': CDS_PINID='CB3_B';
NET_NAME
'M_H_CPU0_SB_CB<4>'
 '@T6G_MB_LIB.T6G(SCH_1):M_H_CPU0_SB_CB'<4>:
 C_SIGNAL='@t6g_mb_lib.t6g(sch_1):m_h_cpu0_sb_cb(4)';
NODE_NAME     U25 BT13
 '@T6G_MB_LIB.T6G(SCH_1):PAGE17_I159@PURE_QUANTA.GENOA_SP5(CHIPS)':
 'MHB_CHECK4': CDS_PINID='MHB_CHECK4';
NODE_NAME     J69 89
 '@T6G_MB_LIB.T6G(SCH_1):PAGE92_I22@PURE_QUANTA.SCONN288_DDR506112002KQ(CHIPS)':
 'CB4_B': CDS_PINID='CB4_B';
NET_NAME
'M_H_CPU0_SB_CB<5>'
 '@T6G_MB_LIB.T6G(SCH_1):M_H_CPU0_SB_CB'<5>:
 C_SIGNAL='@t6g_mb_lib.t6g(sch_1):m_h_cpu0_sb_cb(5)';
NODE_NAME     U25 BU14
 '@T6G_MB_LIB.T6G(SCH_1):PAGE17_I159@PURE_QUANTA.GENOA_SP5(CHIPS)':
 'MHB_CHECK5': CDS_PINID='MHB_CHECK5';
NODE_NAME     J69 91
 '@T6G_MB_LIB.T6G(SCH_1):PAGE92_I22@PURE_QUANTA.SCONN288_DDR506112002KQ(CHIPS)':
 'CB5_B': CDS_PINID='CB5_B';
NET_NAME
'M_H_CPU0_SB_CB<6>'
 '@T6G_MB_LIB.T6G(SCH_1):M_H_CPU0_SB_CB'<6>:
 C_SIGNAL='@t6g_mb_lib.t6g(sch_1):m_h_cpu0_sb_cb(6)';
NODE_NAME     U25 BU12
 '@T6G_MB_LIB.T6G(SCH_1):PAGE17_I159@PURE_QUANTA.GENOA_SP5(CHIPS)':
 'MHB_CHECK6': CDS_PINID='MHB_CHECK6';
NODE_NAME     J69 234
 '@T6G_MB_LIB.T6G(SCH_1):PAGE92_I22@PURE_QUANTA.SCONN288_DDR506112002KQ(CHIPS)':
 'CB6_B': CDS_PINID='CB6_B';
NET_NAME
'M_H_CPU0_SB_CB<7>'
 '@T6G_MB_LIB.T6G(SCH_1):M_H_CPU0_SB_CB'<7>:
 C_SIGNAL='@t6g_mb_lib.t6g(sch_1):m_h_cpu0_sb_cb(7)';
NODE_NAME     U25 BV14
 '@T6G_MB_LIB.T6G(SCH_1):PAGE17_I159@PURE_QUANTA.GENOA_SP5(CHIPS)':
 'MHB_CHECK7': CDS_PINID='MHB_CHECK7';
NODE_NAME     J69 236
 '@T6G_MB_LIB.T6G(SCH_1):PAGE92_I22@PURE_QUANTA.SCONN288_DDR506112002KQ(CHIPS)':
 'CB7_B': CDS_PINID='CB7_B';
NET_NAME
'M_H_CPU0_SB_CS_N<0>'
 '@T6G_MB_LIB.T6G(SCH_1):M_H_CPU0_SB_CS_N'<0>:
 C_SIGNAL='@t6g_mb_lib.t6g(sch_1):m_h_cpu0_sb_cs_n(0)';
NODE_NAME     U25 BM14
 '@T6G_MB_LIB.T6G(SCH_1):PAGE17_I159@PURE_QUANTA.GENOA_SP5(CHIPS)':
 'MHB0_CS_L0': CDS_PINID='MHB0_CS_L0';
NODE_NAME     J69 84
 '@T6G_MB_LIB.T6G(SCH_1):PAGE92_I22@PURE_QUANTA.SCONN288_DDR506112002KQ(CHIPS)':
 'CS0_B_N': CDS_PINID='CS0_B_N';
NET_NAME
'M_H_CPU0_SB_CS_N<1>'
 '@T6G_MB_LIB.T6G(SCH_1):M_H_CPU0_SB_CS_N'<1>:
 C_SIGNAL='@t6g_mb_lib.t6g(sch_1):m_h_cpu0_sb_cs_n(1)';
NODE_NAME     U25 BN12
 '@T6G_MB_LIB.T6G(SCH_1):PAGE17_I159@PURE_QUANTA.GENOA_SP5(CHIPS)':
 'MHB0_CS_L1': CDS_PINID='MHB0_CS_L1';
NODE_NAME     J69 229
 '@T6G_MB_LIB.T6G(SCH_1):PAGE92_I22@PURE_QUANTA.SCONN288_DDR506112002KQ(CHIPS)':
 'CS1_B_N': CDS_PINID='CS1_B_N';
NET_NAME
'M_H_CPU0_SB_DQ<0>'
 '@T6G_MB_LIB.T6G(SCH_1):M_H_CPU0_SB_DQ'<0>:
 C_SIGNAL='@t6g_mb_lib.t6g(sch_1):m_h_cpu0_sb_dq(0)';
NODE_NAME     U25 CB13
 '@T6G_MB_LIB.T6G(SCH_1):PAGE17_I159@PURE_QUANTA.GENOA_SP5(CHIPS)':
 'MHB_DATA0': CDS_PINID='MHB_DATA0';
NODE_NAME     J69 100
 '@T6G_MB_LIB.T6G(SCH_1):PAGE92_I22@PURE_QUANTA.SCONN288_DDR506112002KQ(CHIPS)':
 'DQ0_B': CDS_PINID='DQ0_B';
NET_NAME
'M_H_CPU0_SB_DQ<10>'
 '@T6G_MB_LIB.T6G(SCH_1):M_H_CPU0_SB_DQ'<10>:
 C_SIGNAL='@t6g_mb_lib.t6g(sch_1):m_h_cpu0_sb_dq(10)';
NODE_NAME     U25 CJ12
 '@T6G_MB_LIB.T6G(SCH_1):PAGE17_I159@PURE_QUANTA.GENOA_SP5(CHIPS)':
 'MHB_DATA10': CDS_PINID='MHB_DATA10';
NODE_NAME     J69 256
 '@T6G_MB_LIB.T6G(SCH_1):PAGE92_I22@PURE_QUANTA.SCONN288_DDR506112002KQ(CHIPS)':
 'DQ10_B': CDS_PINID='DQ10_B';
NET_NAME
'M_H_CPU0_SB_DQ<11>'
 '@T6G_MB_LIB.T6G(SCH_1):M_H_CPU0_SB_DQ'<11>:
 C_SIGNAL='@t6g_mb_lib.t6g(sch_1):m_h_cpu0_sb_dq(11)';
NODE_NAME     U25 CK14
 '@T6G_MB_LIB.T6G(SCH_1):PAGE17_I159@PURE_QUANTA.GENOA_SP5(CHIPS)':
 'MHB_DATA11': CDS_PINID='MHB_DATA11';
NODE_NAME     J69 258
 '@T6G_MB_LIB.T6G(SCH_1):PAGE92_I22@PURE_QUANTA.SCONN288_DDR506112002KQ(CHIPS)':
 'DQ11_B': CDS_PINID='DQ11_B';
NET_NAME
'M_H_CPU0_SB_DQ<12>'
 '@T6G_MB_LIB.T6G(SCH_1):M_H_CPU0_SB_DQ'<12>:
 C_SIGNAL='@t6g_mb_lib.t6g(sch_1):m_h_cpu0_sb_dq(12)';
NODE_NAME     U25 CM13
 '@T6G_MB_LIB.T6G(SCH_1):PAGE17_I159@PURE_QUANTA.GENOA_SP5(CHIPS)':
 'MHB_DATA12': CDS_PINID='MHB_DATA12';
NODE_NAME     J69 118
 '@T6G_MB_LIB.T6G(SCH_1):PAGE92_I22@PURE_QUANTA.SCONN288_DDR506112002KQ(CHIPS)':
 'DQ12_B': CDS_PINID='DQ12_B';
NET_NAME
'M_H_CPU0_SB_DQ<13>'
 '@T6G_MB_LIB.T6G(SCH_1):M_H_CPU0_SB_DQ'<13>:
 C_SIGNAL='@t6g_mb_lib.t6g(sch_1):m_h_cpu0_sb_dq(13)';
NODE_NAME     U25 CN14
 '@T6G_MB_LIB.T6G(SCH_1):PAGE17_I159@PURE_QUANTA.GENOA_SP5(CHIPS)':
 'MHB_DATA13': CDS_PINID='MHB_DATA13';
NODE_NAME     J69 120
 '@T6G_MB_LIB.T6G(SCH_1):PAGE92_I22@PURE_QUANTA.SCONN288_DDR506112002KQ(CHIPS)':
 'DQ13_B': CDS_PINID='DQ13_B';
NET_NAME
'M_H_CPU0_SB_DQ<14>'
 '@T6G_MB_LIB.T6G(SCH_1):M_H_CPU0_SB_DQ'<14>:
 C_SIGNAL='@t6g_mb_lib.t6g(sch_1):m_h_cpu0_sb_dq(14)';
NODE_NAME     U25 CN12
 '@T6G_MB_LIB.T6G(SCH_1):PAGE17_I159@PURE_QUANTA.GENOA_SP5(CHIPS)':
 'MHB_DATA14': CDS_PINID='MHB_DATA14';
NODE_NAME     J69 263
 '@T6G_MB_LIB.T6G(SCH_1):PAGE92_I22@PURE_QUANTA.SCONN288_DDR506112002KQ(CHIPS)':
 'DQ14_B': CDS_PINID='DQ14_B';
NET_NAME
'M_H_CPU0_SB_DQ<15>'
 '@T6G_MB_LIB.T6G(SCH_1):M_H_CPU0_SB_DQ'<15>:
 C_SIGNAL='@t6g_mb_lib.t6g(sch_1):m_h_cpu0_sb_dq(15)';
NODE_NAME     U25 CP14
 '@T6G_MB_LIB.T6G(SCH_1):PAGE17_I159@PURE_QUANTA.GENOA_SP5(CHIPS)':
 'MHB_DATA15': CDS_PINID='MHB_DATA15';
NODE_NAME     J69 265
 '@T6G_MB_LIB.T6G(SCH_1):PAGE92_I22@PURE_QUANTA.SCONN288_DDR506112002KQ(CHIPS)':
 'DQ15_B': CDS_PINID='DQ15_B';
NET_NAME
'M_H_CPU0_SB_DQ<16>'
 '@T6G_MB_LIB.T6G(SCH_1):M_H_CPU0_SB_DQ'<16>:
 C_SIGNAL='@t6g_mb_lib.t6g(sch_1):m_h_cpu0_sb_dq(16)';
NODE_NAME     U25 CP13
 '@T6G_MB_LIB.T6G(SCH_1):PAGE17_I159@PURE_QUANTA.GENOA_SP5(CHIPS)':
 'MHB_DATA16': CDS_PINID='MHB_DATA16';
NODE_NAME     J69 122
 '@T6G_MB_LIB.T6G(SCH_1):PAGE92_I22@PURE_QUANTA.SCONN288_DDR506112002KQ(CHIPS)':
 'DQ16_B': CDS_PINID='DQ16_B';
NET_NAME
'M_H_CPU0_SB_DQ<17>'
 '@T6G_MB_LIB.T6G(SCH_1):M_H_CPU0_SB_DQ'<17>:
 C_SIGNAL='@t6g_mb_lib.t6g(sch_1):m_h_cpu0_sb_dq(17)';
NODE_NAME     U25 CR14
 '@T6G_MB_LIB.T6G(SCH_1):PAGE17_I159@PURE_QUANTA.GENOA_SP5(CHIPS)':
 'MHB_DATA17': CDS_PINID='MHB_DATA17';
NODE_NAME     J69 124
 '@T6G_MB_LIB.T6G(SCH_1):PAGE92_I22@PURE_QUANTA.SCONN288_DDR506112002KQ(CHIPS)':
 'DQ17_B': CDS_PINID='DQ17_B';
NET_NAME
'M_H_CPU0_SB_DQ<18>'
 '@T6G_MB_LIB.T6G(SCH_1):M_H_CPU0_SB_DQ'<18>:
 C_SIGNAL='@t6g_mb_lib.t6g(sch_1):m_h_cpu0_sb_dq(18)';
NODE_NAME     U25 CR12
 '@T6G_MB_LIB.T6G(SCH_1):PAGE17_I159@PURE_QUANTA.GENOA_SP5(CHIPS)':
 'MHB_DATA18': CDS_PINID='MHB_DATA18';
NODE_NAME     J69 267
 '@T6G_MB_LIB.T6G(SCH_1):PAGE92_I22@PURE_QUANTA.SCONN288_DDR506112002KQ(CHIPS)':
 'DQ18_B': CDS_PINID='DQ18_B';
NET_NAME
'M_H_CPU0_SB_DQ<19>'
 '@T6G_MB_LIB.T6G(SCH_1):M_H_CPU0_SB_DQ'<19>:
 C_SIGNAL='@t6g_mb_lib.t6g(sch_1):m_h_cpu0_sb_dq(19)';
NODE_NAME     U25 CT14
 '@T6G_MB_LIB.T6G(SCH_1):PAGE17_I159@PURE_QUANTA.GENOA_SP5(CHIPS)':
 'MHB_DATA19': CDS_PINID='MHB_DATA19';
NODE_NAME     J69 269
 '@T6G_MB_LIB.T6G(SCH_1):PAGE92_I22@PURE_QUANTA.SCONN288_DDR506112002KQ(CHIPS)':
 'DQ19_B': CDS_PINID='DQ19_B';
NET_NAME
'M_H_CPU0_SB_DQ<1>'
 '@T6G_MB_LIB.T6G(SCH_1):M_H_CPU0_SB_DQ'<1>:
 C_SIGNAL='@t6g_mb_lib.t6g(sch_1):m_h_cpu0_sb_dq(1)';
NODE_NAME     U25 CC14
 '@T6G_MB_LIB.T6G(SCH_1):PAGE17_I159@PURE_QUANTA.GENOA_SP5(CHIPS)':
 'MHB_DATA1': CDS_PINID='MHB_DATA1';
NODE_NAME     J69 102
 '@T6G_MB_LIB.T6G(SCH_1):PAGE92_I22@PURE_QUANTA.SCONN288_DDR506112002KQ(CHIPS)':
 'DQ1_B': CDS_PINID='DQ1_B';
NET_NAME
'M_H_CPU0_SB_DQ<20>'
 '@T6G_MB_LIB.T6G(SCH_1):M_H_CPU0_SB_DQ'<20>:
 C_SIGNAL='@t6g_mb_lib.t6g(sch_1):m_h_cpu0_sb_dq(20)';
NODE_NAME     U25 CV13
 '@T6G_MB_LIB.T6G(SCH_1):PAGE17_I159@PURE_QUANTA.GENOA_SP5(CHIPS)':
 'MHB_DATA20': CDS_PINID='MHB_DATA20';
NODE_NAME     J69 129
 '@T6G_MB_LIB.T6G(SCH_1):PAGE92_I22@PURE_QUANTA.SCONN288_DDR506112002KQ(CHIPS)':
 'DQ20_B': CDS_PINID='DQ20_B';
NET_NAME
'M_H_CPU0_SB_DQ<21>'
 '@T6G_MB_LIB.T6G(SCH_1):M_H_CPU0_SB_DQ'<21>:
 C_SIGNAL='@t6g_mb_lib.t6g(sch_1):m_h_cpu0_sb_dq(21)';
NODE_NAME     U25 CW14
 '@T6G_MB_LIB.T6G(SCH_1):PAGE17_I159@PURE_QUANTA.GENOA_SP5(CHIPS)':
 'MHB_DATA21': CDS_PINID='MHB_DATA21';
NODE_NAME     J69 131
 '@T6G_MB_LIB.T6G(SCH_1):PAGE92_I22@PURE_QUANTA.SCONN288_DDR506112002KQ(CHIPS)':
 'DQ21_B': CDS_PINID='DQ21_B';
NET_NAME
'M_H_CPU0_SB_DQ<22>'
 '@T6G_MB_LIB.T6G(SCH_1):M_H_CPU0_SB_DQ'<22>:
 C_SIGNAL='@t6g_mb_lib.t6g(sch_1):m_h_cpu0_sb_dq(22)';
NODE_NAME     U25 CW12
 '@T6G_MB_LIB.T6G(SCH_1):PAGE17_I159@PURE_QUANTA.GENOA_SP5(CHIPS)':
 'MHB_DATA22': CDS_PINID='MHB_DATA22';
NODE_NAME     J69 274
 '@T6G_MB_LIB.T6G(SCH_1):PAGE92_I22@PURE_QUANTA.SCONN288_DDR506112002KQ(CHIPS)':
 'DQ22_B': CDS_PINID='DQ22_B';
NET_NAME
'M_H_CPU0_SB_DQ<23>'
 '@T6G_MB_LIB.T6G(SCH_1):M_H_CPU0_SB_DQ'<23>:
 C_SIGNAL='@t6g_mb_lib.t6g(sch_1):m_h_cpu0_sb_dq(23)';
NODE_NAME     U25 CY14
 '@T6G_MB_LIB.T6G(SCH_1):PAGE17_I159@PURE_QUANTA.GENOA_SP5(CHIPS)':
 'MHB_DATA23': CDS_PINID='MHB_DATA23';
NODE_NAME     J69 276
 '@T6G_MB_LIB.T6G(SCH_1):PAGE92_I22@PURE_QUANTA.SCONN288_DDR506112002KQ(CHIPS)':
 'DQ23_B': CDS_PINID='DQ23_B';
NET_NAME
'M_H_CPU0_SB_DQ<24>'
 '@T6G_MB_LIB.T6G(SCH_1):M_H_CPU0_SB_DQ'<24>:
 C_SIGNAL='@t6g_mb_lib.t6g(sch_1):m_h_cpu0_sb_dq(24)';
NODE_NAME     U25 CY13
 '@T6G_MB_LIB.T6G(SCH_1):PAGE17_I159@PURE_QUANTA.GENOA_SP5(CHIPS)':
 'MHB_DATA24': CDS_PINID='MHB_DATA24';
NODE_NAME     J69 133
 '@T6G_MB_LIB.T6G(SCH_1):PAGE92_I22@PURE_QUANTA.SCONN288_DDR506112002KQ(CHIPS)':
 'DQ24_B': CDS_PINID='DQ24_B';
NET_NAME
'M_H_CPU0_SB_DQ<25>'
 '@T6G_MB_LIB.T6G(SCH_1):M_H_CPU0_SB_DQ'<25>:
 C_SIGNAL='@t6g_mb_lib.t6g(sch_1):m_h_cpu0_sb_dq(25)';
NODE_NAME     U25 DA14
 '@T6G_MB_LIB.T6G(SCH_1):PAGE17_I159@PURE_QUANTA.GENOA_SP5(CHIPS)':
 'MHB_DATA25': CDS_PINID='MHB_DATA25';
NODE_NAME     J69 135
 '@T6G_MB_LIB.T6G(SCH_1):PAGE92_I22@PURE_QUANTA.SCONN288_DDR506112002KQ(CHIPS)':
 'DQ25_B': CDS_PINID='DQ25_B';
NET_NAME
'M_H_CPU0_SB_DQ<26>'
 '@T6G_MB_LIB.T6G(SCH_1):M_H_CPU0_SB_DQ'<26>:
 C_SIGNAL='@t6g_mb_lib.t6g(sch_1):m_h_cpu0_sb_dq(26)';
NODE_NAME     U25 DA12
 '@T6G_MB_LIB.T6G(SCH_1):PAGE17_I159@PURE_QUANTA.GENOA_SP5(CHIPS)':
 'MHB_DATA26': CDS_PINID='MHB_DATA26';
NODE_NAME     J69 278
 '@T6G_MB_LIB.T6G(SCH_1):PAGE92_I22@PURE_QUANTA.SCONN288_DDR506112002KQ(CHIPS)':
 'DQ26_B': CDS_PINID='DQ26_B';
NET_NAME
'M_H_CPU0_SB_DQ<27>'
 '@T6G_MB_LIB.T6G(SCH_1):M_H_CPU0_SB_DQ'<27>:
 C_SIGNAL='@t6g_mb_lib.t6g(sch_1):m_h_cpu0_sb_dq(27)';
NODE_NAME     U25 DB14
 '@T6G_MB_LIB.T6G(SCH_1):PAGE17_I159@PURE_QUANTA.GENOA_SP5(CHIPS)':
 'MHB_DATA27': CDS_PINID='MHB_DATA27';
NODE_NAME     J69 280
 '@T6G_MB_LIB.T6G(SCH_1):PAGE92_I22@PURE_QUANTA.SCONN288_DDR506112002KQ(CHIPS)':
 'DQ27_B': CDS_PINID='DQ27_B';
NET_NAME
'M_H_CPU0_SB_DQ<28>'
 '@T6G_MB_LIB.T6G(SCH_1):M_H_CPU0_SB_DQ'<28>:
 C_SIGNAL='@t6g_mb_lib.t6g(sch_1):m_h_cpu0_sb_dq(28)';
NODE_NAME     U25 DD13
 '@T6G_MB_LIB.T6G(SCH_1):PAGE17_I159@PURE_QUANTA.GENOA_SP5(CHIPS)':
 'MHB_DATA28': CDS_PINID='MHB_DATA28';
NODE_NAME     J69 140
 '@T6G_MB_LIB.T6G(SCH_1):PAGE92_I22@PURE_QUANTA.SCONN288_DDR506112002KQ(CHIPS)':
 'DQ28_B': CDS_PINID='DQ28_B';
NET_NAME
'M_H_CPU0_SB_DQ<29>'
 '@T6G_MB_LIB.T6G(SCH_1):M_H_CPU0_SB_DQ'<29>:
 C_SIGNAL='@t6g_mb_lib.t6g(sch_1):m_h_cpu0_sb_dq(29)';
NODE_NAME     U25 DE14
 '@T6G_MB_LIB.T6G(SCH_1):PAGE17_I159@PURE_QUANTA.GENOA_SP5(CHIPS)':
 'MHB_DATA29': CDS_PINID='MHB_DATA29';
NODE_NAME     J69 142
 '@T6G_MB_LIB.T6G(SCH_1):PAGE92_I22@PURE_QUANTA.SCONN288_DDR506112002KQ(CHIPS)':
 'DQ29_B': CDS_PINID='DQ29_B';
NET_NAME
'M_H_CPU0_SB_DQ<2>'
 '@T6G_MB_LIB.T6G(SCH_1):M_H_CPU0_SB_DQ'<2>:
 C_SIGNAL='@t6g_mb_lib.t6g(sch_1):m_h_cpu0_sb_dq(2)';
NODE_NAME     U25 CC12
 '@T6G_MB_LIB.T6G(SCH_1):PAGE17_I159@PURE_QUANTA.GENOA_SP5(CHIPS)':
 'MHB_DATA2': CDS_PINID='MHB_DATA2';
NODE_NAME     J69 245
 '@T6G_MB_LIB.T6G(SCH_1):PAGE92_I22@PURE_QUANTA.SCONN288_DDR506112002KQ(CHIPS)':
 'DQ2_B': CDS_PINID='DQ2_B';
NET_NAME
'M_H_CPU0_SB_DQ<30>'
 '@T6G_MB_LIB.T6G(SCH_1):M_H_CPU0_SB_DQ'<30>:
 C_SIGNAL='@t6g_mb_lib.t6g(sch_1):m_h_cpu0_sb_dq(30)';
NODE_NAME     U25 DE12
 '@T6G_MB_LIB.T6G(SCH_1):PAGE17_I159@PURE_QUANTA.GENOA_SP5(CHIPS)':
 'MHB_DATA30': CDS_PINID='MHB_DATA30';
NODE_NAME     J69 285
 '@T6G_MB_LIB.T6G(SCH_1):PAGE92_I22@PURE_QUANTA.SCONN288_DDR506112002KQ(CHIPS)':
 'DQ30_B': CDS_PINID='DQ30_B';
NET_NAME
'M_H_CPU0_SB_DQ<31>'
 '@T6G_MB_LIB.T6G(SCH_1):M_H_CPU0_SB_DQ'<31>:
 C_SIGNAL='@t6g_mb_lib.t6g(sch_1):m_h_cpu0_sb_dq(31)';
NODE_NAME     U25 DF14
 '@T6G_MB_LIB.T6G(SCH_1):PAGE17_I159@PURE_QUANTA.GENOA_SP5(CHIPS)':
 'MHB_DATA31': CDS_PINID='MHB_DATA31';
NODE_NAME     J69 287
 '@T6G_MB_LIB.T6G(SCH_1):PAGE92_I22@PURE_QUANTA.SCONN288_DDR506112002KQ(CHIPS)':
 'DQ31_B': CDS_PINID='DQ31_B';
NET_NAME
'M_H_CPU0_SB_DQ<3>'
 '@T6G_MB_LIB.T6G(SCH_1):M_H_CPU0_SB_DQ'<3>:
 C_SIGNAL='@t6g_mb_lib.t6g(sch_1):m_h_cpu0_sb_dq(3)';
NODE_NAME     U25 CD14
 '@T6G_MB_LIB.T6G(SCH_1):PAGE17_I159@PURE_QUANTA.GENOA_SP5(CHIPS)':
 'MHB_DATA3': CDS_PINID='MHB_DATA3';
NODE_NAME     J69 247
 '@T6G_MB_LIB.T6G(SCH_1):PAGE92_I22@PURE_QUANTA.SCONN288_DDR506112002KQ(CHIPS)':
 'DQ3_B': CDS_PINID='DQ3_B';
NET_NAME
'M_H_CPU0_SB_DQ<4>'
 '@T6G_MB_LIB.T6G(SCH_1):M_H_CPU0_SB_DQ'<4>:
 C_SIGNAL='@t6g_mb_lib.t6g(sch_1):m_h_cpu0_sb_dq(4)';
NODE_NAME     U25 CF13
 '@T6G_MB_LIB.T6G(SCH_1):PAGE17_I159@PURE_QUANTA.GENOA_SP5(CHIPS)':
 'MHB_DATA4': CDS_PINID='MHB_DATA4';
NODE_NAME     J69 107
 '@T6G_MB_LIB.T6G(SCH_1):PAGE92_I22@PURE_QUANTA.SCONN288_DDR506112002KQ(CHIPS)':
 'DQ4_B': CDS_PINID='DQ4_B';
NET_NAME
'M_H_CPU0_SB_DQ<5>'
 '@T6G_MB_LIB.T6G(SCH_1):M_H_CPU0_SB_DQ'<5>:
 C_SIGNAL='@t6g_mb_lib.t6g(sch_1):m_h_cpu0_sb_dq(5)';
NODE_NAME     U25 CG14
 '@T6G_MB_LIB.T6G(SCH_1):PAGE17_I159@PURE_QUANTA.GENOA_SP5(CHIPS)':
 'MHB_DATA5': CDS_PINID='MHB_DATA5';
NODE_NAME     J69 109
 '@T6G_MB_LIB.T6G(SCH_1):PAGE92_I22@PURE_QUANTA.SCONN288_DDR506112002KQ(CHIPS)':
 'DQ5_B': CDS_PINID='DQ5_B';
NET_NAME
'M_H_CPU0_SB_DQ<6>'
 '@T6G_MB_LIB.T6G(SCH_1):M_H_CPU0_SB_DQ'<6>:
 C_SIGNAL='@t6g_mb_lib.t6g(sch_1):m_h_cpu0_sb_dq(6)';
NODE_NAME     U25 CG12
 '@T6G_MB_LIB.T6G(SCH_1):PAGE17_I159@PURE_QUANTA.GENOA_SP5(CHIPS)':
 'MHB_DATA6': CDS_PINID='MHB_DATA6';
NODE_NAME     J69 252
 '@T6G_MB_LIB.T6G(SCH_1):PAGE92_I22@PURE_QUANTA.SCONN288_DDR506112002KQ(CHIPS)':
 'DQ6_B': CDS_PINID='DQ6_B';
NET_NAME
'M_H_CPU0_SB_DQ<7>'
 '@T6G_MB_LIB.T6G(SCH_1):M_H_CPU0_SB_DQ'<7>:
 C_SIGNAL='@t6g_mb_lib.t6g(sch_1):m_h_cpu0_sb_dq(7)';
NODE_NAME     U25 CH14
 '@T6G_MB_LIB.T6G(SCH_1):PAGE17_I159@PURE_QUANTA.GENOA_SP5(CHIPS)':
 'MHB_DATA7': CDS_PINID='MHB_DATA7';
NODE_NAME     J69 254
 '@T6G_MB_LIB.T6G(SCH_1):PAGE92_I22@PURE_QUANTA.SCONN288_DDR506112002KQ(CHIPS)':
 'DQ7_B': CDS_PINID='DQ7_B';
NET_NAME
'M_H_CPU0_SB_DQ<8>'
 '@T6G_MB_LIB.T6G(SCH_1):M_H_CPU0_SB_DQ'<8>:
 C_SIGNAL='@t6g_mb_lib.t6g(sch_1):m_h_cpu0_sb_dq(8)';
NODE_NAME     U25 CH13
 '@T6G_MB_LIB.T6G(SCH_1):PAGE17_I159@PURE_QUANTA.GENOA_SP5(CHIPS)':
 'MHB_DATA8': CDS_PINID='MHB_DATA8';
NODE_NAME     J69 111
 '@T6G_MB_LIB.T6G(SCH_1):PAGE92_I22@PURE_QUANTA.SCONN288_DDR506112002KQ(CHIPS)':
 'DQ8_B': CDS_PINID='DQ8_B';
NET_NAME
'M_H_CPU0_SB_DQ<9>'
 '@T6G_MB_LIB.T6G(SCH_1):M_H_CPU0_SB_DQ'<9>:
 C_SIGNAL='@t6g_mb_lib.t6g(sch_1):m_h_cpu0_sb_dq(9)';
NODE_NAME     U25 CJ14
 '@T6G_MB_LIB.T6G(SCH_1):PAGE17_I159@PURE_QUANTA.GENOA_SP5(CHIPS)':
 'MHB_DATA9': CDS_PINID='MHB_DATA9';
NODE_NAME     J69 113
 '@T6G_MB_LIB.T6G(SCH_1):PAGE92_I22@PURE_QUANTA.SCONN288_DDR506112002KQ(CHIPS)':
 'DQ9_B': CDS_PINID='DQ9_B';
NET_NAME
'M_H_CPU0_SB_DQS_DN<0>'
 '@T6G_MB_LIB.T6G(SCH_1):M_H_CPU0_SB_DQS_DN'<0>:
 C_SIGNAL='@t6g_mb_lib.t6g(sch_1):m_h_cpu0_sb_dqs_dn(0)';
NODE_NAME     U25 CE12
 '@T6G_MB_LIB.T6G(SCH_1):PAGE17_I159@PURE_QUANTA.GENOA_SP5(CHIPS)':
 'MHB_DQS_L0': CDS_PINID='MHB_DQS_L0';
NODE_NAME     J69 105
 '@T6G_MB_LIB.T6G(SCH_1):PAGE92_I237@PURE_QUANTA.SCONN288_DDR506112002KQ(CHIPS)':
 'DQS0_B_C': CDS_PINID='DQS0_B_C';
NET_NAME
'M_H_CPU0_SB_DQS_DN<1>'
 '@T6G_MB_LIB.T6G(SCH_1):M_H_CPU0_SB_DQS_DN'<1>:
 C_SIGNAL='@t6g_mb_lib.t6g(sch_1):m_h_cpu0_sb_dqs_dn(1)';
NODE_NAME     U25 CL12
 '@T6G_MB_LIB.T6G(SCH_1):PAGE17_I159@PURE_QUANTA.GENOA_SP5(CHIPS)':
 'MHB_DQS_L1': CDS_PINID='MHB_DQS_L1';
NODE_NAME     J69 116
 '@T6G_MB_LIB.T6G(SCH_1):PAGE92_I237@PURE_QUANTA.SCONN288_DDR506112002KQ(CHIPS)':
 'DQS1_B_C': CDS_PINID='DQS1_B_C';
NET_NAME
'M_H_CPU0_SB_DQS_DN<2>'
 '@T6G_MB_LIB.T6G(SCH_1):M_H_CPU0_SB_DQS_DN'<2>:
 C_SIGNAL='@t6g_mb_lib.t6g(sch_1):m_h_cpu0_sb_dqs_dn(2)';
NODE_NAME     U25 CU12
 '@T6G_MB_LIB.T6G(SCH_1):PAGE17_I159@PURE_QUANTA.GENOA_SP5(CHIPS)':
 'MHB_DQS_L2': CDS_PINID='MHB_DQS_L2';
NODE_NAME     J69 127
 '@T6G_MB_LIB.T6G(SCH_1):PAGE92_I237@PURE_QUANTA.SCONN288_DDR506112002KQ(CHIPS)':
 'DQS2_B_C': CDS_PINID='DQS2_B_C';
NET_NAME
'M_H_CPU0_SB_DQS_DN<3>'
 '@T6G_MB_LIB.T6G(SCH_1):M_H_CPU0_SB_DQS_DN'<3>:
 C_SIGNAL='@t6g_mb_lib.t6g(sch_1):m_h_cpu0_sb_dqs_dn(3)';
NODE_NAME     U25 DC12
 '@T6G_MB_LIB.T6G(SCH_1):PAGE17_I159@PURE_QUANTA.GENOA_SP5(CHIPS)':
 'MHB_DQS_L3': CDS_PINID='MHB_DQS_L3';
NODE_NAME     J69 138
 '@T6G_MB_LIB.T6G(SCH_1):PAGE92_I237@PURE_QUANTA.SCONN288_DDR506112002KQ(CHIPS)':
 'DQS3_B_C': CDS_PINID='DQS3_B_C';
NET_NAME
'M_H_CPU0_SB_DQS_DN<4>'
 '@T6G_MB_LIB.T6G(SCH_1):M_H_CPU0_SB_DQS_DN'<4>:
 C_SIGNAL='@t6g_mb_lib.t6g(sch_1):m_h_cpu0_sb_dqs_dn(4)';
NODE_NAME     U25 BW14
 '@T6G_MB_LIB.T6G(SCH_1):PAGE17_I159@PURE_QUANTA.GENOA_SP5(CHIPS)':
 'MHB_DQS_L4': CDS_PINID='MHB_DQS_L4';
NODE_NAME     J69 238
 '@T6G_MB_LIB.T6G(SCH_1):PAGE92_I237@PURE_QUANTA.SCONN288_DDR506112002KQ(CHIPS)':
 'DQS4_B_C': CDS_PINID='DQS4_B_C';
NET_NAME
'M_H_CPU0_SB_DQS_DN<5>'
 '@T6G_MB_LIB.T6G(SCH_1):M_H_CPU0_SB_DQS_DN'<5>:
 C_SIGNAL='@t6g_mb_lib.t6g(sch_1):m_h_cpu0_sb_dqs_dn(5)';
NODE_NAME     U25 CE14
 '@T6G_MB_LIB.T6G(SCH_1):PAGE17_I159@PURE_QUANTA.GENOA_SP5(CHIPS)':
 'MHB_DQS_L5': CDS_PINID='MHB_DQS_L5';
NODE_NAME     J69 249
 '@T6G_MB_LIB.T6G(SCH_1):PAGE92_I237@PURE_QUANTA.SCONN288_DDR506112002KQ(CHIPS)':
 'DQS5_B_C||TDQS5_B_C': CDS_PINID='\dqs5_b_c||tdqs5_b_c\';
NET_NAME
'M_H_CPU0_SB_DQS_DN<6>'
 '@T6G_MB_LIB.T6G(SCH_1):M_H_CPU0_SB_DQS_DN'<6>:
 C_SIGNAL='@t6g_mb_lib.t6g(sch_1):m_h_cpu0_sb_dqs_dn(6)';
NODE_NAME     U25 CL14
 '@T6G_MB_LIB.T6G(SCH_1):PAGE17_I159@PURE_QUANTA.GENOA_SP5(CHIPS)':
 'MHB_DQS_L6': CDS_PINID='MHB_DQS_L6';
NODE_NAME     J69 260
 '@T6G_MB_LIB.T6G(SCH_1):PAGE92_I237@PURE_QUANTA.SCONN288_DDR506112002KQ(CHIPS)':
 'DQS6_B_C||TDQS6_B_C': CDS_PINID='\dqs6_b_c||tdqs6_b_c\';
NET_NAME
'M_H_CPU0_SB_DQS_DN<7>'
 '@T6G_MB_LIB.T6G(SCH_1):M_H_CPU0_SB_DQS_DN'<7>:
 C_SIGNAL='@t6g_mb_lib.t6g(sch_1):m_h_cpu0_sb_dqs_dn(7)';
NODE_NAME     U25 CU14
 '@T6G_MB_LIB.T6G(SCH_1):PAGE17_I159@PURE_QUANTA.GENOA_SP5(CHIPS)':
 'MHB_DQS_L7': CDS_PINID='MHB_DQS_L7';
NODE_NAME     J69 271
 '@T6G_MB_LIB.T6G(SCH_1):PAGE92_I237@PURE_QUANTA.SCONN288_DDR506112002KQ(CHIPS)':
 'DQS7_B_C||TDQS7_B_C': CDS_PINID='\dqs7_b_c||tdqs7_b_c\';
NET_NAME
'M_H_CPU0_SB_DQS_DN<8>'
 '@T6G_MB_LIB.T6G(SCH_1):M_H_CPU0_SB_DQS_DN'<8>:
 C_SIGNAL='@t6g_mb_lib.t6g(sch_1):m_h_cpu0_sb_dqs_dn(8)';
NODE_NAME     U25 DC14
 '@T6G_MB_LIB.T6G(SCH_1):PAGE17_I159@PURE_QUANTA.GENOA_SP5(CHIPS)':
 'MHB_DQS_L8': CDS_PINID='MHB_DQS_L8';
NODE_NAME     J69 282
 '@T6G_MB_LIB.T6G(SCH_1):PAGE92_I237@PURE_QUANTA.SCONN288_DDR506112002KQ(CHIPS)':
 'DQS8_B_C||TDQS8_B_C': CDS_PINID='\dqs8_b_c||tdqs8_b_c\';
NET_NAME
'M_H_CPU0_SB_DQS_DN<9>'
 '@T6G_MB_LIB.T6G(SCH_1):M_H_CPU0_SB_DQS_DN'<9>:
 C_SIGNAL='@t6g_mb_lib.t6g(sch_1):m_h_cpu0_sb_dqs_dn(9)';
NODE_NAME     U25 BW12
 '@T6G_MB_LIB.T6G(SCH_1):PAGE17_I159@PURE_QUANTA.GENOA_SP5(CHIPS)':
 'MHB_DQS_L9': CDS_PINID='MHB_DQS_L9';
NODE_NAME     J69 94
 '@T6G_MB_LIB.T6G(SCH_1):PAGE92_I237@PURE_QUANTA.SCONN288_DDR506112002KQ(CHIPS)':
 'DQS9_B_C||TDQS9_B_C': CDS_PINID='\dqs9_b_c||tdqs9_b_c\';
NET_NAME
'M_H_CPU0_SB_DQS_DP<0>'
 '@T6G_MB_LIB.T6G(SCH_1):M_H_CPU0_SB_DQS_DP'<0>:
 C_SIGNAL='@t6g_mb_lib.t6g(sch_1):m_h_cpu0_sb_dqs_dp(0)';
NODE_NAME     U25 CD13
 '@T6G_MB_LIB.T6G(SCH_1):PAGE17_I159@PURE_QUANTA.GENOA_SP5(CHIPS)':
 'MHB_DQS_H0': CDS_PINID='MHB_DQS_H0';
NODE_NAME     J69 104
 '@T6G_MB_LIB.T6G(SCH_1):PAGE92_I237@PURE_QUANTA.SCONN288_DDR506112002KQ(CHIPS)':
 'DQS0_B_T': CDS_PINID='DQS0_B_T';
NET_NAME
'M_H_CPU0_SB_DQS_DP<1>'
 '@T6G_MB_LIB.T6G(SCH_1):M_H_CPU0_SB_DQS_DP'<1>:
 C_SIGNAL='@t6g_mb_lib.t6g(sch_1):m_h_cpu0_sb_dqs_dp(1)';
NODE_NAME     U25 CK13
 '@T6G_MB_LIB.T6G(SCH_1):PAGE17_I159@PURE_QUANTA.GENOA_SP5(CHIPS)':
 'MHB_DQS_H1': CDS_PINID='MHB_DQS_H1';
NODE_NAME     J69 115
 '@T6G_MB_LIB.T6G(SCH_1):PAGE92_I237@PURE_QUANTA.SCONN288_DDR506112002KQ(CHIPS)':
 'DQS1_B_T': CDS_PINID='DQS1_B_T';
NET_NAME
'M_H_CPU0_SB_DQS_DP<2>'
 '@T6G_MB_LIB.T6G(SCH_1):M_H_CPU0_SB_DQS_DP'<2>:
 C_SIGNAL='@t6g_mb_lib.t6g(sch_1):m_h_cpu0_sb_dqs_dp(2)';
NODE_NAME     U25 CT13
 '@T6G_MB_LIB.T6G(SCH_1):PAGE17_I159@PURE_QUANTA.GENOA_SP5(CHIPS)':
 'MHB_DQS_H2': CDS_PINID='MHB_DQS_H2';
NODE_NAME     J69 126
 '@T6G_MB_LIB.T6G(SCH_1):PAGE92_I237@PURE_QUANTA.SCONN288_DDR506112002KQ(CHIPS)':
 'DQS2_B_T': CDS_PINID='DQS2_B_T';
NET_NAME
'M_H_CPU0_SB_DQS_DP<3>'
 '@T6G_MB_LIB.T6G(SCH_1):M_H_CPU0_SB_DQS_DP'<3>:
 C_SIGNAL='@t6g_mb_lib.t6g(sch_1):m_h_cpu0_sb_dqs_dp(3)';
NODE_NAME     U25 DB13
 '@T6G_MB_LIB.T6G(SCH_1):PAGE17_I159@PURE_QUANTA.GENOA_SP5(CHIPS)':
 'MHB_DQS_H3': CDS_PINID='MHB_DQS_H3';
NODE_NAME     J69 137
 '@T6G_MB_LIB.T6G(SCH_1):PAGE92_I237@PURE_QUANTA.SCONN288_DDR506112002KQ(CHIPS)':
 'DQS3_B_T': CDS_PINID='DQS3_B_T';
NET_NAME
'M_H_CPU0_SB_DQS_DP<4>'
 '@T6G_MB_LIB.T6G(SCH_1):M_H_CPU0_SB_DQS_DP'<4>:
 C_SIGNAL='@t6g_mb_lib.t6g(sch_1):m_h_cpu0_sb_dqs_dp(4)';
NODE_NAME     U25 BY14
 '@T6G_MB_LIB.T6G(SCH_1):PAGE17_I159@PURE_QUANTA.GENOA_SP5(CHIPS)':
 'MHB_DQS_H4': CDS_PINID='MHB_DQS_H4';
NODE_NAME     J69 239
 '@T6G_MB_LIB.T6G(SCH_1):PAGE92_I237@PURE_QUANTA.SCONN288_DDR506112002KQ(CHIPS)':
 'DQS4_B_T': CDS_PINID='DQS4_B_T';
NET_NAME
'M_H_CPU0_SB_DQS_DP<5>'
 '@T6G_MB_LIB.T6G(SCH_1):M_H_CPU0_SB_DQS_DP'<5>:
 C_SIGNAL='@t6g_mb_lib.t6g(sch_1):m_h_cpu0_sb_dqs_dp(5)';
NODE_NAME     U25 CF14
 '@T6G_MB_LIB.T6G(SCH_1):PAGE17_I159@PURE_QUANTA.GENOA_SP5(CHIPS)':
 'MHB_DQS_H5': CDS_PINID='MHB_DQS_H5';
NODE_NAME     J69 250
 '@T6G_MB_LIB.T6G(SCH_1):PAGE92_I237@PURE_QUANTA.SCONN288_DDR506112002KQ(CHIPS)':
 'DQS5_B_T||TDQS5_B_T': CDS_PINID='\dqs5_b_t||tdqs5_b_t\';
NET_NAME
'M_H_CPU0_SB_DQS_DP<6>'
 '@T6G_MB_LIB.T6G(SCH_1):M_H_CPU0_SB_DQS_DP'<6>:
 C_SIGNAL='@t6g_mb_lib.t6g(sch_1):m_h_cpu0_sb_dqs_dp(6)';
NODE_NAME     U25 CM14
 '@T6G_MB_LIB.T6G(SCH_1):PAGE17_I159@PURE_QUANTA.GENOA_SP5(CHIPS)':
 'MHB_DQS_H6': CDS_PINID='MHB_DQS_H6';
NODE_NAME     J69 261
 '@T6G_MB_LIB.T6G(SCH_1):PAGE92_I237@PURE_QUANTA.SCONN288_DDR506112002KQ(CHIPS)':
 'DQS6_B_T||TDQS6_B_T': CDS_PINID='\dqs6_b_t||tdqs6_b_t\';
NET_NAME
'M_H_CPU0_SB_DQS_DP<7>'
 '@T6G_MB_LIB.T6G(SCH_1):M_H_CPU0_SB_DQS_DP'<7>:
 C_SIGNAL='@t6g_mb_lib.t6g(sch_1):m_h_cpu0_sb_dqs_dp(7)';
NODE_NAME     U25 CV14
 '@T6G_MB_LIB.T6G(SCH_1):PAGE17_I159@PURE_QUANTA.GENOA_SP5(CHIPS)':
 'MHB_DQS_H7': CDS_PINID='MHB_DQS_H7';
NODE_NAME     J69 272
 '@T6G_MB_LIB.T6G(SCH_1):PAGE92_I237@PURE_QUANTA.SCONN288_DDR506112002KQ(CHIPS)':
 'DQS7_B_T||TDQS7_B_T': CDS_PINID='\dqs7_b_t||tdqs7_b_t\';
NET_NAME
'M_H_CPU0_SB_DQS_DP<8>'
 '@T6G_MB_LIB.T6G(SCH_1):M_H_CPU0_SB_DQS_DP'<8>:
 C_SIGNAL='@t6g_mb_lib.t6g(sch_1):m_h_cpu0_sb_dqs_dp(8)';
NODE_NAME     U25 DD14
 '@T6G_MB_LIB.T6G(SCH_1):PAGE17_I159@PURE_QUANTA.GENOA_SP5(CHIPS)':
 'MHB_DQS_H8': CDS_PINID='MHB_DQS_H8';
NODE_NAME     J69 283
 '@T6G_MB_LIB.T6G(SCH_1):PAGE92_I237@PURE_QUANTA.SCONN288_DDR506112002KQ(CHIPS)':
 'DQS8_B_T||TDQS8_B_T': CDS_PINID='\dqs8_b_t||tdqs8_b_t\';
NET_NAME
'M_H_CPU0_SB_DQS_DP<9>'
 '@T6G_MB_LIB.T6G(SCH_1):M_H_CPU0_SB_DQS_DP'<9>:
 C_SIGNAL='@t6g_mb_lib.t6g(sch_1):m_h_cpu0_sb_dqs_dp(9)';
NODE_NAME     U25 BV13
 '@T6G_MB_LIB.T6G(SCH_1):PAGE17_I159@PURE_QUANTA.GENOA_SP5(CHIPS)':
 'MHB_DQS_H9': CDS_PINID='MHB_DQS_H9';
NODE_NAME     J69 93
 '@T6G_MB_LIB.T6G(SCH_1):PAGE92_I237@PURE_QUANTA.SCONN288_DDR506112002KQ(CHIPS)':
 'DQS9_B_T||TDQS9_B_T||DBI4_B_N': CDS_PINID='\dqs9_b_t||tdqs9_b_t||dbi4_b_n\';
NET_NAME
'M_H_CPU0_SB_PAR'
 '@T6G_MB_LIB.T6G(SCH_1):M_H_CPU0_SB_PAR':
 C_SIGNAL='@t6g_mb_lib.t6g(sch_1):m_h_cpu0_sb_par';
NODE_NAME     U25 BL14
 '@T6G_MB_LIB.T6G(SCH_1):PAGE17_I159@PURE_QUANTA.GENOA_SP5(CHIPS)':
 'MHB_PAR': CDS_PINID='MHB_PAR';
NODE_NAME     J69 227
 '@T6G_MB_LIB.T6G(SCH_1):PAGE92_I22@PURE_QUANTA.SCONN288_DDR506112002KQ(CHIPS)':
 'PAR_B': CDS_PINID='PAR_B';
NET_NAME
'M_H_CPU0_SB_RSP<0>'
 '@T6G_MB_LIB.T6G(SCH_1):M_H_CPU0_SB_RSP'<0>:
 C_SIGNAL='@t6g_mb_lib.t6g(sch_1):m_h_cpu0_sb_rsp(0)';
NODE_NAME     U25 BP13
 '@T6G_MB_LIB.T6G(SCH_1):PAGE17_I159@PURE_QUANTA.GENOA_SP5(CHIPS)':
 'MHB0_RSP_L': CDS_PINID='MHB0_RSP_L';
NODE_NAME     J69 87
 '@T6G_MB_LIB.T6G(SCH_1):PAGE92_I22@PURE_QUANTA.SCONN288_DDR506112002KQ(CHIPS)':
 'LBS||RSP_B_N': CDS_PINID='\lbs||rsp_b_n\';
NET_NAME
'M_H_CPU1_ALERT_N'
 '@T6G_MB_LIB.T6G(SCH_1):M_H_CPU1_ALERT_N':
 C_SIGNAL='@t6g_mb_lib.t6g(sch_1):m_h_cpu1_alert_n';
NODE_NAME     R507 1
 '@T6G_MB_LIB.T6G(SCH_1):PAGE44_I314@PURE_QUANTA.Q_RES(CHIPS)':
 'A': CDS_PINID='A';
NODE_NAME     J27 62
 '@T6G_MB_LIB.T6G(SCH_1):PAGE104_I22@PURE_QUANTA.SCONN288_DDR506112002KQ(CHIPS)':
 'ALERT_N': CDS_PINID='ALERT_N';
NET_NAME
'M_H_CPU1_ALERT_R_N'
 '@T6G_MB_LIB.T6G(SCH_1):M_H_CPU1_ALERT_R_N':
 C_SIGNAL='@t6g_mb_lib.t6g(sch_1):m_h_cpu1_alert_r_n';
NODE_NAME     U26 AT14
 '@T6G_MB_LIB.T6G(SCH_1):PAGE44_I159@PURE_QUANTA.GENOA_SP5(CHIPS)':
 'MH_ALERT_L': CDS_PINID='MH_ALERT_L';
NODE_NAME     R507 2
 '@T6G_MB_LIB.T6G(SCH_1):PAGE44_I314@PURE_QUANTA.Q_RES(CHIPS)':
 'B': CDS_PINID='B';
NET_NAME
'M_H_CPU1_CLK_DN<0>'
 '@T6G_MB_LIB.T6G(SCH_1):M_H_CPU1_CLK_DN'<0>:
 C_SIGNAL='@t6g_mb_lib.t6g(sch_1):m_h_cpu1_clk_dn(0)';
NODE_NAME     U26 BD13
 '@T6G_MB_LIB.T6G(SCH_1):PAGE44_I159@PURE_QUANTA.GENOA_SP5(CHIPS)':
 'MH0_CLK_L': CDS_PINID='MH0_CLK_L';
NODE_NAME     J27 218
 '@T6G_MB_LIB.T6G(SCH_1):PAGE104_I22@PURE_QUANTA.SCONN288_DDR506112002KQ(CHIPS)':
 'CK_C': CDS_PINID='CK_C';
NET_NAME
'M_H_CPU1_CLK_DP<0>'
 '@T6G_MB_LIB.T6G(SCH_1):M_H_CPU1_CLK_DP'<0>:
 C_SIGNAL='@t6g_mb_lib.t6g(sch_1):m_h_cpu1_clk_dp(0)';
NODE_NAME     U26 BC12
 '@T6G_MB_LIB.T6G(SCH_1):PAGE44_I159@PURE_QUANTA.GENOA_SP5(CHIPS)':
 'MH0_CLK_H': CDS_PINID='MH0_CLK_H';
NODE_NAME     J27 217
 '@T6G_MB_LIB.T6G(SCH_1):PAGE104_I22@PURE_QUANTA.SCONN288_DDR506112002KQ(CHIPS)':
 'CK_T': CDS_PINID='CK_T';
NET_NAME
'M_H_CPU1_RESET_N'
 '@T6G_MB_LIB.T6G(SCH_1):M_H_CPU1_RESET_N':
 C_SIGNAL='@t6g_mb_lib.t6g(sch_1):m_h_cpu1_reset_n';
NODE_NAME     U26 AU14
 '@T6G_MB_LIB.T6G(SCH_1):PAGE44_I159@PURE_QUANTA.GENOA_SP5(CHIPS)':
 'MH_RESET_L': CDS_PINID='MH_RESET_L';
NODE_NAME     J27 207
 '@T6G_MB_LIB.T6G(SCH_1):PAGE104_I22@PURE_QUANTA.SCONN288_DDR506112002KQ(CHIPS)':
 'RESET_N': CDS_PINID='RESET_N';
NET_NAME
'M_H_CPU1_SA_CA<0>'
 '@T6G_MB_LIB.T6G(SCH_1):M_H_CPU1_SA_CA'<0>:
 C_SIGNAL='@t6g_mb_lib.t6g(sch_1):m_h_cpu1_sa_ca(0)';
NODE_NAME     U26 AW12
 '@T6G_MB_LIB.T6G(SCH_1):PAGE44_I159@PURE_QUANTA.GENOA_SP5(CHIPS)':
 'MHA_CA0': CDS_PINID='MHA_CA0';
NODE_NAME     J27 66
 '@T6G_MB_LIB.T6G(SCH_1):PAGE104_I22@PURE_QUANTA.SCONN288_DDR506112002KQ(CHIPS)':
 'CA0_A': CDS_PINID='CA0_A';
NET_NAME
'M_H_CPU1_SA_CA<1>'
 '@T6G_MB_LIB.T6G(SCH_1):M_H_CPU1_SA_CA'<1>:
 C_SIGNAL='@t6g_mb_lib.t6g(sch_1):m_h_cpu1_sa_ca(1)';
NODE_NAME     U26 AY13
 '@T6G_MB_LIB.T6G(SCH_1):PAGE44_I159@PURE_QUANTA.GENOA_SP5(CHIPS)':
 'MHA_CA1': CDS_PINID='MHA_CA1';
NODE_NAME     J27 211
 '@T6G_MB_LIB.T6G(SCH_1):PAGE104_I22@PURE_QUANTA.SCONN288_DDR506112002KQ(CHIPS)':
 'CA1_A': CDS_PINID='CA1_A';
NET_NAME
'M_H_CPU1_SA_CA<2>'
 '@T6G_MB_LIB.T6G(SCH_1):M_H_CPU1_SA_CA'<2>:
 C_SIGNAL='@t6g_mb_lib.t6g(sch_1):m_h_cpu1_sa_ca(2)';
NODE_NAME     U26 AY14
 '@T6G_MB_LIB.T6G(SCH_1):PAGE44_I159@PURE_QUANTA.GENOA_SP5(CHIPS)':
 'MHA_CA2': CDS_PINID='MHA_CA2';
NODE_NAME     J27 68
 '@T6G_MB_LIB.T6G(SCH_1):PAGE104_I22@PURE_QUANTA.SCONN288_DDR506112002KQ(CHIPS)':
 'CA2_A': CDS_PINID='CA2_A';
NET_NAME
'M_H_CPU1_SA_CA<3>'
 '@T6G_MB_LIB.T6G(SCH_1):M_H_CPU1_SA_CA'<3>:
 C_SIGNAL='@t6g_mb_lib.t6g(sch_1):m_h_cpu1_sa_ca(3)';
NODE_NAME     U26 BA14
 '@T6G_MB_LIB.T6G(SCH_1):PAGE44_I159@PURE_QUANTA.GENOA_SP5(CHIPS)':
 'MHA_CA3': CDS_PINID='MHA_CA3';
NODE_NAME     J27 213
 '@T6G_MB_LIB.T6G(SCH_1):PAGE104_I22@PURE_QUANTA.SCONN288_DDR506112002KQ(CHIPS)':
 'CA3_A': CDS_PINID='CA3_A';
NET_NAME
'M_H_CPU1_SA_CA<4>'
 '@T6G_MB_LIB.T6G(SCH_1):M_H_CPU1_SA_CA'<4>:
 C_SIGNAL='@t6g_mb_lib.t6g(sch_1):m_h_cpu1_sa_ca(4)';
NODE_NAME     U26 BA12
 '@T6G_MB_LIB.T6G(SCH_1):PAGE44_I159@PURE_QUANTA.GENOA_SP5(CHIPS)':
 'MHA_CA4': CDS_PINID='MHA_CA4';
NODE_NAME     J27 70
 '@T6G_MB_LIB.T6G(SCH_1):PAGE104_I22@PURE_QUANTA.SCONN288_DDR506112002KQ(CHIPS)':
 'CA4_A': CDS_PINID='CA4_A';
NET_NAME
'M_H_CPU1_SA_CA<5>'
 '@T6G_MB_LIB.T6G(SCH_1):M_H_CPU1_SA_CA'<5>:
 C_SIGNAL='@t6g_mb_lib.t6g(sch_1):m_h_cpu1_sa_ca(5)';
NODE_NAME     U26 BB13
 '@T6G_MB_LIB.T6G(SCH_1):PAGE44_I159@PURE_QUANTA.GENOA_SP5(CHIPS)':
 'MHA_CA5': CDS_PINID='MHA_CA5';
NODE_NAME     J27 215
 '@T6G_MB_LIB.T6G(SCH_1):PAGE104_I22@PURE_QUANTA.SCONN288_DDR506112002KQ(CHIPS)':
 'CA5_A': CDS_PINID='CA5_A';
NET_NAME
'M_H_CPU1_SA_CA<6>'
 '@T6G_MB_LIB.T6G(SCH_1):M_H_CPU1_SA_CA'<6>:
 C_SIGNAL='@t6g_mb_lib.t6g(sch_1):m_h_cpu1_sa_ca(6)';
NODE_NAME     U26 BB14
 '@T6G_MB_LIB.T6G(SCH_1):PAGE44_I159@PURE_QUANTA.GENOA_SP5(CHIPS)':
 'MHA_CA6': CDS_PINID='MHA_CA6';
NODE_NAME     J27 72
 '@T6G_MB_LIB.T6G(SCH_1):PAGE104_I22@PURE_QUANTA.SCONN288_DDR506112002KQ(CHIPS)':
 'CA6_A': CDS_PINID='CA6_A';
NET_NAME
'M_H_CPU1_SA_CB<0>'
 '@T6G_MB_LIB.T6G(SCH_1):M_H_CPU1_SA_CB'<0>:
 C_SIGNAL='@t6g_mb_lib.t6g(sch_1):m_h_cpu1_sa_cb(0)';
NODE_NAME     U26 AJ12
 '@T6G_MB_LIB.T6G(SCH_1):PAGE44_I159@PURE_QUANTA.GENOA_SP5(CHIPS)':
 'MHA_CHECK0': CDS_PINID='MHA_CHECK0';
NODE_NAME     J27 51
 '@T6G_MB_LIB.T6G(SCH_1):PAGE104_I22@PURE_QUANTA.SCONN288_DDR506112002KQ(CHIPS)':
 'CB0_A': CDS_PINID='CB0_A';
NET_NAME
'M_H_CPU1_SA_CB<1>'
 '@T6G_MB_LIB.T6G(SCH_1):M_H_CPU1_SA_CB'<1>:
 C_SIGNAL='@t6g_mb_lib.t6g(sch_1):m_h_cpu1_sa_cb(1)';
NODE_NAME     U26 AK14
 '@T6G_MB_LIB.T6G(SCH_1):PAGE44_I159@PURE_QUANTA.GENOA_SP5(CHIPS)':
 'MHA_CHECK1': CDS_PINID='MHA_CHECK1';
NODE_NAME     J27 53
 '@T6G_MB_LIB.T6G(SCH_1):PAGE104_I22@PURE_QUANTA.SCONN288_DDR506112002KQ(CHIPS)':
 'CB1_A': CDS_PINID='CB1_A';
NET_NAME
'M_H_CPU1_SA_CB<2>'
 '@T6G_MB_LIB.T6G(SCH_1):M_H_CPU1_SA_CB'<2>:
 C_SIGNAL='@t6g_mb_lib.t6g(sch_1):m_h_cpu1_sa_cb(2)';
NODE_NAME     U26 AK13
 '@T6G_MB_LIB.T6G(SCH_1):PAGE44_I159@PURE_QUANTA.GENOA_SP5(CHIPS)':
 'MHA_CHECK2': CDS_PINID='MHA_CHECK2';
NODE_NAME     J27 196
 '@T6G_MB_LIB.T6G(SCH_1):PAGE104_I22@PURE_QUANTA.SCONN288_DDR506112002KQ(CHIPS)':
 'CB2_A': CDS_PINID='CB2_A';
NET_NAME
'M_H_CPU1_SA_CB<3>'
 '@T6G_MB_LIB.T6G(SCH_1):M_H_CPU1_SA_CB'<3>:
 C_SIGNAL='@t6g_mb_lib.t6g(sch_1):m_h_cpu1_sa_cb(3)';
NODE_NAME     U26 AL14
 '@T6G_MB_LIB.T6G(SCH_1):PAGE44_I159@PURE_QUANTA.GENOA_SP5(CHIPS)':
 'MHA_CHECK3': CDS_PINID='MHA_CHECK3';
NODE_NAME     J27 198
 '@T6G_MB_LIB.T6G(SCH_1):PAGE104_I22@PURE_QUANTA.SCONN288_DDR506112002KQ(CHIPS)':
 'CB3_A': CDS_PINID='CB3_A';
NET_NAME
'M_H_CPU1_SA_CB<4>'
 '@T6G_MB_LIB.T6G(SCH_1):M_H_CPU1_SA_CB'<4>:
 C_SIGNAL='@t6g_mb_lib.t6g(sch_1):m_h_cpu1_sa_cb(4)';
NODE_NAME     U26 AN12
 '@T6G_MB_LIB.T6G(SCH_1):PAGE44_I159@PURE_QUANTA.GENOA_SP5(CHIPS)':
 'MHA_CHECK4': CDS_PINID='MHA_CHECK4';
NODE_NAME     J27 58
 '@T6G_MB_LIB.T6G(SCH_1):PAGE104_I22@PURE_QUANTA.SCONN288_DDR506112002KQ(CHIPS)':
 'CB4_A': CDS_PINID='CB4_A';
NET_NAME
'M_H_CPU1_SA_CB<5>'
 '@T6G_MB_LIB.T6G(SCH_1):M_H_CPU1_SA_CB'<5>:
 C_SIGNAL='@t6g_mb_lib.t6g(sch_1):m_h_cpu1_sa_cb(5)';
NODE_NAME     U26 AP14
 '@T6G_MB_LIB.T6G(SCH_1):PAGE44_I159@PURE_QUANTA.GENOA_SP5(CHIPS)':
 'MHA_CHECK5': CDS_PINID='MHA_CHECK5';
NODE_NAME     J27 60
 '@T6G_MB_LIB.T6G(SCH_1):PAGE104_I22@PURE_QUANTA.SCONN288_DDR506112002KQ(CHIPS)':
 'CB5_A': CDS_PINID='CB5_A';
NET_NAME
'M_H_CPU1_SA_CB<6>'
 '@T6G_MB_LIB.T6G(SCH_1):M_H_CPU1_SA_CB'<6>:
 C_SIGNAL='@t6g_mb_lib.t6g(sch_1):m_h_cpu1_sa_cb(6)';
NODE_NAME     U26 AP13
 '@T6G_MB_LIB.T6G(SCH_1):PAGE44_I159@PURE_QUANTA.GENOA_SP5(CHIPS)':
 'MHA_CHECK6': CDS_PINID='MHA_CHECK6';
NODE_NAME     J27 203
 '@T6G_MB_LIB.T6G(SCH_1):PAGE104_I22@PURE_QUANTA.SCONN288_DDR506112002KQ(CHIPS)':
 'CB6_A': CDS_PINID='CB6_A';
NET_NAME
'M_H_CPU1_SA_CB<7>'
 '@T6G_MB_LIB.T6G(SCH_1):M_H_CPU1_SA_CB'<7>:
 C_SIGNAL='@t6g_mb_lib.t6g(sch_1):m_h_cpu1_sa_cb(7)';
NODE_NAME     U26 AR14
 '@T6G_MB_LIB.T6G(SCH_1):PAGE44_I159@PURE_QUANTA.GENOA_SP5(CHIPS)':
 'MHA_CHECK7': CDS_PINID='MHA_CHECK7';
NODE_NAME     J27 205
 '@T6G_MB_LIB.T6G(SCH_1):PAGE104_I22@PURE_QUANTA.SCONN288_DDR506112002KQ(CHIPS)':
 'CB7_A': CDS_PINID='CB7_A';
NET_NAME
'M_H_CPU1_SA_CS_N<0>'
 '@T6G_MB_LIB.T6G(SCH_1):M_H_CPU1_SA_CS_N'<0>:
 C_SIGNAL='@t6g_mb_lib.t6g(sch_1):m_h_cpu1_sa_cs_n(0)';
NODE_NAME     U26 AU12
 '@T6G_MB_LIB.T6G(SCH_1):PAGE44_I159@PURE_QUANTA.GENOA_SP5(CHIPS)':
 'MHA0_CS_L0': CDS_PINID='MHA0_CS_L0';
NODE_NAME     J27 64
 '@T6G_MB_LIB.T6G(SCH_1):PAGE104_I22@PURE_QUANTA.SCONN288_DDR506112002KQ(CHIPS)':
 'CS0_A_N': CDS_PINID='CS0_A_N';
NET_NAME
'M_H_CPU1_SA_CS_N<1>'
 '@T6G_MB_LIB.T6G(SCH_1):M_H_CPU1_SA_CS_N'<1>:
 C_SIGNAL='@t6g_mb_lib.t6g(sch_1):m_h_cpu1_sa_cs_n(1)';
NODE_NAME     U26 AV14
 '@T6G_MB_LIB.T6G(SCH_1):PAGE44_I159@PURE_QUANTA.GENOA_SP5(CHIPS)':
 'MHA0_CS_L1': CDS_PINID='MHA0_CS_L1';
NODE_NAME     J27 209
 '@T6G_MB_LIB.T6G(SCH_1):PAGE104_I22@PURE_QUANTA.SCONN288_DDR506112002KQ(CHIPS)':
 'CS1_A_N': CDS_PINID='CS1_A_N';
NET_NAME
'M_H_CPU1_SA_DQ<0>'
 '@T6G_MB_LIB.T6G(SCH_1):M_H_CPU1_SA_DQ'<0>:
 C_SIGNAL='@t6g_mb_lib.t6g(sch_1):m_h_cpu1_sa_dq(0)';
NODE_NAME     U26 E12
 '@T6G_MB_LIB.T6G(SCH_1):PAGE44_I159@PURE_QUANTA.GENOA_SP5(CHIPS)':
 'MHA_DATA0': CDS_PINID='MHA_DATA0';
NODE_NAME     J27 7
 '@T6G_MB_LIB.T6G(SCH_1):PAGE104_I22@PURE_QUANTA.SCONN288_DDR506112002KQ(CHIPS)':
 'DQ0_A': CDS_PINID='DQ0_A';
NET_NAME
'M_H_CPU1_SA_DQ<10>'
 '@T6G_MB_LIB.T6G(SCH_1):M_H_CPU1_SA_DQ'<10>:
 C_SIGNAL='@t6g_mb_lib.t6g(sch_1):m_h_cpu1_sa_dq(10)';
NODE_NAME     U26 M13
 '@T6G_MB_LIB.T6G(SCH_1):PAGE44_I159@PURE_QUANTA.GENOA_SP5(CHIPS)':
 'MHA_DATA10': CDS_PINID='MHA_DATA10';
NODE_NAME     J27 163
 '@T6G_MB_LIB.T6G(SCH_1):PAGE104_I22@PURE_QUANTA.SCONN288_DDR506112002KQ(CHIPS)':
 'DQ10_A': CDS_PINID='DQ10_A';
NET_NAME
'M_H_CPU1_SA_DQ<11>'
 '@T6G_MB_LIB.T6G(SCH_1):M_H_CPU1_SA_DQ'<11>:
 C_SIGNAL='@t6g_mb_lib.t6g(sch_1):m_h_cpu1_sa_dq(11)';
NODE_NAME     U26 N14
 '@T6G_MB_LIB.T6G(SCH_1):PAGE44_I159@PURE_QUANTA.GENOA_SP5(CHIPS)':
 'MHA_DATA11': CDS_PINID='MHA_DATA11';
NODE_NAME     J27 165
 '@T6G_MB_LIB.T6G(SCH_1):PAGE104_I22@PURE_QUANTA.SCONN288_DDR506112002KQ(CHIPS)':
 'DQ11_A': CDS_PINID='DQ11_A';
NET_NAME
'M_H_CPU1_SA_DQ<12>'
 '@T6G_MB_LIB.T6G(SCH_1):M_H_CPU1_SA_DQ'<12>:
 C_SIGNAL='@t6g_mb_lib.t6g(sch_1):m_h_cpu1_sa_dq(12)';
NODE_NAME     U26 R12
 '@T6G_MB_LIB.T6G(SCH_1):PAGE44_I159@PURE_QUANTA.GENOA_SP5(CHIPS)':
 'MHA_DATA12': CDS_PINID='MHA_DATA12';
NODE_NAME     J27 25
 '@T6G_MB_LIB.T6G(SCH_1):PAGE104_I22@PURE_QUANTA.SCONN288_DDR506112002KQ(CHIPS)':
 'DQ12_A': CDS_PINID='DQ12_A';
NET_NAME
'M_H_CPU1_SA_DQ<13>'
 '@T6G_MB_LIB.T6G(SCH_1):M_H_CPU1_SA_DQ'<13>:
 C_SIGNAL='@t6g_mb_lib.t6g(sch_1):m_h_cpu1_sa_dq(13)';
NODE_NAME     U26 T14
 '@T6G_MB_LIB.T6G(SCH_1):PAGE44_I159@PURE_QUANTA.GENOA_SP5(CHIPS)':
 'MHA_DATA13': CDS_PINID='MHA_DATA13';
NODE_NAME     J27 27
 '@T6G_MB_LIB.T6G(SCH_1):PAGE104_I22@PURE_QUANTA.SCONN288_DDR506112002KQ(CHIPS)':
 'DQ13_A': CDS_PINID='DQ13_A';
NET_NAME
'M_H_CPU1_SA_DQ<14>'
 '@T6G_MB_LIB.T6G(SCH_1):M_H_CPU1_SA_DQ'<14>:
 C_SIGNAL='@t6g_mb_lib.t6g(sch_1):m_h_cpu1_sa_dq(14)';
NODE_NAME     U26 T13
 '@T6G_MB_LIB.T6G(SCH_1):PAGE44_I159@PURE_QUANTA.GENOA_SP5(CHIPS)':
 'MHA_DATA14': CDS_PINID='MHA_DATA14';
NODE_NAME     J27 170
 '@T6G_MB_LIB.T6G(SCH_1):PAGE104_I22@PURE_QUANTA.SCONN288_DDR506112002KQ(CHIPS)':
 'DQ14_A': CDS_PINID='DQ14_A';
NET_NAME
'M_H_CPU1_SA_DQ<15>'
 '@T6G_MB_LIB.T6G(SCH_1):M_H_CPU1_SA_DQ'<15>:
 C_SIGNAL='@t6g_mb_lib.t6g(sch_1):m_h_cpu1_sa_dq(15)';
NODE_NAME     U26 U14
 '@T6G_MB_LIB.T6G(SCH_1):PAGE44_I159@PURE_QUANTA.GENOA_SP5(CHIPS)':
 'MHA_DATA15': CDS_PINID='MHA_DATA15';
NODE_NAME     J27 172
 '@T6G_MB_LIB.T6G(SCH_1):PAGE104_I22@PURE_QUANTA.SCONN288_DDR506112002KQ(CHIPS)':
 'DQ15_A': CDS_PINID='DQ15_A';
NET_NAME
'M_H_CPU1_SA_DQ<16>'
 '@T6G_MB_LIB.T6G(SCH_1):M_H_CPU1_SA_DQ'<16>:
 C_SIGNAL='@t6g_mb_lib.t6g(sch_1):m_h_cpu1_sa_dq(16)';
NODE_NAME     U26 U12
 '@T6G_MB_LIB.T6G(SCH_1):PAGE44_I159@PURE_QUANTA.GENOA_SP5(CHIPS)':
 'MHA_DATA16': CDS_PINID='MHA_DATA16';
NODE_NAME     J27 29
 '@T6G_MB_LIB.T6G(SCH_1):PAGE104_I22@PURE_QUANTA.SCONN288_DDR506112002KQ(CHIPS)':
 'DQ16_A': CDS_PINID='DQ16_A';
NET_NAME
'M_H_CPU1_SA_DQ<17>'
 '@T6G_MB_LIB.T6G(SCH_1):M_H_CPU1_SA_DQ'<17>:
 C_SIGNAL='@t6g_mb_lib.t6g(sch_1):m_h_cpu1_sa_dq(17)';
NODE_NAME     U26 V14
 '@T6G_MB_LIB.T6G(SCH_1):PAGE44_I159@PURE_QUANTA.GENOA_SP5(CHIPS)':
 'MHA_DATA17': CDS_PINID='MHA_DATA17';
NODE_NAME     J27 31
 '@T6G_MB_LIB.T6G(SCH_1):PAGE104_I22@PURE_QUANTA.SCONN288_DDR506112002KQ(CHIPS)':
 'DQ17_A': CDS_PINID='DQ17_A';
NET_NAME
'M_H_CPU1_SA_DQ<18>'
 '@T6G_MB_LIB.T6G(SCH_1):M_H_CPU1_SA_DQ'<18>:
 C_SIGNAL='@t6g_mb_lib.t6g(sch_1):m_h_cpu1_sa_dq(18)';
NODE_NAME     U26 V13
 '@T6G_MB_LIB.T6G(SCH_1):PAGE44_I159@PURE_QUANTA.GENOA_SP5(CHIPS)':
 'MHA_DATA18': CDS_PINID='MHA_DATA18';
NODE_NAME     J27 174
 '@T6G_MB_LIB.T6G(SCH_1):PAGE104_I22@PURE_QUANTA.SCONN288_DDR506112002KQ(CHIPS)':
 'DQ18_A': CDS_PINID='DQ18_A';
NET_NAME
'M_H_CPU1_SA_DQ<19>'
 '@T6G_MB_LIB.T6G(SCH_1):M_H_CPU1_SA_DQ'<19>:
 C_SIGNAL='@t6g_mb_lib.t6g(sch_1):m_h_cpu1_sa_dq(19)';
NODE_NAME     U26 W14
 '@T6G_MB_LIB.T6G(SCH_1):PAGE44_I159@PURE_QUANTA.GENOA_SP5(CHIPS)':
 'MHA_DATA19': CDS_PINID='MHA_DATA19';
NODE_NAME     J27 176
 '@T6G_MB_LIB.T6G(SCH_1):PAGE104_I22@PURE_QUANTA.SCONN288_DDR506112002KQ(CHIPS)':
 'DQ19_A': CDS_PINID='DQ19_A';
NET_NAME
'M_H_CPU1_SA_DQ<1>'
 '@T6G_MB_LIB.T6G(SCH_1):M_H_CPU1_SA_DQ'<1>:
 C_SIGNAL='@t6g_mb_lib.t6g(sch_1):m_h_cpu1_sa_dq(1)';
NODE_NAME     U26 F14
 '@T6G_MB_LIB.T6G(SCH_1):PAGE44_I159@PURE_QUANTA.GENOA_SP5(CHIPS)':
 'MHA_DATA1': CDS_PINID='MHA_DATA1';
NODE_NAME     J27 9
 '@T6G_MB_LIB.T6G(SCH_1):PAGE104_I22@PURE_QUANTA.SCONN288_DDR506112002KQ(CHIPS)':
 'DQ1_A': CDS_PINID='DQ1_A';
NET_NAME
'M_H_CPU1_SA_DQ<20>'
 '@T6G_MB_LIB.T6G(SCH_1):M_H_CPU1_SA_DQ'<20>:
 C_SIGNAL='@t6g_mb_lib.t6g(sch_1):m_h_cpu1_sa_dq(20)';
NODE_NAME     U26 AA12
 '@T6G_MB_LIB.T6G(SCH_1):PAGE44_I159@PURE_QUANTA.GENOA_SP5(CHIPS)':
 'MHA_DATA20': CDS_PINID='MHA_DATA20';
NODE_NAME     J27 36
 '@T6G_MB_LIB.T6G(SCH_1):PAGE104_I22@PURE_QUANTA.SCONN288_DDR506112002KQ(CHIPS)':
 'DQ20_A': CDS_PINID='DQ20_A';
NET_NAME
'M_H_CPU1_SA_DQ<21>'
 '@T6G_MB_LIB.T6G(SCH_1):M_H_CPU1_SA_DQ'<21>:
 C_SIGNAL='@t6g_mb_lib.t6g(sch_1):m_h_cpu1_sa_dq(21)';
NODE_NAME     U26 AB14
 '@T6G_MB_LIB.T6G(SCH_1):PAGE44_I159@PURE_QUANTA.GENOA_SP5(CHIPS)':
 'MHA_DATA21': CDS_PINID='MHA_DATA21';
NODE_NAME     J27 38
 '@T6G_MB_LIB.T6G(SCH_1):PAGE104_I22@PURE_QUANTA.SCONN288_DDR506112002KQ(CHIPS)':
 'DQ21_A': CDS_PINID='DQ21_A';
NET_NAME
'M_H_CPU1_SA_DQ<22>'
 '@T6G_MB_LIB.T6G(SCH_1):M_H_CPU1_SA_DQ'<22>:
 C_SIGNAL='@t6g_mb_lib.t6g(sch_1):m_h_cpu1_sa_dq(22)';
NODE_NAME     U26 AB13
 '@T6G_MB_LIB.T6G(SCH_1):PAGE44_I159@PURE_QUANTA.GENOA_SP5(CHIPS)':
 'MHA_DATA22': CDS_PINID='MHA_DATA22';
NODE_NAME     J27 181
 '@T6G_MB_LIB.T6G(SCH_1):PAGE104_I22@PURE_QUANTA.SCONN288_DDR506112002KQ(CHIPS)':
 'DQ22_A': CDS_PINID='DQ22_A';
NET_NAME
'M_H_CPU1_SA_DQ<23>'
 '@T6G_MB_LIB.T6G(SCH_1):M_H_CPU1_SA_DQ'<23>:
 C_SIGNAL='@t6g_mb_lib.t6g(sch_1):m_h_cpu1_sa_dq(23)';
NODE_NAME     U26 AC14
 '@T6G_MB_LIB.T6G(SCH_1):PAGE44_I159@PURE_QUANTA.GENOA_SP5(CHIPS)':
 'MHA_DATA23': CDS_PINID='MHA_DATA23';
NODE_NAME     J27 183
 '@T6G_MB_LIB.T6G(SCH_1):PAGE104_I22@PURE_QUANTA.SCONN288_DDR506112002KQ(CHIPS)':
 'DQ23_A': CDS_PINID='DQ23_A';
NET_NAME
'M_H_CPU1_SA_DQ<24>'
 '@T6G_MB_LIB.T6G(SCH_1):M_H_CPU1_SA_DQ'<24>:
 C_SIGNAL='@t6g_mb_lib.t6g(sch_1):m_h_cpu1_sa_dq(24)';
NODE_NAME     U26 AC12
 '@T6G_MB_LIB.T6G(SCH_1):PAGE44_I159@PURE_QUANTA.GENOA_SP5(CHIPS)':
 'MHA_DATA24': CDS_PINID='MHA_DATA24';
NODE_NAME     J27 40
 '@T6G_MB_LIB.T6G(SCH_1):PAGE104_I22@PURE_QUANTA.SCONN288_DDR506112002KQ(CHIPS)':
 'DQ24_A': CDS_PINID='DQ24_A';
NET_NAME
'M_H_CPU1_SA_DQ<25>'
 '@T6G_MB_LIB.T6G(SCH_1):M_H_CPU1_SA_DQ'<25>:
 C_SIGNAL='@t6g_mb_lib.t6g(sch_1):m_h_cpu1_sa_dq(25)';
NODE_NAME     U26 AD14
 '@T6G_MB_LIB.T6G(SCH_1):PAGE44_I159@PURE_QUANTA.GENOA_SP5(CHIPS)':
 'MHA_DATA25': CDS_PINID='MHA_DATA25';
NODE_NAME     J27 42
 '@T6G_MB_LIB.T6G(SCH_1):PAGE104_I22@PURE_QUANTA.SCONN288_DDR506112002KQ(CHIPS)':
 'DQ25_A': CDS_PINID='DQ25_A';
NET_NAME
'M_H_CPU1_SA_DQ<26>'
 '@T6G_MB_LIB.T6G(SCH_1):M_H_CPU1_SA_DQ'<26>:
 C_SIGNAL='@t6g_mb_lib.t6g(sch_1):m_h_cpu1_sa_dq(26)';
NODE_NAME     U26 AD13
 '@T6G_MB_LIB.T6G(SCH_1):PAGE44_I159@PURE_QUANTA.GENOA_SP5(CHIPS)':
 'MHA_DATA26': CDS_PINID='MHA_DATA26';
NODE_NAME     J27 185
 '@T6G_MB_LIB.T6G(SCH_1):PAGE104_I22@PURE_QUANTA.SCONN288_DDR506112002KQ(CHIPS)':
 'DQ26_A': CDS_PINID='DQ26_A';
NET_NAME
'M_H_CPU1_SA_DQ<27>'
 '@T6G_MB_LIB.T6G(SCH_1):M_H_CPU1_SA_DQ'<27>:
 C_SIGNAL='@t6g_mb_lib.t6g(sch_1):m_h_cpu1_sa_dq(27)';
NODE_NAME     U26 AE14
 '@T6G_MB_LIB.T6G(SCH_1):PAGE44_I159@PURE_QUANTA.GENOA_SP5(CHIPS)':
 'MHA_DATA27': CDS_PINID='MHA_DATA27';
NODE_NAME     J27 187
 '@T6G_MB_LIB.T6G(SCH_1):PAGE104_I22@PURE_QUANTA.SCONN288_DDR506112002KQ(CHIPS)':
 'DQ27_A': CDS_PINID='DQ27_A';
NET_NAME
'M_H_CPU1_SA_DQ<28>'
 '@T6G_MB_LIB.T6G(SCH_1):M_H_CPU1_SA_DQ'<28>:
 C_SIGNAL='@t6g_mb_lib.t6g(sch_1):m_h_cpu1_sa_dq(28)';
NODE_NAME     U26 AG12
 '@T6G_MB_LIB.T6G(SCH_1):PAGE44_I159@PURE_QUANTA.GENOA_SP5(CHIPS)':
 'MHA_DATA28': CDS_PINID='MHA_DATA28';
NODE_NAME     J27 47
 '@T6G_MB_LIB.T6G(SCH_1):PAGE104_I22@PURE_QUANTA.SCONN288_DDR506112002KQ(CHIPS)':
 'DQ28_A': CDS_PINID='DQ28_A';
NET_NAME
'M_H_CPU1_SA_DQ<29>'
 '@T6G_MB_LIB.T6G(SCH_1):M_H_CPU1_SA_DQ'<29>:
 C_SIGNAL='@t6g_mb_lib.t6g(sch_1):m_h_cpu1_sa_dq(29)';
NODE_NAME     U26 AH14
 '@T6G_MB_LIB.T6G(SCH_1):PAGE44_I159@PURE_QUANTA.GENOA_SP5(CHIPS)':
 'MHA_DATA29': CDS_PINID='MHA_DATA29';
NODE_NAME     J27 49
 '@T6G_MB_LIB.T6G(SCH_1):PAGE104_I22@PURE_QUANTA.SCONN288_DDR506112002KQ(CHIPS)':
 'DQ29_A': CDS_PINID='DQ29_A';
NET_NAME
'M_H_CPU1_SA_DQ<2>'
 '@T6G_MB_LIB.T6G(SCH_1):M_H_CPU1_SA_DQ'<2>:
 C_SIGNAL='@t6g_mb_lib.t6g(sch_1):m_h_cpu1_sa_dq(2)';
NODE_NAME     U26 F13
 '@T6G_MB_LIB.T6G(SCH_1):PAGE44_I159@PURE_QUANTA.GENOA_SP5(CHIPS)':
 'MHA_DATA2': CDS_PINID='MHA_DATA2';
NODE_NAME     J27 152
 '@T6G_MB_LIB.T6G(SCH_1):PAGE104_I22@PURE_QUANTA.SCONN288_DDR506112002KQ(CHIPS)':
 'DQ2_A': CDS_PINID='DQ2_A';
NET_NAME
'M_H_CPU1_SA_DQ<30>'
 '@T6G_MB_LIB.T6G(SCH_1):M_H_CPU1_SA_DQ'<30>:
 C_SIGNAL='@t6g_mb_lib.t6g(sch_1):m_h_cpu1_sa_dq(30)';
NODE_NAME     U26 AH13
 '@T6G_MB_LIB.T6G(SCH_1):PAGE44_I159@PURE_QUANTA.GENOA_SP5(CHIPS)':
 'MHA_DATA30': CDS_PINID='MHA_DATA30';
NODE_NAME     J27 192
 '@T6G_MB_LIB.T6G(SCH_1):PAGE104_I22@PURE_QUANTA.SCONN288_DDR506112002KQ(CHIPS)':
 'DQ30_A': CDS_PINID='DQ30_A';
NET_NAME
'M_H_CPU1_SA_DQ<31>'
 '@T6G_MB_LIB.T6G(SCH_1):M_H_CPU1_SA_DQ'<31>:
 C_SIGNAL='@t6g_mb_lib.t6g(sch_1):m_h_cpu1_sa_dq(31)';
NODE_NAME     U26 AJ14
 '@T6G_MB_LIB.T6G(SCH_1):PAGE44_I159@PURE_QUANTA.GENOA_SP5(CHIPS)':
 'MHA_DATA31': CDS_PINID='MHA_DATA31';
NODE_NAME     J27 194
 '@T6G_MB_LIB.T6G(SCH_1):PAGE104_I22@PURE_QUANTA.SCONN288_DDR506112002KQ(CHIPS)':
 'DQ31_A': CDS_PINID='DQ31_A';
NET_NAME
'M_H_CPU1_SA_DQ<3>'
 '@T6G_MB_LIB.T6G(SCH_1):M_H_CPU1_SA_DQ'<3>:
 C_SIGNAL='@t6g_mb_lib.t6g(sch_1):m_h_cpu1_sa_dq(3)';
NODE_NAME     U26 G14
 '@T6G_MB_LIB.T6G(SCH_1):PAGE44_I159@PURE_QUANTA.GENOA_SP5(CHIPS)':
 'MHA_DATA3': CDS_PINID='MHA_DATA3';
NODE_NAME     J27 154
 '@T6G_MB_LIB.T6G(SCH_1):PAGE104_I22@PURE_QUANTA.SCONN288_DDR506112002KQ(CHIPS)':
 'DQ3_A': CDS_PINID='DQ3_A';
NET_NAME
'M_H_CPU1_SA_DQ<4>'
 '@T6G_MB_LIB.T6G(SCH_1):M_H_CPU1_SA_DQ'<4>:
 C_SIGNAL='@t6g_mb_lib.t6g(sch_1):m_h_cpu1_sa_dq(4)';
NODE_NAME     U26 J12
 '@T6G_MB_LIB.T6G(SCH_1):PAGE44_I159@PURE_QUANTA.GENOA_SP5(CHIPS)':
 'MHA_DATA4': CDS_PINID='MHA_DATA4';
NODE_NAME     J27 14
 '@T6G_MB_LIB.T6G(SCH_1):PAGE104_I22@PURE_QUANTA.SCONN288_DDR506112002KQ(CHIPS)':
 'DQ4_A': CDS_PINID='DQ4_A';
NET_NAME
'M_H_CPU1_SA_DQ<5>'
 '@T6G_MB_LIB.T6G(SCH_1):M_H_CPU1_SA_DQ'<5>:
 C_SIGNAL='@t6g_mb_lib.t6g(sch_1):m_h_cpu1_sa_dq(5)';
NODE_NAME     U26 K14
 '@T6G_MB_LIB.T6G(SCH_1):PAGE44_I159@PURE_QUANTA.GENOA_SP5(CHIPS)':
 'MHA_DATA5': CDS_PINID='MHA_DATA5';
NODE_NAME     J27 16
 '@T6G_MB_LIB.T6G(SCH_1):PAGE104_I22@PURE_QUANTA.SCONN288_DDR506112002KQ(CHIPS)':
 'DQ5_A': CDS_PINID='DQ5_A';
NET_NAME
'M_H_CPU1_SA_DQ<6>'
 '@T6G_MB_LIB.T6G(SCH_1):M_H_CPU1_SA_DQ'<6>:
 C_SIGNAL='@t6g_mb_lib.t6g(sch_1):m_h_cpu1_sa_dq(6)';
NODE_NAME     U26 K13
 '@T6G_MB_LIB.T6G(SCH_1):PAGE44_I159@PURE_QUANTA.GENOA_SP5(CHIPS)':
 'MHA_DATA6': CDS_PINID='MHA_DATA6';
NODE_NAME     J27 159
 '@T6G_MB_LIB.T6G(SCH_1):PAGE104_I22@PURE_QUANTA.SCONN288_DDR506112002KQ(CHIPS)':
 'DQ6_A': CDS_PINID='DQ6_A';
NET_NAME
'M_H_CPU1_SA_DQ<7>'
 '@T6G_MB_LIB.T6G(SCH_1):M_H_CPU1_SA_DQ'<7>:
 C_SIGNAL='@t6g_mb_lib.t6g(sch_1):m_h_cpu1_sa_dq(7)';
NODE_NAME     U26 L14
 '@T6G_MB_LIB.T6G(SCH_1):PAGE44_I159@PURE_QUANTA.GENOA_SP5(CHIPS)':
 'MHA_DATA7': CDS_PINID='MHA_DATA7';
NODE_NAME     J27 161
 '@T6G_MB_LIB.T6G(SCH_1):PAGE104_I22@PURE_QUANTA.SCONN288_DDR506112002KQ(CHIPS)':
 'DQ7_A': CDS_PINID='DQ7_A';
NET_NAME
'M_H_CPU1_SA_DQ<8>'
 '@T6G_MB_LIB.T6G(SCH_1):M_H_CPU1_SA_DQ'<8>:
 C_SIGNAL='@t6g_mb_lib.t6g(sch_1):m_h_cpu1_sa_dq(8)';
NODE_NAME     U26 L12
 '@T6G_MB_LIB.T6G(SCH_1):PAGE44_I159@PURE_QUANTA.GENOA_SP5(CHIPS)':
 'MHA_DATA8': CDS_PINID='MHA_DATA8';
NODE_NAME     J27 18
 '@T6G_MB_LIB.T6G(SCH_1):PAGE104_I22@PURE_QUANTA.SCONN288_DDR506112002KQ(CHIPS)':
 'DQ8_A': CDS_PINID='DQ8_A';
NET_NAME
'M_H_CPU1_SA_DQ<9>'
 '@T6G_MB_LIB.T6G(SCH_1):M_H_CPU1_SA_DQ'<9>:
 C_SIGNAL='@t6g_mb_lib.t6g(sch_1):m_h_cpu1_sa_dq(9)';
NODE_NAME     U26 M14
 '@T6G_MB_LIB.T6G(SCH_1):PAGE44_I159@PURE_QUANTA.GENOA_SP5(CHIPS)':
 'MHA_DATA9': CDS_PINID='MHA_DATA9';
NODE_NAME     J27 20
 '@T6G_MB_LIB.T6G(SCH_1):PAGE104_I22@PURE_QUANTA.SCONN288_DDR506112002KQ(CHIPS)':
 'DQ9_A': CDS_PINID='DQ9_A';
NET_NAME
'M_H_CPU1_SA_DQS_DN<0>'
 '@T6G_MB_LIB.T6G(SCH_1):M_H_CPU1_SA_DQS_DN'<0>:
 C_SIGNAL='@t6g_mb_lib.t6g(sch_1):m_h_cpu1_sa_dqs_dn(0)';
NODE_NAME     U26 H13
 '@T6G_MB_LIB.T6G(SCH_1):PAGE44_I159@PURE_QUANTA.GENOA_SP5(CHIPS)':
 'MHA_DQS_L0': CDS_PINID='MHA_DQS_L0';
NODE_NAME     J27 12
 '@T6G_MB_LIB.T6G(SCH_1):PAGE104_I238@PURE_QUANTA.SCONN288_DDR506112002KQ(CHIPS)':
 'DQS0_A_C': CDS_PINID='DQS0_A_C';
NET_NAME
'M_H_CPU1_SA_DQS_DN<1>'
 '@T6G_MB_LIB.T6G(SCH_1):M_H_CPU1_SA_DQS_DN'<1>:
 C_SIGNAL='@t6g_mb_lib.t6g(sch_1):m_h_cpu1_sa_dqs_dn(1)';
NODE_NAME     U26 P13
 '@T6G_MB_LIB.T6G(SCH_1):PAGE44_I159@PURE_QUANTA.GENOA_SP5(CHIPS)':
 'MHA_DQS_L1': CDS_PINID='MHA_DQS_L1';
NODE_NAME     J27 23
 '@T6G_MB_LIB.T6G(SCH_1):PAGE104_I238@PURE_QUANTA.SCONN288_DDR506112002KQ(CHIPS)':
 'DQS1_A_C': CDS_PINID='DQS1_A_C';
NET_NAME
'M_H_CPU1_SA_DQS_DN<2>'
 '@T6G_MB_LIB.T6G(SCH_1):M_H_CPU1_SA_DQS_DN'<2>:
 C_SIGNAL='@t6g_mb_lib.t6g(sch_1):m_h_cpu1_sa_dqs_dn(2)';
NODE_NAME     U26 Y13
 '@T6G_MB_LIB.T6G(SCH_1):PAGE44_I159@PURE_QUANTA.GENOA_SP5(CHIPS)':
 'MHA_DQS_L2': CDS_PINID='MHA_DQS_L2';
NODE_NAME     J27 34
 '@T6G_MB_LIB.T6G(SCH_1):PAGE104_I238@PURE_QUANTA.SCONN288_DDR506112002KQ(CHIPS)':
 'DQS2_A_C': CDS_PINID='DQS2_A_C';
NET_NAME
'M_H_CPU1_SA_DQS_DN<3>'
 '@T6G_MB_LIB.T6G(SCH_1):M_H_CPU1_SA_DQS_DN'<3>:
 C_SIGNAL='@t6g_mb_lib.t6g(sch_1):m_h_cpu1_sa_dqs_dn(3)';
NODE_NAME     U26 AF13
 '@T6G_MB_LIB.T6G(SCH_1):PAGE44_I159@PURE_QUANTA.GENOA_SP5(CHIPS)':
 'MHA_DQS_L3': CDS_PINID='MHA_DQS_L3';
NODE_NAME     J27 45
 '@T6G_MB_LIB.T6G(SCH_1):PAGE104_I238@PURE_QUANTA.SCONN288_DDR506112002KQ(CHIPS)':
 'DQS3_A_C': CDS_PINID='DQS3_A_C';
NET_NAME
'M_H_CPU1_SA_DQS_DN<4>'
 '@T6G_MB_LIB.T6G(SCH_1):M_H_CPU1_SA_DQS_DN'<4>:
 C_SIGNAL='@t6g_mb_lib.t6g(sch_1):m_h_cpu1_sa_dqs_dn(4)';
NODE_NAME     U26 AM13
 '@T6G_MB_LIB.T6G(SCH_1):PAGE44_I159@PURE_QUANTA.GENOA_SP5(CHIPS)':
 'MHA_DQS_L4': CDS_PINID='MHA_DQS_L4';
NODE_NAME     J27 56
 '@T6G_MB_LIB.T6G(SCH_1):PAGE104_I238@PURE_QUANTA.SCONN288_DDR506112002KQ(CHIPS)':
 'DQS4_A_C': CDS_PINID='DQS4_A_C';
NET_NAME
'M_H_CPU1_SA_DQS_DN<5>'
 '@T6G_MB_LIB.T6G(SCH_1):M_H_CPU1_SA_DQS_DN'<5>:
 C_SIGNAL='@t6g_mb_lib.t6g(sch_1):m_h_cpu1_sa_dqs_dn(5)';
NODE_NAME     U26 H14
 '@T6G_MB_LIB.T6G(SCH_1):PAGE44_I159@PURE_QUANTA.GENOA_SP5(CHIPS)':
 'MHA_DQS_L5': CDS_PINID='MHA_DQS_L5';
NODE_NAME     J27 156
 '@T6G_MB_LIB.T6G(SCH_1):PAGE104_I238@PURE_QUANTA.SCONN288_DDR506112002KQ(CHIPS)':
 'DQS5_A_C||TDQS5_A_C||DQS5_A_T||TDQS5_A_T': CDS_PINID='\dqs5_a_c||tdqs5_a_c||dqs5_a_t||tdqs5_a_t\';
NET_NAME
'M_H_CPU1_SA_DQS_DN<6>'
 '@T6G_MB_LIB.T6G(SCH_1):M_H_CPU1_SA_DQS_DN'<6>:
 C_SIGNAL='@t6g_mb_lib.t6g(sch_1):m_h_cpu1_sa_dqs_dn(6)';
NODE_NAME     U26 P14
 '@T6G_MB_LIB.T6G(SCH_1):PAGE44_I159@PURE_QUANTA.GENOA_SP5(CHIPS)':
 'MHA_DQS_L6': CDS_PINID='MHA_DQS_L6';
NODE_NAME     J27 167
 '@T6G_MB_LIB.T6G(SCH_1):PAGE104_I238@PURE_QUANTA.SCONN288_DDR506112002KQ(CHIPS)':
 'DQS6_A_C||TDQS6_A_C||DQS6_A_T||TDQS6_A_T': CDS_PINID='\dqs6_a_c||tdqs6_a_c||dqs6_a_t||tdqs6_a_t\';
NET_NAME
'M_H_CPU1_SA_DQS_DN<7>'
 '@T6G_MB_LIB.T6G(SCH_1):M_H_CPU1_SA_DQS_DN'<7>:
 C_SIGNAL='@t6g_mb_lib.t6g(sch_1):m_h_cpu1_sa_dqs_dn(7)';
NODE_NAME     U26 Y14
 '@T6G_MB_LIB.T6G(SCH_1):PAGE44_I159@PURE_QUANTA.GENOA_SP5(CHIPS)':
 'MHA_DQS_L7': CDS_PINID='MHA_DQS_L7';
NODE_NAME     J27 178
 '@T6G_MB_LIB.T6G(SCH_1):PAGE104_I238@PURE_QUANTA.SCONN288_DDR506112002KQ(CHIPS)':
 'DQS7_A_C||TDQS7_A_C': CDS_PINID='\dqs7_a_c||tdqs7_a_c\';
NET_NAME
'M_H_CPU1_SA_DQS_DN<8>'
 '@T6G_MB_LIB.T6G(SCH_1):M_H_CPU1_SA_DQS_DN'<8>:
 C_SIGNAL='@t6g_mb_lib.t6g(sch_1):m_h_cpu1_sa_dqs_dn(8)';
NODE_NAME     U26 AF14
 '@T6G_MB_LIB.T6G(SCH_1):PAGE44_I159@PURE_QUANTA.GENOA_SP5(CHIPS)':
 'MHA_DQS_L8': CDS_PINID='MHA_DQS_L8';
NODE_NAME     J27 189
 '@T6G_MB_LIB.T6G(SCH_1):PAGE104_I238@PURE_QUANTA.SCONN288_DDR506112002KQ(CHIPS)':
 'DQS8_A_C||TDQS8_A_C': CDS_PINID='\dqs8_a_c||tdqs8_a_c\';
NET_NAME
'M_H_CPU1_SA_DQS_DN<9>'
 '@T6G_MB_LIB.T6G(SCH_1):M_H_CPU1_SA_DQS_DN'<9>:
 C_SIGNAL='@t6g_mb_lib.t6g(sch_1):m_h_cpu1_sa_dqs_dn(9)';
NODE_NAME     U26 AM14
 '@T6G_MB_LIB.T6G(SCH_1):PAGE44_I159@PURE_QUANTA.GENOA_SP5(CHIPS)':
 'MHA_DQS_L9': CDS_PINID='MHA_DQS_L9';
NODE_NAME     J27 200
 '@T6G_MB_LIB.T6G(SCH_1):PAGE104_I238@PURE_QUANTA.SCONN288_DDR506112002KQ(CHIPS)':
 'DQS9_A_C||TDQS9_A_C': CDS_PINID='\dqs9_a_c||tdqs9_a_c\';
NET_NAME
'M_H_CPU1_SA_DQS_DP<0>'
 '@T6G_MB_LIB.T6G(SCH_1):M_H_CPU1_SA_DQS_DP'<0>:
 C_SIGNAL='@t6g_mb_lib.t6g(sch_1):m_h_cpu1_sa_dqs_dp(0)';
NODE_NAME     U26 G12
 '@T6G_MB_LIB.T6G(SCH_1):PAGE44_I159@PURE_QUANTA.GENOA_SP5(CHIPS)':
 'MHA_DQS_H0': CDS_PINID='MHA_DQS_H0';
NODE_NAME     J27 11
 '@T6G_MB_LIB.T6G(SCH_1):PAGE104_I238@PURE_QUANTA.SCONN288_DDR506112002KQ(CHIPS)':
 'DQS0_A_T': CDS_PINID='DQS0_A_T';
NET_NAME
'M_H_CPU1_SA_DQS_DP<1>'
 '@T6G_MB_LIB.T6G(SCH_1):M_H_CPU1_SA_DQS_DP'<1>:
 C_SIGNAL='@t6g_mb_lib.t6g(sch_1):m_h_cpu1_sa_dqs_dp(1)';
NODE_NAME     U26 N12
 '@T6G_MB_LIB.T6G(SCH_1):PAGE44_I159@PURE_QUANTA.GENOA_SP5(CHIPS)':
 'MHA_DQS_H1': CDS_PINID='MHA_DQS_H1';
NODE_NAME     J27 22
 '@T6G_MB_LIB.T6G(SCH_1):PAGE104_I238@PURE_QUANTA.SCONN288_DDR506112002KQ(CHIPS)':
 'DQS1_A_T': CDS_PINID='DQS1_A_T';
NET_NAME
'M_H_CPU1_SA_DQS_DP<2>'
 '@T6G_MB_LIB.T6G(SCH_1):M_H_CPU1_SA_DQS_DP'<2>:
 C_SIGNAL='@t6g_mb_lib.t6g(sch_1):m_h_cpu1_sa_dqs_dp(2)';
NODE_NAME     U26 W12
 '@T6G_MB_LIB.T6G(SCH_1):PAGE44_I159@PURE_QUANTA.GENOA_SP5(CHIPS)':
 'MHA_DQS_H2': CDS_PINID='MHA_DQS_H2';
NODE_NAME     J27 33
 '@T6G_MB_LIB.T6G(SCH_1):PAGE104_I238@PURE_QUANTA.SCONN288_DDR506112002KQ(CHIPS)':
 'DQS2_A_T': CDS_PINID='DQS2_A_T';
NET_NAME
'M_H_CPU1_SA_DQS_DP<3>'
 '@T6G_MB_LIB.T6G(SCH_1):M_H_CPU1_SA_DQS_DP'<3>:
 C_SIGNAL='@t6g_mb_lib.t6g(sch_1):m_h_cpu1_sa_dqs_dp(3)';
NODE_NAME     U26 AE12
 '@T6G_MB_LIB.T6G(SCH_1):PAGE44_I159@PURE_QUANTA.GENOA_SP5(CHIPS)':
 'MHA_DQS_H3': CDS_PINID='MHA_DQS_H3';
NODE_NAME     J27 44
 '@T6G_MB_LIB.T6G(SCH_1):PAGE104_I238@PURE_QUANTA.SCONN288_DDR506112002KQ(CHIPS)':
 'DQS3_A_T': CDS_PINID='DQS3_A_T';
NET_NAME
'M_H_CPU1_SA_DQS_DP<4>'
 '@T6G_MB_LIB.T6G(SCH_1):M_H_CPU1_SA_DQS_DP'<4>:
 C_SIGNAL='@t6g_mb_lib.t6g(sch_1):m_h_cpu1_sa_dqs_dp(4)';
NODE_NAME     U26 AL12
 '@T6G_MB_LIB.T6G(SCH_1):PAGE44_I159@PURE_QUANTA.GENOA_SP5(CHIPS)':
 'MHA_DQS_H4': CDS_PINID='MHA_DQS_H4';
NODE_NAME     J27 55
 '@T6G_MB_LIB.T6G(SCH_1):PAGE104_I238@PURE_QUANTA.SCONN288_DDR506112002KQ(CHIPS)':
 'DQS4_A_T': CDS_PINID='DQS4_A_T';
NET_NAME
'M_H_CPU1_SA_DQS_DP<5>'
 '@T6G_MB_LIB.T6G(SCH_1):M_H_CPU1_SA_DQS_DP'<5>:
 C_SIGNAL='@t6g_mb_lib.t6g(sch_1):m_h_cpu1_sa_dqs_dp(5)';
NODE_NAME     U26 J14
 '@T6G_MB_LIB.T6G(SCH_1):PAGE44_I159@PURE_QUANTA.GENOA_SP5(CHIPS)':
 'MHA_DQS_H5': CDS_PINID='MHA_DQS_H5';
NODE_NAME     J27 157
 '@T6G_MB_LIB.T6G(SCH_1):PAGE104_I238@PURE_QUANTA.SCONN288_DDR506112002KQ(CHIPS)':
 'DQS5_A_T||TDQS5_A_T': CDS_PINID='\dqs5_a_t||tdqs5_a_t\';
NET_NAME
'M_H_CPU1_SA_DQS_DP<6>'
 '@T6G_MB_LIB.T6G(SCH_1):M_H_CPU1_SA_DQS_DP'<6>:
 C_SIGNAL='@t6g_mb_lib.t6g(sch_1):m_h_cpu1_sa_dqs_dp(6)';
NODE_NAME     U26 R14
 '@T6G_MB_LIB.T6G(SCH_1):PAGE44_I159@PURE_QUANTA.GENOA_SP5(CHIPS)':
 'MHA_DQS_H6': CDS_PINID='MHA_DQS_H6';
NODE_NAME     J27 168
 '@T6G_MB_LIB.T6G(SCH_1):PAGE104_I238@PURE_QUANTA.SCONN288_DDR506112002KQ(CHIPS)':
 'DQS6_A_T||TDQS6_A_T': CDS_PINID='\dqs6_a_t||tdqs6_a_t\';
NET_NAME
'M_H_CPU1_SA_DQS_DP<7>'
 '@T6G_MB_LIB.T6G(SCH_1):M_H_CPU1_SA_DQS_DP'<7>:
 C_SIGNAL='@t6g_mb_lib.t6g(sch_1):m_h_cpu1_sa_dqs_dp(7)';
NODE_NAME     U26 AA14
 '@T6G_MB_LIB.T6G(SCH_1):PAGE44_I159@PURE_QUANTA.GENOA_SP5(CHIPS)':
 'MHA_DQS_H7': CDS_PINID='MHA_DQS_H7';
NODE_NAME     J27 179
 '@T6G_MB_LIB.T6G(SCH_1):PAGE104_I238@PURE_QUANTA.SCONN288_DDR506112002KQ(CHIPS)':
 'DQS7_A_T||TDQS7_A_T': CDS_PINID='\dqs7_a_t||tdqs7_a_t\';
NET_NAME
'M_H_CPU1_SA_DQS_DP<8>'
 '@T6G_MB_LIB.T6G(SCH_1):M_H_CPU1_SA_DQS_DP'<8>:
 C_SIGNAL='@t6g_mb_lib.t6g(sch_1):m_h_cpu1_sa_dqs_dp(8)';
NODE_NAME     U26 AG14
 '@T6G_MB_LIB.T6G(SCH_1):PAGE44_I159@PURE_QUANTA.GENOA_SP5(CHIPS)':
 'MHA_DQS_H8': CDS_PINID='MHA_DQS_H8';
NODE_NAME     J27 190
 '@T6G_MB_LIB.T6G(SCH_1):PAGE104_I238@PURE_QUANTA.SCONN288_DDR506112002KQ(CHIPS)':
 'DQS8_A_T||TDQS8_A_T': CDS_PINID='\dqs8_a_t||tdqs8_a_t\';
NET_NAME
'M_H_CPU1_SA_DQS_DP<9>'
 '@T6G_MB_LIB.T6G(SCH_1):M_H_CPU1_SA_DQS_DP'<9>:
 C_SIGNAL='@t6g_mb_lib.t6g(sch_1):m_h_cpu1_sa_dqs_dp(9)';
NODE_NAME     U26 AN14
 '@T6G_MB_LIB.T6G(SCH_1):PAGE44_I159@PURE_QUANTA.GENOA_SP5(CHIPS)':
 'MHA_DQS_H9': CDS_PINID='MHA_DQS_H9';
NODE_NAME     J27 201
 '@T6G_MB_LIB.T6G(SCH_1):PAGE104_I238@PURE_QUANTA.SCONN288_DDR506112002KQ(CHIPS)':
 'DQS9_A_T||TDQS9_A_T': CDS_PINID='\dqs9_a_t||tdqs9_a_t\';
NET_NAME
'M_H_CPU1_SA_PAR'
 '@T6G_MB_LIB.T6G(SCH_1):M_H_CPU1_SA_PAR':
 C_SIGNAL='@t6g_mb_lib.t6g(sch_1):m_h_cpu1_sa_par';
NODE_NAME     U26 BC14
 '@T6G_MB_LIB.T6G(SCH_1):PAGE44_I159@PURE_QUANTA.GENOA_SP5(CHIPS)':
 'MHA_PAR': CDS_PINID='MHA_PAR';
NODE_NAME     J27 74
 '@T6G_MB_LIB.T6G(SCH_1):PAGE104_I22@PURE_QUANTA.SCONN288_DDR506112002KQ(CHIPS)':
 'PAR_A': CDS_PINID='PAR_A';
NET_NAME
'M_H_CPU1_SA_RSP<0>'
 '@T6G_MB_LIB.T6G(SCH_1):M_H_CPU1_SA_RSP'<0>:
 C_SIGNAL='@t6g_mb_lib.t6g(sch_1):m_h_cpu1_sa_rsp(0)';
NODE_NAME     U26 BN14
 '@T6G_MB_LIB.T6G(SCH_1):PAGE44_I159@PURE_QUANTA.GENOA_SP5(CHIPS)':
 'MHA0_RSP_L': CDS_PINID='MHA0_RSP_L';
NODE_NAME     J27 86
 '@T6G_MB_LIB.T6G(SCH_1):PAGE104_I22@PURE_QUANTA.SCONN288_DDR506112002KQ(CHIPS)':
 'LBD||RSP_A_N': CDS_PINID='\lbd||rsp_a_n\';
NET_NAME
'M_H_CPU1_SB_CA<0>'
 '@T6G_MB_LIB.T6G(SCH_1):M_H_CPU1_SB_CA'<0>:
 C_SIGNAL='@t6g_mb_lib.t6g(sch_1):m_h_cpu1_sb_ca(0)';
NODE_NAME     U26 BG14
 '@T6G_MB_LIB.T6G(SCH_1):PAGE44_I159@PURE_QUANTA.GENOA_SP5(CHIPS)':
 'MHB_CA0': CDS_PINID='MHB_CA0';
NODE_NAME     J27 76
 '@T6G_MB_LIB.T6G(SCH_1):PAGE104_I22@PURE_QUANTA.SCONN288_DDR506112002KQ(CHIPS)':
 'CA0_B': CDS_PINID='CA0_B';
NET_NAME
'M_H_CPU1_SB_CA<1>'
 '@T6G_MB_LIB.T6G(SCH_1):M_H_CPU1_SB_CA'<1>:
 C_SIGNAL='@t6g_mb_lib.t6g(sch_1):m_h_cpu1_sb_ca(1)';
NODE_NAME     U26 BH14
 '@T6G_MB_LIB.T6G(SCH_1):PAGE44_I159@PURE_QUANTA.GENOA_SP5(CHIPS)':
 'MHB_CA1': CDS_PINID='MHB_CA1';
NODE_NAME     J27 221
 '@T6G_MB_LIB.T6G(SCH_1):PAGE104_I22@PURE_QUANTA.SCONN288_DDR506112002KQ(CHIPS)':
 'CA1_B': CDS_PINID='CA1_B';
NET_NAME
'M_H_CPU1_SB_CA<2>'
 '@T6G_MB_LIB.T6G(SCH_1):M_H_CPU1_SB_CA'<2>:
 C_SIGNAL='@t6g_mb_lib.t6g(sch_1):m_h_cpu1_sb_ca(2)';
NODE_NAME     U26 BH13
 '@T6G_MB_LIB.T6G(SCH_1):PAGE44_I159@PURE_QUANTA.GENOA_SP5(CHIPS)':
 'MHB_CA2': CDS_PINID='MHB_CA2';
NODE_NAME     J27 78
 '@T6G_MB_LIB.T6G(SCH_1):PAGE104_I22@PURE_QUANTA.SCONN288_DDR506112002KQ(CHIPS)':
 'CA2_B': CDS_PINID='CA2_B';
NET_NAME
'M_H_CPU1_SB_CA<3>'
 '@T6G_MB_LIB.T6G(SCH_1):M_H_CPU1_SB_CA'<3>:
 C_SIGNAL='@t6g_mb_lib.t6g(sch_1):m_h_cpu1_sb_ca(3)';
NODE_NAME     U26 BJ12
 '@T6G_MB_LIB.T6G(SCH_1):PAGE44_I159@PURE_QUANTA.GENOA_SP5(CHIPS)':
 'MHB_CA3': CDS_PINID='MHB_CA3';
NODE_NAME     J27 223
 '@T6G_MB_LIB.T6G(SCH_1):PAGE104_I22@PURE_QUANTA.SCONN288_DDR506112002KQ(CHIPS)':
 'CA3_B': CDS_PINID='CA3_B';
NET_NAME
'M_H_CPU1_SB_CA<4>'
 '@T6G_MB_LIB.T6G(SCH_1):M_H_CPU1_SB_CA'<4>:
 C_SIGNAL='@t6g_mb_lib.t6g(sch_1):m_h_cpu1_sb_ca(4)';
NODE_NAME     U26 BJ14
 '@T6G_MB_LIB.T6G(SCH_1):PAGE44_I159@PURE_QUANTA.GENOA_SP5(CHIPS)':
 'MHB_CA4': CDS_PINID='MHB_CA4';
NODE_NAME     J27 80
 '@T6G_MB_LIB.T6G(SCH_1):PAGE104_I22@PURE_QUANTA.SCONN288_DDR506112002KQ(CHIPS)':
 'CA4_B': CDS_PINID='CA4_B';
NET_NAME
'M_H_CPU1_SB_CA<5>'
 '@T6G_MB_LIB.T6G(SCH_1):M_H_CPU1_SB_CA'<5>:
 C_SIGNAL='@t6g_mb_lib.t6g(sch_1):m_h_cpu1_sb_ca(5)';
NODE_NAME     U26 BK14
 '@T6G_MB_LIB.T6G(SCH_1):PAGE44_I159@PURE_QUANTA.GENOA_SP5(CHIPS)':
 'MHB_CA5': CDS_PINID='MHB_CA5';
NODE_NAME     J27 225
 '@T6G_MB_LIB.T6G(SCH_1):PAGE104_I22@PURE_QUANTA.SCONN288_DDR506112002KQ(CHIPS)':
 'CA5_B': CDS_PINID='CA5_B';
NET_NAME
'M_H_CPU1_SB_CA<6>'
 '@T6G_MB_LIB.T6G(SCH_1):M_H_CPU1_SB_CA'<6>:
 C_SIGNAL='@t6g_mb_lib.t6g(sch_1):m_h_cpu1_sb_ca(6)';
NODE_NAME     U26 BK13
 '@T6G_MB_LIB.T6G(SCH_1):PAGE44_I159@PURE_QUANTA.GENOA_SP5(CHIPS)':
 'MHB_CA6': CDS_PINID='MHB_CA6';
NODE_NAME     J27 82
 '@T6G_MB_LIB.T6G(SCH_1):PAGE104_I22@PURE_QUANTA.SCONN288_DDR506112002KQ(CHIPS)':
 'CA6_B': CDS_PINID='CA6_B';
NET_NAME
'M_H_CPU1_SB_CB<0>'
 '@T6G_MB_LIB.T6G(SCH_1):M_H_CPU1_SB_CB'<0>:
 C_SIGNAL='@t6g_mb_lib.t6g(sch_1):m_h_cpu1_sb_cb(0)';
NODE_NAME     U26 BY13
 '@T6G_MB_LIB.T6G(SCH_1):PAGE44_I159@PURE_QUANTA.GENOA_SP5(CHIPS)':
 'MHB_CHECK0': CDS_PINID='MHB_CHECK0';
NODE_NAME     J27 96
 '@T6G_MB_LIB.T6G(SCH_1):PAGE104_I22@PURE_QUANTA.SCONN288_DDR506112002KQ(CHIPS)':
 'CB0_B': CDS_PINID='CB0_B';
NET_NAME
'M_H_CPU1_SB_CB<1>'
 '@T6G_MB_LIB.T6G(SCH_1):M_H_CPU1_SB_CB'<1>:
 C_SIGNAL='@t6g_mb_lib.t6g(sch_1):m_h_cpu1_sb_cb(1)';
NODE_NAME     U26 CA14
 '@T6G_MB_LIB.T6G(SCH_1):PAGE44_I159@PURE_QUANTA.GENOA_SP5(CHIPS)':
 'MHB_CHECK1': CDS_PINID='MHB_CHECK1';
NODE_NAME     J27 98
 '@T6G_MB_LIB.T6G(SCH_1):PAGE104_I22@PURE_QUANTA.SCONN288_DDR506112002KQ(CHIPS)':
 'CB1_B': CDS_PINID='CB1_B';
NET_NAME
'M_H_CPU1_SB_CB<2>'
 '@T6G_MB_LIB.T6G(SCH_1):M_H_CPU1_SB_CB'<2>:
 C_SIGNAL='@t6g_mb_lib.t6g(sch_1):m_h_cpu1_sb_cb(2)';
NODE_NAME     U26 CA12
 '@T6G_MB_LIB.T6G(SCH_1):PAGE44_I159@PURE_QUANTA.GENOA_SP5(CHIPS)':
 'MHB_CHECK2': CDS_PINID='MHB_CHECK2';
NODE_NAME     J27 241
 '@T6G_MB_LIB.T6G(SCH_1):PAGE104_I22@PURE_QUANTA.SCONN288_DDR506112002KQ(CHIPS)':
 'CB2_B': CDS_PINID='CB2_B';
NET_NAME
'M_H_CPU1_SB_CB<3>'
 '@T6G_MB_LIB.T6G(SCH_1):M_H_CPU1_SB_CB'<3>:
 C_SIGNAL='@t6g_mb_lib.t6g(sch_1):m_h_cpu1_sb_cb(3)';
NODE_NAME     U26 CB14
 '@T6G_MB_LIB.T6G(SCH_1):PAGE44_I159@PURE_QUANTA.GENOA_SP5(CHIPS)':
 'MHB_CHECK3': CDS_PINID='MHB_CHECK3';
NODE_NAME     J27 243
 '@T6G_MB_LIB.T6G(SCH_1):PAGE104_I22@PURE_QUANTA.SCONN288_DDR506112002KQ(CHIPS)':
 'CB3_B': CDS_PINID='CB3_B';
NET_NAME
'M_H_CPU1_SB_CB<4>'
 '@T6G_MB_LIB.T6G(SCH_1):M_H_CPU1_SB_CB'<4>:
 C_SIGNAL='@t6g_mb_lib.t6g(sch_1):m_h_cpu1_sb_cb(4)';
NODE_NAME     U26 BT13
 '@T6G_MB_LIB.T6G(SCH_1):PAGE44_I159@PURE_QUANTA.GENOA_SP5(CHIPS)':
 'MHB_CHECK4': CDS_PINID='MHB_CHECK4';
NODE_NAME     J27 89
 '@T6G_MB_LIB.T6G(SCH_1):PAGE104_I22@PURE_QUANTA.SCONN288_DDR506112002KQ(CHIPS)':
 'CB4_B': CDS_PINID='CB4_B';
NET_NAME
'M_H_CPU1_SB_CB<5>'
 '@T6G_MB_LIB.T6G(SCH_1):M_H_CPU1_SB_CB'<5>:
 C_SIGNAL='@t6g_mb_lib.t6g(sch_1):m_h_cpu1_sb_cb(5)';
NODE_NAME     U26 BU14
 '@T6G_MB_LIB.T6G(SCH_1):PAGE44_I159@PURE_QUANTA.GENOA_SP5(CHIPS)':
 'MHB_CHECK5': CDS_PINID='MHB_CHECK5';
NODE_NAME     J27 91
 '@T6G_MB_LIB.T6G(SCH_1):PAGE104_I22@PURE_QUANTA.SCONN288_DDR506112002KQ(CHIPS)':
 'CB5_B': CDS_PINID='CB5_B';
NET_NAME
'M_H_CPU1_SB_CB<6>'
 '@T6G_MB_LIB.T6G(SCH_1):M_H_CPU1_SB_CB'<6>:
 C_SIGNAL='@t6g_mb_lib.t6g(sch_1):m_h_cpu1_sb_cb(6)';
NODE_NAME     U26 BU12
 '@T6G_MB_LIB.T6G(SCH_1):PAGE44_I159@PURE_QUANTA.GENOA_SP5(CHIPS)':
 'MHB_CHECK6': CDS_PINID='MHB_CHECK6';
NODE_NAME     J27 234
 '@T6G_MB_LIB.T6G(SCH_1):PAGE104_I22@PURE_QUANTA.SCONN288_DDR506112002KQ(CHIPS)':
 'CB6_B': CDS_PINID='CB6_B';
NET_NAME
'M_H_CPU1_SB_CB<7>'
 '@T6G_MB_LIB.T6G(SCH_1):M_H_CPU1_SB_CB'<7>:
 C_SIGNAL='@t6g_mb_lib.t6g(sch_1):m_h_cpu1_sb_cb(7)';
NODE_NAME     U26 BV14
 '@T6G_MB_LIB.T6G(SCH_1):PAGE44_I159@PURE_QUANTA.GENOA_SP5(CHIPS)':
 'MHB_CHECK7': CDS_PINID='MHB_CHECK7';
NODE_NAME     J27 236
 '@T6G_MB_LIB.T6G(SCH_1):PAGE104_I22@PURE_QUANTA.SCONN288_DDR506112002KQ(CHIPS)':
 'CB7_B': CDS_PINID='CB7_B';
NET_NAME
'M_H_CPU1_SB_CS_N<0>'
 '@T6G_MB_LIB.T6G(SCH_1):M_H_CPU1_SB_CS_N'<0>:
 C_SIGNAL='@t6g_mb_lib.t6g(sch_1):m_h_cpu1_sb_cs_n(0)';
NODE_NAME     U26 BM14
 '@T6G_MB_LIB.T6G(SCH_1):PAGE44_I159@PURE_QUANTA.GENOA_SP5(CHIPS)':
 'MHB0_CS_L0': CDS_PINID='MHB0_CS_L0';
NODE_NAME     J27 84
 '@T6G_MB_LIB.T6G(SCH_1):PAGE104_I22@PURE_QUANTA.SCONN288_DDR506112002KQ(CHIPS)':
 'CS0_B_N': CDS_PINID='CS0_B_N';
NET_NAME
'M_H_CPU1_SB_CS_N<1>'
 '@T6G_MB_LIB.T6G(SCH_1):M_H_CPU1_SB_CS_N'<1>:
 C_SIGNAL='@t6g_mb_lib.t6g(sch_1):m_h_cpu1_sb_cs_n(1)';
NODE_NAME     U26 BN12
 '@T6G_MB_LIB.T6G(SCH_1):PAGE44_I159@PURE_QUANTA.GENOA_SP5(CHIPS)':
 'MHB0_CS_L1': CDS_PINID='MHB0_CS_L1';
NODE_NAME     J27 229
 '@T6G_MB_LIB.T6G(SCH_1):PAGE104_I22@PURE_QUANTA.SCONN288_DDR506112002KQ(CHIPS)':
 'CS1_B_N': CDS_PINID='CS1_B_N';
NET_NAME
'M_H_CPU1_SB_DQ<0>'
 '@T6G_MB_LIB.T6G(SCH_1):M_H_CPU1_SB_DQ'<0>:
 C_SIGNAL='@t6g_mb_lib.t6g(sch_1):m_h_cpu1_sb_dq(0)';
NODE_NAME     U26 CB13
 '@T6G_MB_LIB.T6G(SCH_1):PAGE44_I159@PURE_QUANTA.GENOA_SP5(CHIPS)':
 'MHB_DATA0': CDS_PINID='MHB_DATA0';
NODE_NAME     J27 100
 '@T6G_MB_LIB.T6G(SCH_1):PAGE104_I22@PURE_QUANTA.SCONN288_DDR506112002KQ(CHIPS)':
 'DQ0_B': CDS_PINID='DQ0_B';
NET_NAME
'M_H_CPU1_SB_DQ<10>'
 '@T6G_MB_LIB.T6G(SCH_1):M_H_CPU1_SB_DQ'<10>:
 C_SIGNAL='@t6g_mb_lib.t6g(sch_1):m_h_cpu1_sb_dq(10)';
NODE_NAME     U26 CJ12
 '@T6G_MB_LIB.T6G(SCH_1):PAGE44_I159@PURE_QUANTA.GENOA_SP5(CHIPS)':
 'MHB_DATA10': CDS_PINID='MHB_DATA10';
NODE_NAME     J27 256
 '@T6G_MB_LIB.T6G(SCH_1):PAGE104_I22@PURE_QUANTA.SCONN288_DDR506112002KQ(CHIPS)':
 'DQ10_B': CDS_PINID='DQ10_B';
NET_NAME
'M_H_CPU1_SB_DQ<11>'
 '@T6G_MB_LIB.T6G(SCH_1):M_H_CPU1_SB_DQ'<11>:
 C_SIGNAL='@t6g_mb_lib.t6g(sch_1):m_h_cpu1_sb_dq(11)';
NODE_NAME     U26 CK14
 '@T6G_MB_LIB.T6G(SCH_1):PAGE44_I159@PURE_QUANTA.GENOA_SP5(CHIPS)':
 'MHB_DATA11': CDS_PINID='MHB_DATA11';
NODE_NAME     J27 258
 '@T6G_MB_LIB.T6G(SCH_1):PAGE104_I22@PURE_QUANTA.SCONN288_DDR506112002KQ(CHIPS)':
 'DQ11_B': CDS_PINID='DQ11_B';
NET_NAME
'M_H_CPU1_SB_DQ<12>'
 '@T6G_MB_LIB.T6G(SCH_1):M_H_CPU1_SB_DQ'<12>:
 C_SIGNAL='@t6g_mb_lib.t6g(sch_1):m_h_cpu1_sb_dq(12)';
NODE_NAME     U26 CM13
 '@T6G_MB_LIB.T6G(SCH_1):PAGE44_I159@PURE_QUANTA.GENOA_SP5(CHIPS)':
 'MHB_DATA12': CDS_PINID='MHB_DATA12';
NODE_NAME     J27 118
 '@T6G_MB_LIB.T6G(SCH_1):PAGE104_I22@PURE_QUANTA.SCONN288_DDR506112002KQ(CHIPS)':
 'DQ12_B': CDS_PINID='DQ12_B';
NET_NAME
'M_H_CPU1_SB_DQ<13>'
 '@T6G_MB_LIB.T6G(SCH_1):M_H_CPU1_SB_DQ'<13>:
 C_SIGNAL='@t6g_mb_lib.t6g(sch_1):m_h_cpu1_sb_dq(13)';
NODE_NAME     U26 CN14
 '@T6G_MB_LIB.T6G(SCH_1):PAGE44_I159@PURE_QUANTA.GENOA_SP5(CHIPS)':
 'MHB_DATA13': CDS_PINID='MHB_DATA13';
NODE_NAME     J27 120
 '@T6G_MB_LIB.T6G(SCH_1):PAGE104_I22@PURE_QUANTA.SCONN288_DDR506112002KQ(CHIPS)':
 'DQ13_B': CDS_PINID='DQ13_B';
NET_NAME
'M_H_CPU1_SB_DQ<14>'
 '@T6G_MB_LIB.T6G(SCH_1):M_H_CPU1_SB_DQ'<14>:
 C_SIGNAL='@t6g_mb_lib.t6g(sch_1):m_h_cpu1_sb_dq(14)';
NODE_NAME     U26 CN12
 '@T6G_MB_LIB.T6G(SCH_1):PAGE44_I159@PURE_QUANTA.GENOA_SP5(CHIPS)':
 'MHB_DATA14': CDS_PINID='MHB_DATA14';
NODE_NAME     J27 263
 '@T6G_MB_LIB.T6G(SCH_1):PAGE104_I22@PURE_QUANTA.SCONN288_DDR506112002KQ(CHIPS)':
 'DQ14_B': CDS_PINID='DQ14_B';
NET_NAME
'M_H_CPU1_SB_DQ<15>'
 '@T6G_MB_LIB.T6G(SCH_1):M_H_CPU1_SB_DQ'<15>:
 C_SIGNAL='@t6g_mb_lib.t6g(sch_1):m_h_cpu1_sb_dq(15)';
NODE_NAME     U26 CP14
 '@T6G_MB_LIB.T6G(SCH_1):PAGE44_I159@PURE_QUANTA.GENOA_SP5(CHIPS)':
 'MHB_DATA15': CDS_PINID='MHB_DATA15';
NODE_NAME     J27 265
 '@T6G_MB_LIB.T6G(SCH_1):PAGE104_I22@PURE_QUANTA.SCONN288_DDR506112002KQ(CHIPS)':
 'DQ15_B': CDS_PINID='DQ15_B';
NET_NAME
'M_H_CPU1_SB_DQ<16>'
 '@T6G_MB_LIB.T6G(SCH_1):M_H_CPU1_SB_DQ'<16>:
 C_SIGNAL='@t6g_mb_lib.t6g(sch_1):m_h_cpu1_sb_dq(16)';
NODE_NAME     U26 CP13
 '@T6G_MB_LIB.T6G(SCH_1):PAGE44_I159@PURE_QUANTA.GENOA_SP5(CHIPS)':
 'MHB_DATA16': CDS_PINID='MHB_DATA16';
NODE_NAME     J27 122
 '@T6G_MB_LIB.T6G(SCH_1):PAGE104_I22@PURE_QUANTA.SCONN288_DDR506112002KQ(CHIPS)':
 'DQ16_B': CDS_PINID='DQ16_B';
NET_NAME
'M_H_CPU1_SB_DQ<17>'
 '@T6G_MB_LIB.T6G(SCH_1):M_H_CPU1_SB_DQ'<17>:
 C_SIGNAL='@t6g_mb_lib.t6g(sch_1):m_h_cpu1_sb_dq(17)';
NODE_NAME     U26 CR14
 '@T6G_MB_LIB.T6G(SCH_1):PAGE44_I159@PURE_QUANTA.GENOA_SP5(CHIPS)':
 'MHB_DATA17': CDS_PINID='MHB_DATA17';
NODE_NAME     J27 124
 '@T6G_MB_LIB.T6G(SCH_1):PAGE104_I22@PURE_QUANTA.SCONN288_DDR506112002KQ(CHIPS)':
 'DQ17_B': CDS_PINID='DQ17_B';
NET_NAME
'M_H_CPU1_SB_DQ<18>'
 '@T6G_MB_LIB.T6G(SCH_1):M_H_CPU1_SB_DQ'<18>:
 C_SIGNAL='@t6g_mb_lib.t6g(sch_1):m_h_cpu1_sb_dq(18)';
NODE_NAME     U26 CR12
 '@T6G_MB_LIB.T6G(SCH_1):PAGE44_I159@PURE_QUANTA.GENOA_SP5(CHIPS)':
 'MHB_DATA18': CDS_PINID='MHB_DATA18';
NODE_NAME     J27 267
 '@T6G_MB_LIB.T6G(SCH_1):PAGE104_I22@PURE_QUANTA.SCONN288_DDR506112002KQ(CHIPS)':
 'DQ18_B': CDS_PINID='DQ18_B';
NET_NAME
'M_H_CPU1_SB_DQ<19>'
 '@T6G_MB_LIB.T6G(SCH_1):M_H_CPU1_SB_DQ'<19>:
 C_SIGNAL='@t6g_mb_lib.t6g(sch_1):m_h_cpu1_sb_dq(19)';
NODE_NAME     U26 CT14
 '@T6G_MB_LIB.T6G(SCH_1):PAGE44_I159@PURE_QUANTA.GENOA_SP5(CHIPS)':
 'MHB_DATA19': CDS_PINID='MHB_DATA19';
NODE_NAME     J27 269
 '@T6G_MB_LIB.T6G(SCH_1):PAGE104_I22@PURE_QUANTA.SCONN288_DDR506112002KQ(CHIPS)':
 'DQ19_B': CDS_PINID='DQ19_B';
NET_NAME
'M_H_CPU1_SB_DQ<1>'
 '@T6G_MB_LIB.T6G(SCH_1):M_H_CPU1_SB_DQ'<1>:
 C_SIGNAL='@t6g_mb_lib.t6g(sch_1):m_h_cpu1_sb_dq(1)';
NODE_NAME     U26 CC14
 '@T6G_MB_LIB.T6G(SCH_1):PAGE44_I159@PURE_QUANTA.GENOA_SP5(CHIPS)':
 'MHB_DATA1': CDS_PINID='MHB_DATA1';
NODE_NAME     J27 102
 '@T6G_MB_LIB.T6G(SCH_1):PAGE104_I22@PURE_QUANTA.SCONN288_DDR506112002KQ(CHIPS)':
 'DQ1_B': CDS_PINID='DQ1_B';
NET_NAME
'M_H_CPU1_SB_DQ<20>'
 '@T6G_MB_LIB.T6G(SCH_1):M_H_CPU1_SB_DQ'<20>:
 C_SIGNAL='@t6g_mb_lib.t6g(sch_1):m_h_cpu1_sb_dq(20)';
NODE_NAME     U26 CV13
 '@T6G_MB_LIB.T6G(SCH_1):PAGE44_I159@PURE_QUANTA.GENOA_SP5(CHIPS)':
 'MHB_DATA20': CDS_PINID='MHB_DATA20';
NODE_NAME     J27 129
 '@T6G_MB_LIB.T6G(SCH_1):PAGE104_I22@PURE_QUANTA.SCONN288_DDR506112002KQ(CHIPS)':
 'DQ20_B': CDS_PINID='DQ20_B';
NET_NAME
'M_H_CPU1_SB_DQ<21>'
 '@T6G_MB_LIB.T6G(SCH_1):M_H_CPU1_SB_DQ'<21>:
 C_SIGNAL='@t6g_mb_lib.t6g(sch_1):m_h_cpu1_sb_dq(21)';
NODE_NAME     U26 CW14
 '@T6G_MB_LIB.T6G(SCH_1):PAGE44_I159@PURE_QUANTA.GENOA_SP5(CHIPS)':
 'MHB_DATA21': CDS_PINID='MHB_DATA21';
NODE_NAME     J27 131
 '@T6G_MB_LIB.T6G(SCH_1):PAGE104_I22@PURE_QUANTA.SCONN288_DDR506112002KQ(CHIPS)':
 'DQ21_B': CDS_PINID='DQ21_B';
NET_NAME
'M_H_CPU1_SB_DQ<22>'
 '@T6G_MB_LIB.T6G(SCH_1):M_H_CPU1_SB_DQ'<22>:
 C_SIGNAL='@t6g_mb_lib.t6g(sch_1):m_h_cpu1_sb_dq(22)';
NODE_NAME     U26 CW12
 '@T6G_MB_LIB.T6G(SCH_1):PAGE44_I159@PURE_QUANTA.GENOA_SP5(CHIPS)':
 'MHB_DATA22': CDS_PINID='MHB_DATA22';
NODE_NAME     J27 274
 '@T6G_MB_LIB.T6G(SCH_1):PAGE104_I22@PURE_QUANTA.SCONN288_DDR506112002KQ(CHIPS)':
 'DQ22_B': CDS_PINID='DQ22_B';
NET_NAME
'M_H_CPU1_SB_DQ<23>'
 '@T6G_MB_LIB.T6G(SCH_1):M_H_CPU1_SB_DQ'<23>:
 C_SIGNAL='@t6g_mb_lib.t6g(sch_1):m_h_cpu1_sb_dq(23)';
NODE_NAME     U26 CY14
 '@T6G_MB_LIB.T6G(SCH_1):PAGE44_I159@PURE_QUANTA.GENOA_SP5(CHIPS)':
 'MHB_DATA23': CDS_PINID='MHB_DATA23';
NODE_NAME     J27 276
 '@T6G_MB_LIB.T6G(SCH_1):PAGE104_I22@PURE_QUANTA.SCONN288_DDR506112002KQ(CHIPS)':
 'DQ23_B': CDS_PINID='DQ23_B';
NET_NAME
'M_H_CPU1_SB_DQ<24>'
 '@T6G_MB_LIB.T6G(SCH_1):M_H_CPU1_SB_DQ'<24>:
 C_SIGNAL='@t6g_mb_lib.t6g(sch_1):m_h_cpu1_sb_dq(24)';
NODE_NAME     U26 CY13
 '@T6G_MB_LIB.T6G(SCH_1):PAGE44_I159@PURE_QUANTA.GENOA_SP5(CHIPS)':
 'MHB_DATA24': CDS_PINID='MHB_DATA24';
NODE_NAME     J27 133
 '@T6G_MB_LIB.T6G(SCH_1):PAGE104_I22@PURE_QUANTA.SCONN288_DDR506112002KQ(CHIPS)':
 'DQ24_B': CDS_PINID='DQ24_B';
NET_NAME
'M_H_CPU1_SB_DQ<25>'
 '@T6G_MB_LIB.T6G(SCH_1):M_H_CPU1_SB_DQ'<25>:
 C_SIGNAL='@t6g_mb_lib.t6g(sch_1):m_h_cpu1_sb_dq(25)';
NODE_NAME     U26 DA14
 '@T6G_MB_LIB.T6G(SCH_1):PAGE44_I159@PURE_QUANTA.GENOA_SP5(CHIPS)':
 'MHB_DATA25': CDS_PINID='MHB_DATA25';
NODE_NAME     J27 135
 '@T6G_MB_LIB.T6G(SCH_1):PAGE104_I22@PURE_QUANTA.SCONN288_DDR506112002KQ(CHIPS)':
 'DQ25_B': CDS_PINID='DQ25_B';
NET_NAME
'M_H_CPU1_SB_DQ<26>'
 '@T6G_MB_LIB.T6G(SCH_1):M_H_CPU1_SB_DQ'<26>:
 C_SIGNAL='@t6g_mb_lib.t6g(sch_1):m_h_cpu1_sb_dq(26)';
NODE_NAME     U26 DA12
 '@T6G_MB_LIB.T6G(SCH_1):PAGE44_I159@PURE_QUANTA.GENOA_SP5(CHIPS)':
 'MHB_DATA26': CDS_PINID='MHB_DATA26';
NODE_NAME     J27 278
 '@T6G_MB_LIB.T6G(SCH_1):PAGE104_I22@PURE_QUANTA.SCONN288_DDR506112002KQ(CHIPS)':
 'DQ26_B': CDS_PINID='DQ26_B';
NET_NAME
'M_H_CPU1_SB_DQ<27>'
 '@T6G_MB_LIB.T6G(SCH_1):M_H_CPU1_SB_DQ'<27>:
 C_SIGNAL='@t6g_mb_lib.t6g(sch_1):m_h_cpu1_sb_dq(27)';
NODE_NAME     U26 DB14
 '@T6G_MB_LIB.T6G(SCH_1):PAGE44_I159@PURE_QUANTA.GENOA_SP5(CHIPS)':
 'MHB_DATA27': CDS_PINID='MHB_DATA27';
NODE_NAME     J27 280
 '@T6G_MB_LIB.T6G(SCH_1):PAGE104_I22@PURE_QUANTA.SCONN288_DDR506112002KQ(CHIPS)':
 'DQ27_B': CDS_PINID='DQ27_B';
NET_NAME
'M_H_CPU1_SB_DQ<28>'
 '@T6G_MB_LIB.T6G(SCH_1):M_H_CPU1_SB_DQ'<28>:
 C_SIGNAL='@t6g_mb_lib.t6g(sch_1):m_h_cpu1_sb_dq(28)';
NODE_NAME     U26 DD13
 '@T6G_MB_LIB.T6G(SCH_1):PAGE44_I159@PURE_QUANTA.GENOA_SP5(CHIPS)':
 'MHB_DATA28': CDS_PINID='MHB_DATA28';
NODE_NAME     J27 140
 '@T6G_MB_LIB.T6G(SCH_1):PAGE104_I22@PURE_QUANTA.SCONN288_DDR506112002KQ(CHIPS)':
 'DQ28_B': CDS_PINID='DQ28_B';
NET_NAME
'M_H_CPU1_SB_DQ<29>'
 '@T6G_MB_LIB.T6G(SCH_1):M_H_CPU1_SB_DQ'<29>:
 C_SIGNAL='@t6g_mb_lib.t6g(sch_1):m_h_cpu1_sb_dq(29)';
NODE_NAME     U26 DE14
 '@T6G_MB_LIB.T6G(SCH_1):PAGE44_I159@PURE_QUANTA.GENOA_SP5(CHIPS)':
 'MHB_DATA29': CDS_PINID='MHB_DATA29';
NODE_NAME     J27 142
 '@T6G_MB_LIB.T6G(SCH_1):PAGE104_I22@PURE_QUANTA.SCONN288_DDR506112002KQ(CHIPS)':
 'DQ29_B': CDS_PINID='DQ29_B';
NET_NAME
'M_H_CPU1_SB_DQ<2>'
 '@T6G_MB_LIB.T6G(SCH_1):M_H_CPU1_SB_DQ'<2>:
 C_SIGNAL='@t6g_mb_lib.t6g(sch_1):m_h_cpu1_sb_dq(2)';
NODE_NAME     U26 CC12
 '@T6G_MB_LIB.T6G(SCH_1):PAGE44_I159@PURE_QUANTA.GENOA_SP5(CHIPS)':
 'MHB_DATA2': CDS_PINID='MHB_DATA2';
NODE_NAME     J27 245
 '@T6G_MB_LIB.T6G(SCH_1):PAGE104_I22@PURE_QUANTA.SCONN288_DDR506112002KQ(CHIPS)':
 'DQ2_B': CDS_PINID='DQ2_B';
NET_NAME
'M_H_CPU1_SB_DQ<30>'
 '@T6G_MB_LIB.T6G(SCH_1):M_H_CPU1_SB_DQ'<30>:
 C_SIGNAL='@t6g_mb_lib.t6g(sch_1):m_h_cpu1_sb_dq(30)';
NODE_NAME     U26 DE12
 '@T6G_MB_LIB.T6G(SCH_1):PAGE44_I159@PURE_QUANTA.GENOA_SP5(CHIPS)':
 'MHB_DATA30': CDS_PINID='MHB_DATA30';
NODE_NAME     J27 285
 '@T6G_MB_LIB.T6G(SCH_1):PAGE104_I22@PURE_QUANTA.SCONN288_DDR506112002KQ(CHIPS)':
 'DQ30_B': CDS_PINID='DQ30_B';
NET_NAME
'M_H_CPU1_SB_DQ<31>'
 '@T6G_MB_LIB.T6G(SCH_1):M_H_CPU1_SB_DQ'<31>:
 C_SIGNAL='@t6g_mb_lib.t6g(sch_1):m_h_cpu1_sb_dq(31)';
NODE_NAME     U26 DF14
 '@T6G_MB_LIB.T6G(SCH_1):PAGE44_I159@PURE_QUANTA.GENOA_SP5(CHIPS)':
 'MHB_DATA31': CDS_PINID='MHB_DATA31';
NODE_NAME     J27 287
 '@T6G_MB_LIB.T6G(SCH_1):PAGE104_I22@PURE_QUANTA.SCONN288_DDR506112002KQ(CHIPS)':
 'DQ31_B': CDS_PINID='DQ31_B';
NET_NAME
'M_H_CPU1_SB_DQ<3>'
 '@T6G_MB_LIB.T6G(SCH_1):M_H_CPU1_SB_DQ'<3>:
 C_SIGNAL='@t6g_mb_lib.t6g(sch_1):m_h_cpu1_sb_dq(3)';
NODE_NAME     U26 CD14
 '@T6G_MB_LIB.T6G(SCH_1):PAGE44_I159@PURE_QUANTA.GENOA_SP5(CHIPS)':
 'MHB_DATA3': CDS_PINID='MHB_DATA3';
NODE_NAME     J27 247
 '@T6G_MB_LIB.T6G(SCH_1):PAGE104_I22@PURE_QUANTA.SCONN288_DDR506112002KQ(CHIPS)':
 'DQ3_B': CDS_PINID='DQ3_B';
NET_NAME
'M_H_CPU1_SB_DQ<4>'
 '@T6G_MB_LIB.T6G(SCH_1):M_H_CPU1_SB_DQ'<4>:
 C_SIGNAL='@t6g_mb_lib.t6g(sch_1):m_h_cpu1_sb_dq(4)';
NODE_NAME     U26 CF13
 '@T6G_MB_LIB.T6G(SCH_1):PAGE44_I159@PURE_QUANTA.GENOA_SP5(CHIPS)':
 'MHB_DATA4': CDS_PINID='MHB_DATA4';
NODE_NAME     J27 107
 '@T6G_MB_LIB.T6G(SCH_1):PAGE104_I22@PURE_QUANTA.SCONN288_DDR506112002KQ(CHIPS)':
 'DQ4_B': CDS_PINID='DQ4_B';
NET_NAME
'M_H_CPU1_SB_DQ<5>'
 '@T6G_MB_LIB.T6G(SCH_1):M_H_CPU1_SB_DQ'<5>:
 C_SIGNAL='@t6g_mb_lib.t6g(sch_1):m_h_cpu1_sb_dq(5)';
NODE_NAME     U26 CG14
 '@T6G_MB_LIB.T6G(SCH_1):PAGE44_I159@PURE_QUANTA.GENOA_SP5(CHIPS)':
 'MHB_DATA5': CDS_PINID='MHB_DATA5';
NODE_NAME     J27 109
 '@T6G_MB_LIB.T6G(SCH_1):PAGE104_I22@PURE_QUANTA.SCONN288_DDR506112002KQ(CHIPS)':
 'DQ5_B': CDS_PINID='DQ5_B';
NET_NAME
'M_H_CPU1_SB_DQ<6>'
 '@T6G_MB_LIB.T6G(SCH_1):M_H_CPU1_SB_DQ'<6>:
 C_SIGNAL='@t6g_mb_lib.t6g(sch_1):m_h_cpu1_sb_dq(6)';
NODE_NAME     U26 CG12
 '@T6G_MB_LIB.T6G(SCH_1):PAGE44_I159@PURE_QUANTA.GENOA_SP5(CHIPS)':
 'MHB_DATA6': CDS_PINID='MHB_DATA6';
NODE_NAME     J27 252
 '@T6G_MB_LIB.T6G(SCH_1):PAGE104_I22@PURE_QUANTA.SCONN288_DDR506112002KQ(CHIPS)':
 'DQ6_B': CDS_PINID='DQ6_B';
NET_NAME
'M_H_CPU1_SB_DQ<7>'
 '@T6G_MB_LIB.T6G(SCH_1):M_H_CPU1_SB_DQ'<7>:
 C_SIGNAL='@t6g_mb_lib.t6g(sch_1):m_h_cpu1_sb_dq(7)';
NODE_NAME     U26 CH14
 '@T6G_MB_LIB.T6G(SCH_1):PAGE44_I159@PURE_QUANTA.GENOA_SP5(CHIPS)':
 'MHB_DATA7': CDS_PINID='MHB_DATA7';
NODE_NAME     J27 254
 '@T6G_MB_LIB.T6G(SCH_1):PAGE104_I22@PURE_QUANTA.SCONN288_DDR506112002KQ(CHIPS)':
 'DQ7_B': CDS_PINID='DQ7_B';
NET_NAME
'M_H_CPU1_SB_DQ<8>'
 '@T6G_MB_LIB.T6G(SCH_1):M_H_CPU1_SB_DQ'<8>:
 C_SIGNAL='@t6g_mb_lib.t6g(sch_1):m_h_cpu1_sb_dq(8)';
NODE_NAME     U26 CH13
 '@T6G_MB_LIB.T6G(SCH_1):PAGE44_I159@PURE_QUANTA.GENOA_SP5(CHIPS)':
 'MHB_DATA8': CDS_PINID='MHB_DATA8';
NODE_NAME     J27 111
 '@T6G_MB_LIB.T6G(SCH_1):PAGE104_I22@PURE_QUANTA.SCONN288_DDR506112002KQ(CHIPS)':
 'DQ8_B': CDS_PINID='DQ8_B';
NET_NAME
'M_H_CPU1_SB_DQ<9>'
 '@T6G_MB_LIB.T6G(SCH_1):M_H_CPU1_SB_DQ'<9>:
 C_SIGNAL='@t6g_mb_lib.t6g(sch_1):m_h_cpu1_sb_dq(9)';
NODE_NAME     U26 CJ14
 '@T6G_MB_LIB.T6G(SCH_1):PAGE44_I159@PURE_QUANTA.GENOA_SP5(CHIPS)':
 'MHB_DATA9': CDS_PINID='MHB_DATA9';
NODE_NAME     J27 113
 '@T6G_MB_LIB.T6G(SCH_1):PAGE104_I22@PURE_QUANTA.SCONN288_DDR506112002KQ(CHIPS)':
 'DQ9_B': CDS_PINID='DQ9_B';
NET_NAME
'M_H_CPU1_SB_DQS_DN<0>'
 '@T6G_MB_LIB.T6G(SCH_1):M_H_CPU1_SB_DQS_DN'<0>:
 C_SIGNAL='@t6g_mb_lib.t6g(sch_1):m_h_cpu1_sb_dqs_dn(0)';
NODE_NAME     U26 CE12
 '@T6G_MB_LIB.T6G(SCH_1):PAGE44_I159@PURE_QUANTA.GENOA_SP5(CHIPS)':
 'MHB_DQS_L0': CDS_PINID='MHB_DQS_L0';
NODE_NAME     J27 105
 '@T6G_MB_LIB.T6G(SCH_1):PAGE104_I238@PURE_QUANTA.SCONN288_DDR506112002KQ(CHIPS)':
 'DQS0_B_C': CDS_PINID='DQS0_B_C';
NET_NAME
'M_H_CPU1_SB_DQS_DN<1>'
 '@T6G_MB_LIB.T6G(SCH_1):M_H_CPU1_SB_DQS_DN'<1>:
 C_SIGNAL='@t6g_mb_lib.t6g(sch_1):m_h_cpu1_sb_dqs_dn(1)';
NODE_NAME     U26 CL12
 '@T6G_MB_LIB.T6G(SCH_1):PAGE44_I159@PURE_QUANTA.GENOA_SP5(CHIPS)':
 'MHB_DQS_L1': CDS_PINID='MHB_DQS_L1';
NODE_NAME     J27 116
 '@T6G_MB_LIB.T6G(SCH_1):PAGE104_I238@PURE_QUANTA.SCONN288_DDR506112002KQ(CHIPS)':
 'DQS1_B_C': CDS_PINID='DQS1_B_C';
NET_NAME
'M_H_CPU1_SB_DQS_DN<2>'
 '@T6G_MB_LIB.T6G(SCH_1):M_H_CPU1_SB_DQS_DN'<2>:
 C_SIGNAL='@t6g_mb_lib.t6g(sch_1):m_h_cpu1_sb_dqs_dn(2)';
NODE_NAME     U26 CU12
 '@T6G_MB_LIB.T6G(SCH_1):PAGE44_I159@PURE_QUANTA.GENOA_SP5(CHIPS)':
 'MHB_DQS_L2': CDS_PINID='MHB_DQS_L2';
NODE_NAME     J27 127
 '@T6G_MB_LIB.T6G(SCH_1):PAGE104_I238@PURE_QUANTA.SCONN288_DDR506112002KQ(CHIPS)':
 'DQS2_B_C': CDS_PINID='DQS2_B_C';
NET_NAME
'M_H_CPU1_SB_DQS_DN<3>'
 '@T6G_MB_LIB.T6G(SCH_1):M_H_CPU1_SB_DQS_DN'<3>:
 C_SIGNAL='@t6g_mb_lib.t6g(sch_1):m_h_cpu1_sb_dqs_dn(3)';
NODE_NAME     U26 DC12
 '@T6G_MB_LIB.T6G(SCH_1):PAGE44_I159@PURE_QUANTA.GENOA_SP5(CHIPS)':
 'MHB_DQS_L3': CDS_PINID='MHB_DQS_L3';
NODE_NAME     J27 138
 '@T6G_MB_LIB.T6G(SCH_1):PAGE104_I238@PURE_QUANTA.SCONN288_DDR506112002KQ(CHIPS)':
 'DQS3_B_C': CDS_PINID='DQS3_B_C';
NET_NAME
'M_H_CPU1_SB_DQS_DN<4>'
 '@T6G_MB_LIB.T6G(SCH_1):M_H_CPU1_SB_DQS_DN'<4>:
 C_SIGNAL='@t6g_mb_lib.t6g(sch_1):m_h_cpu1_sb_dqs_dn(4)';
NODE_NAME     U26 BW14
 '@T6G_MB_LIB.T6G(SCH_1):PAGE44_I159@PURE_QUANTA.GENOA_SP5(CHIPS)':
 'MHB_DQS_L4': CDS_PINID='MHB_DQS_L4';
NODE_NAME     J27 238
 '@T6G_MB_LIB.T6G(SCH_1):PAGE104_I238@PURE_QUANTA.SCONN288_DDR506112002KQ(CHIPS)':
 'DQS4_B_C': CDS_PINID='DQS4_B_C';
NET_NAME
'M_H_CPU1_SB_DQS_DN<5>'
 '@T6G_MB_LIB.T6G(SCH_1):M_H_CPU1_SB_DQS_DN'<5>:
 C_SIGNAL='@t6g_mb_lib.t6g(sch_1):m_h_cpu1_sb_dqs_dn(5)';
NODE_NAME     U26 CE14
 '@T6G_MB_LIB.T6G(SCH_1):PAGE44_I159@PURE_QUANTA.GENOA_SP5(CHIPS)':
 'MHB_DQS_L5': CDS_PINID='MHB_DQS_L5';
NODE_NAME     J27 249
 '@T6G_MB_LIB.T6G(SCH_1):PAGE104_I238@PURE_QUANTA.SCONN288_DDR506112002KQ(CHIPS)':
 'DQS5_B_C||TDQS5_B_C': CDS_PINID='\dqs5_b_c||tdqs5_b_c\';
NET_NAME
'M_H_CPU1_SB_DQS_DN<6>'
 '@T6G_MB_LIB.T6G(SCH_1):M_H_CPU1_SB_DQS_DN'<6>:
 C_SIGNAL='@t6g_mb_lib.t6g(sch_1):m_h_cpu1_sb_dqs_dn(6)';
NODE_NAME     U26 CL14
 '@T6G_MB_LIB.T6G(SCH_1):PAGE44_I159@PURE_QUANTA.GENOA_SP5(CHIPS)':
 'MHB_DQS_L6': CDS_PINID='MHB_DQS_L6';
NODE_NAME     J27 260
 '@T6G_MB_LIB.T6G(SCH_1):PAGE104_I238@PURE_QUANTA.SCONN288_DDR506112002KQ(CHIPS)':
 'DQS6_B_C||TDQS6_B_C': CDS_PINID='\dqs6_b_c||tdqs6_b_c\';
NET_NAME
'M_H_CPU1_SB_DQS_DN<7>'
 '@T6G_MB_LIB.T6G(SCH_1):M_H_CPU1_SB_DQS_DN'<7>:
 C_SIGNAL='@t6g_mb_lib.t6g(sch_1):m_h_cpu1_sb_dqs_dn(7)';
NODE_NAME     U26 CU14
 '@T6G_MB_LIB.T6G(SCH_1):PAGE44_I159@PURE_QUANTA.GENOA_SP5(CHIPS)':
 'MHB_DQS_L7': CDS_PINID='MHB_DQS_L7';
NODE_NAME     J27 271
 '@T6G_MB_LIB.T6G(SCH_1):PAGE104_I238@PURE_QUANTA.SCONN288_DDR506112002KQ(CHIPS)':
 'DQS7_B_C||TDQS7_B_C': CDS_PINID='\dqs7_b_c||tdqs7_b_c\';
NET_NAME
'M_H_CPU1_SB_DQS_DN<8>'
 '@T6G_MB_LIB.T6G(SCH_1):M_H_CPU1_SB_DQS_DN'<8>:
 C_SIGNAL='@t6g_mb_lib.t6g(sch_1):m_h_cpu1_sb_dqs_dn(8)';
NODE_NAME     U26 DC14
 '@T6G_MB_LIB.T6G(SCH_1):PAGE44_I159@PURE_QUANTA.GENOA_SP5(CHIPS)':
 'MHB_DQS_L8': CDS_PINID='MHB_DQS_L8';
NODE_NAME     J27 282
 '@T6G_MB_LIB.T6G(SCH_1):PAGE104_I238@PURE_QUANTA.SCONN288_DDR506112002KQ(CHIPS)':
 'DQS8_B_C||TDQS8_B_C': CDS_PINID='\dqs8_b_c||tdqs8_b_c\';
NET_NAME
'M_H_CPU1_SB_DQS_DN<9>'
 '@T6G_MB_LIB.T6G(SCH_1):M_H_CPU1_SB_DQS_DN'<9>:
 C_SIGNAL='@t6g_mb_lib.t6g(sch_1):m_h_cpu1_sb_dqs_dn(9)';
NODE_NAME     U26 BW12
 '@T6G_MB_LIB.T6G(SCH_1):PAGE44_I159@PURE_QUANTA.GENOA_SP5(CHIPS)':
 'MHB_DQS_L9': CDS_PINID='MHB_DQS_L9';
NODE_NAME     J27 94
 '@T6G_MB_LIB.T6G(SCH_1):PAGE104_I238@PURE_QUANTA.SCONN288_DDR506112002KQ(CHIPS)':
 'DQS9_B_C||TDQS9_B_C': CDS_PINID='\dqs9_b_c||tdqs9_b_c\';
NET_NAME
'M_H_CPU1_SB_DQS_DP<0>'
 '@T6G_MB_LIB.T6G(SCH_1):M_H_CPU1_SB_DQS_DP'<0>:
 C_SIGNAL='@t6g_mb_lib.t6g(sch_1):m_h_cpu1_sb_dqs_dp(0)';
NODE_NAME     U26 CD13
 '@T6G_MB_LIB.T6G(SCH_1):PAGE44_I159@PURE_QUANTA.GENOA_SP5(CHIPS)':
 'MHB_DQS_H0': CDS_PINID='MHB_DQS_H0';
NODE_NAME     J27 104
 '@T6G_MB_LIB.T6G(SCH_1):PAGE104_I238@PURE_QUANTA.SCONN288_DDR506112002KQ(CHIPS)':
 'DQS0_B_T': CDS_PINID='DQS0_B_T';
NET_NAME
'M_H_CPU1_SB_DQS_DP<1>'
 '@T6G_MB_LIB.T6G(SCH_1):M_H_CPU1_SB_DQS_DP'<1>:
 C_SIGNAL='@t6g_mb_lib.t6g(sch_1):m_h_cpu1_sb_dqs_dp(1)';
NODE_NAME     U26 CK13
 '@T6G_MB_LIB.T6G(SCH_1):PAGE44_I159@PURE_QUANTA.GENOA_SP5(CHIPS)':
 'MHB_DQS_H1': CDS_PINID='MHB_DQS_H1';
NODE_NAME     J27 115
 '@T6G_MB_LIB.T6G(SCH_1):PAGE104_I238@PURE_QUANTA.SCONN288_DDR506112002KQ(CHIPS)':
 'DQS1_B_T': CDS_PINID='DQS1_B_T';
NET_NAME
'M_H_CPU1_SB_DQS_DP<2>'
 '@T6G_MB_LIB.T6G(SCH_1):M_H_CPU1_SB_DQS_DP'<2>:
 C_SIGNAL='@t6g_mb_lib.t6g(sch_1):m_h_cpu1_sb_dqs_dp(2)';
NODE_NAME     U26 CT13
 '@T6G_MB_LIB.T6G(SCH_1):PAGE44_I159@PURE_QUANTA.GENOA_SP5(CHIPS)':
 'MHB_DQS_H2': CDS_PINID='MHB_DQS_H2';
NODE_NAME     J27 126
 '@T6G_MB_LIB.T6G(SCH_1):PAGE104_I238@PURE_QUANTA.SCONN288_DDR506112002KQ(CHIPS)':
 'DQS2_B_T': CDS_PINID='DQS2_B_T';
NET_NAME
'M_H_CPU1_SB_DQS_DP<3>'
 '@T6G_MB_LIB.T6G(SCH_1):M_H_CPU1_SB_DQS_DP'<3>:
 C_SIGNAL='@t6g_mb_lib.t6g(sch_1):m_h_cpu1_sb_dqs_dp(3)';
NODE_NAME     U26 DB13
 '@T6G_MB_LIB.T6G(SCH_1):PAGE44_I159@PURE_QUANTA.GENOA_SP5(CHIPS)':
 'MHB_DQS_H3': CDS_PINID='MHB_DQS_H3';
NODE_NAME     J27 137
 '@T6G_MB_LIB.T6G(SCH_1):PAGE104_I238@PURE_QUANTA.SCONN288_DDR506112002KQ(CHIPS)':
 'DQS3_B_T': CDS_PINID='DQS3_B_T';
NET_NAME
'M_H_CPU1_SB_DQS_DP<4>'
 '@T6G_MB_LIB.T6G(SCH_1):M_H_CPU1_SB_DQS_DP'<4>:
 C_SIGNAL='@t6g_mb_lib.t6g(sch_1):m_h_cpu1_sb_dqs_dp(4)';
NODE_NAME     U26 BY14
 '@T6G_MB_LIB.T6G(SCH_1):PAGE44_I159@PURE_QUANTA.GENOA_SP5(CHIPS)':
 'MHB_DQS_H4': CDS_PINID='MHB_DQS_H4';
NODE_NAME     J27 239
 '@T6G_MB_LIB.T6G(SCH_1):PAGE104_I238@PURE_QUANTA.SCONN288_DDR506112002KQ(CHIPS)':
 'DQS4_B_T': CDS_PINID='DQS4_B_T';
NET_NAME
'M_H_CPU1_SB_DQS_DP<5>'
 '@T6G_MB_LIB.T6G(SCH_1):M_H_CPU1_SB_DQS_DP'<5>:
 C_SIGNAL='@t6g_mb_lib.t6g(sch_1):m_h_cpu1_sb_dqs_dp(5)';
NODE_NAME     U26 CF14
 '@T6G_MB_LIB.T6G(SCH_1):PAGE44_I159@PURE_QUANTA.GENOA_SP5(CHIPS)':
 'MHB_DQS_H5': CDS_PINID='MHB_DQS_H5';
NODE_NAME     J27 250
 '@T6G_MB_LIB.T6G(SCH_1):PAGE104_I238@PURE_QUANTA.SCONN288_DDR506112002KQ(CHIPS)':
 'DQS5_B_T||TDQS5_B_T': CDS_PINID='\dqs5_b_t||tdqs5_b_t\';
NET_NAME
'M_H_CPU1_SB_DQS_DP<6>'
 '@T6G_MB_LIB.T6G(SCH_1):M_H_CPU1_SB_DQS_DP'<6>:
 C_SIGNAL='@t6g_mb_lib.t6g(sch_1):m_h_cpu1_sb_dqs_dp(6)';
NODE_NAME     U26 CM14
 '@T6G_MB_LIB.T6G(SCH_1):PAGE44_I159@PURE_QUANTA.GENOA_SP5(CHIPS)':
 'MHB_DQS_H6': CDS_PINID='MHB_DQS_H6';
NODE_NAME     J27 261
 '@T6G_MB_LIB.T6G(SCH_1):PAGE104_I238@PURE_QUANTA.SCONN288_DDR506112002KQ(CHIPS)':
 'DQS6_B_T||TDQS6_B_T': CDS_PINID='\dqs6_b_t||tdqs6_b_t\';
NET_NAME
'M_H_CPU1_SB_DQS_DP<7>'
 '@T6G_MB_LIB.T6G(SCH_1):M_H_CPU1_SB_DQS_DP'<7>:
 C_SIGNAL='@t6g_mb_lib.t6g(sch_1):m_h_cpu1_sb_dqs_dp(7)';
NODE_NAME     U26 CV14
 '@T6G_MB_LIB.T6G(SCH_1):PAGE44_I159@PURE_QUANTA.GENOA_SP5(CHIPS)':
 'MHB_DQS_H7': CDS_PINID='MHB_DQS_H7';
NODE_NAME     J27 272
 '@T6G_MB_LIB.T6G(SCH_1):PAGE104_I238@PURE_QUANTA.SCONN288_DDR506112002KQ(CHIPS)':
 'DQS7_B_T||TDQS7_B_T': CDS_PINID='\dqs7_b_t||tdqs7_b_t\';
NET_NAME
'M_H_CPU1_SB_DQS_DP<8>'
 '@T6G_MB_LIB.T6G(SCH_1):M_H_CPU1_SB_DQS_DP'<8>:
 C_SIGNAL='@t6g_mb_lib.t6g(sch_1):m_h_cpu1_sb_dqs_dp(8)';
NODE_NAME     U26 DD14
 '@T6G_MB_LIB.T6G(SCH_1):PAGE44_I159@PURE_QUANTA.GENOA_SP5(CHIPS)':
 'MHB_DQS_H8': CDS_PINID='MHB_DQS_H8';
NODE_NAME     J27 283
 '@T6G_MB_LIB.T6G(SCH_1):PAGE104_I238@PURE_QUANTA.SCONN288_DDR506112002KQ(CHIPS)':
 'DQS8_B_T||TDQS8_B_T': CDS_PINID='\dqs8_b_t||tdqs8_b_t\';
NET_NAME
'M_H_CPU1_SB_DQS_DP<9>'
 '@T6G_MB_LIB.T6G(SCH_1):M_H_CPU1_SB_DQS_DP'<9>:
 C_SIGNAL='@t6g_mb_lib.t6g(sch_1):m_h_cpu1_sb_dqs_dp(9)';
NODE_NAME     U26 BV13
 '@T6G_MB_LIB.T6G(SCH_1):PAGE44_I159@PURE_QUANTA.GENOA_SP5(CHIPS)':
 'MHB_DQS_H9': CDS_PINID='MHB_DQS_H9';
NODE_NAME     J27 93
 '@T6G_MB_LIB.T6G(SCH_1):PAGE104_I238@PURE_QUANTA.SCONN288_DDR506112002KQ(CHIPS)':
 'DQS9_B_T||TDQS9_B_T||DBI4_B_N': CDS_PINID='\dqs9_b_t||tdqs9_b_t||dbi4_b_n\';
NET_NAME
'M_H_CPU1_SB_PAR'
 '@T6G_MB_LIB.T6G(SCH_1):M_H_CPU1_SB_PAR':
 C_SIGNAL='@t6g_mb_lib.t6g(sch_1):m_h_cpu1_sb_par';
NODE_NAME     U26 BL14
 '@T6G_MB_LIB.T6G(SCH_1):PAGE44_I159@PURE_QUANTA.GENOA_SP5(CHIPS)':
 'MHB_PAR': CDS_PINID='MHB_PAR';
NODE_NAME     J27 227
 '@T6G_MB_LIB.T6G(SCH_1):PAGE104_I22@PURE_QUANTA.SCONN288_DDR506112002KQ(CHIPS)':
 'PAR_B': CDS_PINID='PAR_B';
NET_NAME
'M_H_CPU1_SB_RSP<0>'
 '@T6G_MB_LIB.T6G(SCH_1):M_H_CPU1_SB_RSP'<0>:
 C_SIGNAL='@t6g_mb_lib.t6g(sch_1):m_h_cpu1_sb_rsp(0)';
NODE_NAME     U26 BP13
 '@T6G_MB_LIB.T6G(SCH_1):PAGE44_I159@PURE_QUANTA.GENOA_SP5(CHIPS)':
 'MHB0_RSP_L': CDS_PINID='MHB0_RSP_L';
NODE_NAME     J27 87
 '@T6G_MB_LIB.T6G(SCH_1):PAGE104_I22@PURE_QUANTA.SCONN288_DDR506112002KQ(CHIPS)':
 'LBS||RSP_B_N': CDS_PINID='\lbs||rsp_b_n\';
NET_NAME
'M_I_CPU0_ALERT_N'
 '@T6G_MB_LIB.T6G(SCH_1):M_I_CPU0_ALERT_N':
 C_SIGNAL='@t6g_mb_lib.t6g(sch_1):m_i_cpu0_alert_n';
NODE_NAME     R383 1
 '@T6G_MB_LIB.T6G(SCH_1):PAGE18_I314@PURE_QUANTA.Q_RES(CHIPS)':
 'A': CDS_PINID='A';
NODE_NAME     J18 62
 '@T6G_MB_LIB.T6G(SCH_1):PAGE93_I22@PURE_QUANTA.SCONN288_DDR506112002KQ(CHIPS)':
 'ALERT_N': CDS_PINID='ALERT_N';
NET_NAME
'M_I_CPU0_ALERT_R_N'
 '@T6G_MB_LIB.T6G(SCH_1):M_I_CPU0_ALERT_R_N':
 C_SIGNAL='@t6g_mb_lib.t6g(sch_1):m_i_cpu0_alert_r_n';
NODE_NAME     U25 AT21
 '@T6G_MB_LIB.T6G(SCH_1):PAGE18_I159@PURE_QUANTA.GENOA_SP5(CHIPS)':
 'MI_ALERT_L': CDS_PINID='MI_ALERT_L';
NODE_NAME     R383 2
 '@T6G_MB_LIB.T6G(SCH_1):PAGE18_I314@PURE_QUANTA.Q_RES(CHIPS)':
 'B': CDS_PINID='B';
NET_NAME
'M_I_CPU0_CLK_DN<0>'
 '@T6G_MB_LIB.T6G(SCH_1):M_I_CPU0_CLK_DN'<0>:
 C_SIGNAL='@t6g_mb_lib.t6g(sch_1):m_i_cpu0_clk_dn(0)';
NODE_NAME     U25 BD20
 '@T6G_MB_LIB.T6G(SCH_1):PAGE18_I159@PURE_QUANTA.GENOA_SP5(CHIPS)':
 'MI0_CLK_L': CDS_PINID='MI0_CLK_L';
NODE_NAME     J18 218
 '@T6G_MB_LIB.T6G(SCH_1):PAGE93_I22@PURE_QUANTA.SCONN288_DDR506112002KQ(CHIPS)':
 'CK_C': CDS_PINID='CK_C';
NET_NAME
'M_I_CPU0_CLK_DP<0>'
 '@T6G_MB_LIB.T6G(SCH_1):M_I_CPU0_CLK_DP'<0>:
 C_SIGNAL='@t6g_mb_lib.t6g(sch_1):m_i_cpu0_clk_dp(0)';
NODE_NAME     U25 BC19
 '@T6G_MB_LIB.T6G(SCH_1):PAGE18_I159@PURE_QUANTA.GENOA_SP5(CHIPS)':
 'MI0_CLK_H': CDS_PINID='MI0_CLK_H';
NODE_NAME     J18 217
 '@T6G_MB_LIB.T6G(SCH_1):PAGE93_I22@PURE_QUANTA.SCONN288_DDR506112002KQ(CHIPS)':
 'CK_T': CDS_PINID='CK_T';
NET_NAME
'M_I_CPU0_RESET_N'
 '@T6G_MB_LIB.T6G(SCH_1):M_I_CPU0_RESET_N':
 C_SIGNAL='@t6g_mb_lib.t6g(sch_1):m_i_cpu0_reset_n';
NODE_NAME     U25 AU21
 '@T6G_MB_LIB.T6G(SCH_1):PAGE18_I159@PURE_QUANTA.GENOA_SP5(CHIPS)':
 'MI_RESET_L': CDS_PINID='MI_RESET_L';
NODE_NAME     J18 207
 '@T6G_MB_LIB.T6G(SCH_1):PAGE93_I22@PURE_QUANTA.SCONN288_DDR506112002KQ(CHIPS)':
 'RESET_N': CDS_PINID='RESET_N';
NET_NAME
'M_I_CPU0_SA_CA<0>'
 '@T6G_MB_LIB.T6G(SCH_1):M_I_CPU0_SA_CA'<0>:
 C_SIGNAL='@t6g_mb_lib.t6g(sch_1):m_i_cpu0_sa_ca(0)';
NODE_NAME     U25 AW19
 '@T6G_MB_LIB.T6G(SCH_1):PAGE18_I159@PURE_QUANTA.GENOA_SP5(CHIPS)':
 'MIA_CA0': CDS_PINID='MIA_CA0';
NODE_NAME     J18 66
 '@T6G_MB_LIB.T6G(SCH_1):PAGE93_I22@PURE_QUANTA.SCONN288_DDR506112002KQ(CHIPS)':
 'CA0_A': CDS_PINID='CA0_A';
NET_NAME
'M_I_CPU0_SA_CA<1>'
 '@T6G_MB_LIB.T6G(SCH_1):M_I_CPU0_SA_CA'<1>:
 C_SIGNAL='@t6g_mb_lib.t6g(sch_1):m_i_cpu0_sa_ca(1)';
NODE_NAME     U25 AY20
 '@T6G_MB_LIB.T6G(SCH_1):PAGE18_I159@PURE_QUANTA.GENOA_SP5(CHIPS)':
 'MIA_CA1': CDS_PINID='MIA_CA1';
NODE_NAME     J18 211
 '@T6G_MB_LIB.T6G(SCH_1):PAGE93_I22@PURE_QUANTA.SCONN288_DDR506112002KQ(CHIPS)':
 'CA1_A': CDS_PINID='CA1_A';
NET_NAME
'M_I_CPU0_SA_CA<2>'
 '@T6G_MB_LIB.T6G(SCH_1):M_I_CPU0_SA_CA'<2>:
 C_SIGNAL='@t6g_mb_lib.t6g(sch_1):m_i_cpu0_sa_ca(2)';
NODE_NAME     U25 AY21
 '@T6G_MB_LIB.T6G(SCH_1):PAGE18_I159@PURE_QUANTA.GENOA_SP5(CHIPS)':
 'MIA_CA2': CDS_PINID='MIA_CA2';
NODE_NAME     J18 68
 '@T6G_MB_LIB.T6G(SCH_1):PAGE93_I22@PURE_QUANTA.SCONN288_DDR506112002KQ(CHIPS)':
 'CA2_A': CDS_PINID='CA2_A';
NET_NAME
'M_I_CPU0_SA_CA<3>'
 '@T6G_MB_LIB.T6G(SCH_1):M_I_CPU0_SA_CA'<3>:
 C_SIGNAL='@t6g_mb_lib.t6g(sch_1):m_i_cpu0_sa_ca(3)';
NODE_NAME     U25 BA21
 '@T6G_MB_LIB.T6G(SCH_1):PAGE18_I159@PURE_QUANTA.GENOA_SP5(CHIPS)':
 'MIA_CA3': CDS_PINID='MIA_CA3';
NODE_NAME     J18 213
 '@T6G_MB_LIB.T6G(SCH_1):PAGE93_I22@PURE_QUANTA.SCONN288_DDR506112002KQ(CHIPS)':
 'CA3_A': CDS_PINID='CA3_A';
NET_NAME
'M_I_CPU0_SA_CA<4>'
 '@T6G_MB_LIB.T6G(SCH_1):M_I_CPU0_SA_CA'<4>:
 C_SIGNAL='@t6g_mb_lib.t6g(sch_1):m_i_cpu0_sa_ca(4)';
NODE_NAME     U25 BA19
 '@T6G_MB_LIB.T6G(SCH_1):PAGE18_I159@PURE_QUANTA.GENOA_SP5(CHIPS)':
 'MIA_CA4': CDS_PINID='MIA_CA4';
NODE_NAME     J18 70
 '@T6G_MB_LIB.T6G(SCH_1):PAGE93_I22@PURE_QUANTA.SCONN288_DDR506112002KQ(CHIPS)':
 'CA4_A': CDS_PINID='CA4_A';
NET_NAME
'M_I_CPU0_SA_CA<5>'
 '@T6G_MB_LIB.T6G(SCH_1):M_I_CPU0_SA_CA'<5>:
 C_SIGNAL='@t6g_mb_lib.t6g(sch_1):m_i_cpu0_sa_ca(5)';
NODE_NAME     U25 BB20
 '@T6G_MB_LIB.T6G(SCH_1):PAGE18_I159@PURE_QUANTA.GENOA_SP5(CHIPS)':
 'MIA_CA5': CDS_PINID='MIA_CA5';
NODE_NAME     J18 215
 '@T6G_MB_LIB.T6G(SCH_1):PAGE93_I22@PURE_QUANTA.SCONN288_DDR506112002KQ(CHIPS)':
 'CA5_A': CDS_PINID='CA5_A';
NET_NAME
'M_I_CPU0_SA_CA<6>'
 '@T6G_MB_LIB.T6G(SCH_1):M_I_CPU0_SA_CA'<6>:
 C_SIGNAL='@t6g_mb_lib.t6g(sch_1):m_i_cpu0_sa_ca(6)';
NODE_NAME     U25 BB21
 '@T6G_MB_LIB.T6G(SCH_1):PAGE18_I159@PURE_QUANTA.GENOA_SP5(CHIPS)':
 'MIA_CA6': CDS_PINID='MIA_CA6';
NODE_NAME     J18 72
 '@T6G_MB_LIB.T6G(SCH_1):PAGE93_I22@PURE_QUANTA.SCONN288_DDR506112002KQ(CHIPS)':
 'CA6_A': CDS_PINID='CA6_A';
NET_NAME
'M_I_CPU0_SA_CB<0>'
 '@T6G_MB_LIB.T6G(SCH_1):M_I_CPU0_SA_CB'<0>:
 C_SIGNAL='@t6g_mb_lib.t6g(sch_1):m_i_cpu0_sa_cb(0)';
NODE_NAME     U25 AJ19
 '@T6G_MB_LIB.T6G(SCH_1):PAGE18_I159@PURE_QUANTA.GENOA_SP5(CHIPS)':
 'MIA_CHECK0': CDS_PINID='MIA_CHECK0';
NODE_NAME     J18 51
 '@T6G_MB_LIB.T6G(SCH_1):PAGE93_I22@PURE_QUANTA.SCONN288_DDR506112002KQ(CHIPS)':
 'CB0_A': CDS_PINID='CB0_A';
NET_NAME
'M_I_CPU0_SA_CB<1>'
 '@T6G_MB_LIB.T6G(SCH_1):M_I_CPU0_SA_CB'<1>:
 C_SIGNAL='@t6g_mb_lib.t6g(sch_1):m_i_cpu0_sa_cb(1)';
NODE_NAME     U25 AK21
 '@T6G_MB_LIB.T6G(SCH_1):PAGE18_I159@PURE_QUANTA.GENOA_SP5(CHIPS)':
 'MIA_CHECK1': CDS_PINID='MIA_CHECK1';
NODE_NAME     J18 53
 '@T6G_MB_LIB.T6G(SCH_1):PAGE93_I22@PURE_QUANTA.SCONN288_DDR506112002KQ(CHIPS)':
 'CB1_A': CDS_PINID='CB1_A';
NET_NAME
'M_I_CPU0_SA_CB<2>'
 '@T6G_MB_LIB.T6G(SCH_1):M_I_CPU0_SA_CB'<2>:
 C_SIGNAL='@t6g_mb_lib.t6g(sch_1):m_i_cpu0_sa_cb(2)';
NODE_NAME     U25 AK20
 '@T6G_MB_LIB.T6G(SCH_1):PAGE18_I159@PURE_QUANTA.GENOA_SP5(CHIPS)':
 'MIA_CHECK2': CDS_PINID='MIA_CHECK2';
NODE_NAME     J18 196
 '@T6G_MB_LIB.T6G(SCH_1):PAGE93_I22@PURE_QUANTA.SCONN288_DDR506112002KQ(CHIPS)':
 'CB2_A': CDS_PINID='CB2_A';
NET_NAME
'M_I_CPU0_SA_CB<3>'
 '@T6G_MB_LIB.T6G(SCH_1):M_I_CPU0_SA_CB'<3>:
 C_SIGNAL='@t6g_mb_lib.t6g(sch_1):m_i_cpu0_sa_cb(3)';
NODE_NAME     U25 AL21
 '@T6G_MB_LIB.T6G(SCH_1):PAGE18_I159@PURE_QUANTA.GENOA_SP5(CHIPS)':
 'MIA_CHECK3': CDS_PINID='MIA_CHECK3';
NODE_NAME     J18 198
 '@T6G_MB_LIB.T6G(SCH_1):PAGE93_I22@PURE_QUANTA.SCONN288_DDR506112002KQ(CHIPS)':
 'CB3_A': CDS_PINID='CB3_A';
NET_NAME
'M_I_CPU0_SA_CB<4>'
 '@T6G_MB_LIB.T6G(SCH_1):M_I_CPU0_SA_CB'<4>:
 C_SIGNAL='@t6g_mb_lib.t6g(sch_1):m_i_cpu0_sa_cb(4)';
NODE_NAME     U25 AN19
 '@T6G_MB_LIB.T6G(SCH_1):PAGE18_I159@PURE_QUANTA.GENOA_SP5(CHIPS)':
 'MIA_CHECK4': CDS_PINID='MIA_CHECK4';
NODE_NAME     J18 58
 '@T6G_MB_LIB.T6G(SCH_1):PAGE93_I22@PURE_QUANTA.SCONN288_DDR506112002KQ(CHIPS)':
 'CB4_A': CDS_PINID='CB4_A';
NET_NAME
'M_I_CPU0_SA_CB<5>'
 '@T6G_MB_LIB.T6G(SCH_1):M_I_CPU0_SA_CB'<5>:
 C_SIGNAL='@t6g_mb_lib.t6g(sch_1):m_i_cpu0_sa_cb(5)';
NODE_NAME     U25 AP21
 '@T6G_MB_LIB.T6G(SCH_1):PAGE18_I159@PURE_QUANTA.GENOA_SP5(CHIPS)':
 'MIA_CHECK5': CDS_PINID='MIA_CHECK5';
NODE_NAME     J18 60
 '@T6G_MB_LIB.T6G(SCH_1):PAGE93_I22@PURE_QUANTA.SCONN288_DDR506112002KQ(CHIPS)':
 'CB5_A': CDS_PINID='CB5_A';
NET_NAME
'M_I_CPU0_SA_CB<6>'
 '@T6G_MB_LIB.T6G(SCH_1):M_I_CPU0_SA_CB'<6>:
 C_SIGNAL='@t6g_mb_lib.t6g(sch_1):m_i_cpu0_sa_cb(6)';
NODE_NAME     U25 AP20
 '@T6G_MB_LIB.T6G(SCH_1):PAGE18_I159@PURE_QUANTA.GENOA_SP5(CHIPS)':
 'MIA_CHECK6': CDS_PINID='MIA_CHECK6';
NODE_NAME     J18 203
 '@T6G_MB_LIB.T6G(SCH_1):PAGE93_I22@PURE_QUANTA.SCONN288_DDR506112002KQ(CHIPS)':
 'CB6_A': CDS_PINID='CB6_A';
NET_NAME
'M_I_CPU0_SA_CB<7>'
 '@T6G_MB_LIB.T6G(SCH_1):M_I_CPU0_SA_CB'<7>:
 C_SIGNAL='@t6g_mb_lib.t6g(sch_1):m_i_cpu0_sa_cb(7)';
NODE_NAME     U25 AR21
 '@T6G_MB_LIB.T6G(SCH_1):PAGE18_I159@PURE_QUANTA.GENOA_SP5(CHIPS)':
 'MIA_CHECK7': CDS_PINID='MIA_CHECK7';
NODE_NAME     J18 205
 '@T6G_MB_LIB.T6G(SCH_1):PAGE93_I22@PURE_QUANTA.SCONN288_DDR506112002KQ(CHIPS)':
 'CB7_A': CDS_PINID='CB7_A';
NET_NAME
'M_I_CPU0_SA_CS_N<0>'
 '@T6G_MB_LIB.T6G(SCH_1):M_I_CPU0_SA_CS_N'<0>:
 C_SIGNAL='@t6g_mb_lib.t6g(sch_1):m_i_cpu0_sa_cs_n(0)';
NODE_NAME     U25 AU19
 '@T6G_MB_LIB.T6G(SCH_1):PAGE18_I159@PURE_QUANTA.GENOA_SP5(CHIPS)':
 'MIA0_CS_L0': CDS_PINID='MIA0_CS_L0';
NODE_NAME     J18 64
 '@T6G_MB_LIB.T6G(SCH_1):PAGE93_I22@PURE_QUANTA.SCONN288_DDR506112002KQ(CHIPS)':
 'CS0_A_N': CDS_PINID='CS0_A_N';
NET_NAME
'M_I_CPU0_SA_CS_N<1>'
 '@T6G_MB_LIB.T6G(SCH_1):M_I_CPU0_SA_CS_N'<1>:
 C_SIGNAL='@t6g_mb_lib.t6g(sch_1):m_i_cpu0_sa_cs_n(1)';
NODE_NAME     U25 AV21
 '@T6G_MB_LIB.T6G(SCH_1):PAGE18_I159@PURE_QUANTA.GENOA_SP5(CHIPS)':
 'MIA0_CS_L1': CDS_PINID='MIA0_CS_L1';
NODE_NAME     J18 209
 '@T6G_MB_LIB.T6G(SCH_1):PAGE93_I22@PURE_QUANTA.SCONN288_DDR506112002KQ(CHIPS)':
 'CS1_A_N': CDS_PINID='CS1_A_N';
NET_NAME
'M_I_CPU0_SA_DQ<0>'
 '@T6G_MB_LIB.T6G(SCH_1):M_I_CPU0_SA_DQ'<0>:
 C_SIGNAL='@t6g_mb_lib.t6g(sch_1):m_i_cpu0_sa_dq(0)';
NODE_NAME     U25 E19
 '@T6G_MB_LIB.T6G(SCH_1):PAGE18_I159@PURE_QUANTA.GENOA_SP5(CHIPS)':
 'MIA_DATA0': CDS_PINID='MIA_DATA0';
NODE_NAME     J18 7
 '@T6G_MB_LIB.T6G(SCH_1):PAGE93_I22@PURE_QUANTA.SCONN288_DDR506112002KQ(CHIPS)':
 'DQ0_A': CDS_PINID='DQ0_A';
NET_NAME
'M_I_CPU0_SA_DQ<10>'
 '@T6G_MB_LIB.T6G(SCH_1):M_I_CPU0_SA_DQ'<10>:
 C_SIGNAL='@t6g_mb_lib.t6g(sch_1):m_i_cpu0_sa_dq(10)';
NODE_NAME     U25 M20
 '@T6G_MB_LIB.T6G(SCH_1):PAGE18_I159@PURE_QUANTA.GENOA_SP5(CHIPS)':
 'MIA_DATA10': CDS_PINID='MIA_DATA10';
NODE_NAME     J18 163
 '@T6G_MB_LIB.T6G(SCH_1):PAGE93_I22@PURE_QUANTA.SCONN288_DDR506112002KQ(CHIPS)':
 'DQ10_A': CDS_PINID='DQ10_A';
NET_NAME
'M_I_CPU0_SA_DQ<11>'
 '@T6G_MB_LIB.T6G(SCH_1):M_I_CPU0_SA_DQ'<11>:
 C_SIGNAL='@t6g_mb_lib.t6g(sch_1):m_i_cpu0_sa_dq(11)';
NODE_NAME     U25 N21
 '@T6G_MB_LIB.T6G(SCH_1):PAGE18_I159@PURE_QUANTA.GENOA_SP5(CHIPS)':
 'MIA_DATA11': CDS_PINID='MIA_DATA11';
NODE_NAME     J18 165
 '@T6G_MB_LIB.T6G(SCH_1):PAGE93_I22@PURE_QUANTA.SCONN288_DDR506112002KQ(CHIPS)':
 'DQ11_A': CDS_PINID='DQ11_A';
NET_NAME
'M_I_CPU0_SA_DQ<12>'
 '@T6G_MB_LIB.T6G(SCH_1):M_I_CPU0_SA_DQ'<12>:
 C_SIGNAL='@t6g_mb_lib.t6g(sch_1):m_i_cpu0_sa_dq(12)';
NODE_NAME     U25 R19
 '@T6G_MB_LIB.T6G(SCH_1):PAGE18_I159@PURE_QUANTA.GENOA_SP5(CHIPS)':
 'MIA_DATA12': CDS_PINID='MIA_DATA12';
NODE_NAME     J18 25
 '@T6G_MB_LIB.T6G(SCH_1):PAGE93_I22@PURE_QUANTA.SCONN288_DDR506112002KQ(CHIPS)':
 'DQ12_A': CDS_PINID='DQ12_A';
NET_NAME
'M_I_CPU0_SA_DQ<13>'
 '@T6G_MB_LIB.T6G(SCH_1):M_I_CPU0_SA_DQ'<13>:
 C_SIGNAL='@t6g_mb_lib.t6g(sch_1):m_i_cpu0_sa_dq(13)';
NODE_NAME     U25 T21
 '@T6G_MB_LIB.T6G(SCH_1):PAGE18_I159@PURE_QUANTA.GENOA_SP5(CHIPS)':
 'MIA_DATA13': CDS_PINID='MIA_DATA13';
NODE_NAME     J18 27
 '@T6G_MB_LIB.T6G(SCH_1):PAGE93_I22@PURE_QUANTA.SCONN288_DDR506112002KQ(CHIPS)':
 'DQ13_A': CDS_PINID='DQ13_A';
NET_NAME
'M_I_CPU0_SA_DQ<14>'
 '@T6G_MB_LIB.T6G(SCH_1):M_I_CPU0_SA_DQ'<14>:
 C_SIGNAL='@t6g_mb_lib.t6g(sch_1):m_i_cpu0_sa_dq(14)';
NODE_NAME     U25 T20
 '@T6G_MB_LIB.T6G(SCH_1):PAGE18_I159@PURE_QUANTA.GENOA_SP5(CHIPS)':
 'MIA_DATA14': CDS_PINID='MIA_DATA14';
NODE_NAME     J18 170
 '@T6G_MB_LIB.T6G(SCH_1):PAGE93_I22@PURE_QUANTA.SCONN288_DDR506112002KQ(CHIPS)':
 'DQ14_A': CDS_PINID='DQ14_A';
NET_NAME
'M_I_CPU0_SA_DQ<15>'
 '@T6G_MB_LIB.T6G(SCH_1):M_I_CPU0_SA_DQ'<15>:
 C_SIGNAL='@t6g_mb_lib.t6g(sch_1):m_i_cpu0_sa_dq(15)';
NODE_NAME     U25 U21
 '@T6G_MB_LIB.T6G(SCH_1):PAGE18_I159@PURE_QUANTA.GENOA_SP5(CHIPS)':
 'MIA_DATA15': CDS_PINID='MIA_DATA15';
NODE_NAME     J18 172
 '@T6G_MB_LIB.T6G(SCH_1):PAGE93_I22@PURE_QUANTA.SCONN288_DDR506112002KQ(CHIPS)':
 'DQ15_A': CDS_PINID='DQ15_A';
NET_NAME
'M_I_CPU0_SA_DQ<16>'
 '@T6G_MB_LIB.T6G(SCH_1):M_I_CPU0_SA_DQ'<16>:
 C_SIGNAL='@t6g_mb_lib.t6g(sch_1):m_i_cpu0_sa_dq(16)';
NODE_NAME     U25 U19
 '@T6G_MB_LIB.T6G(SCH_1):PAGE18_I159@PURE_QUANTA.GENOA_SP5(CHIPS)':
 'MIA_DATA16': CDS_PINID='MIA_DATA16';
NODE_NAME     J18 29
 '@T6G_MB_LIB.T6G(SCH_1):PAGE93_I22@PURE_QUANTA.SCONN288_DDR506112002KQ(CHIPS)':
 'DQ16_A': CDS_PINID='DQ16_A';
NET_NAME
'M_I_CPU0_SA_DQ<17>'
 '@T6G_MB_LIB.T6G(SCH_1):M_I_CPU0_SA_DQ'<17>:
 C_SIGNAL='@t6g_mb_lib.t6g(sch_1):m_i_cpu0_sa_dq(17)';
NODE_NAME     U25 V21
 '@T6G_MB_LIB.T6G(SCH_1):PAGE18_I159@PURE_QUANTA.GENOA_SP5(CHIPS)':
 'MIA_DATA17': CDS_PINID='MIA_DATA17';
NODE_NAME     J18 31
 '@T6G_MB_LIB.T6G(SCH_1):PAGE93_I22@PURE_QUANTA.SCONN288_DDR506112002KQ(CHIPS)':
 'DQ17_A': CDS_PINID='DQ17_A';
NET_NAME
'M_I_CPU0_SA_DQ<18>'
 '@T6G_MB_LIB.T6G(SCH_1):M_I_CPU0_SA_DQ'<18>:
 C_SIGNAL='@t6g_mb_lib.t6g(sch_1):m_i_cpu0_sa_dq(18)';
NODE_NAME     U25 V20
 '@T6G_MB_LIB.T6G(SCH_1):PAGE18_I159@PURE_QUANTA.GENOA_SP5(CHIPS)':
 'MIA_DATA18': CDS_PINID='MIA_DATA18';
NODE_NAME     J18 174
 '@T6G_MB_LIB.T6G(SCH_1):PAGE93_I22@PURE_QUANTA.SCONN288_DDR506112002KQ(CHIPS)':
 'DQ18_A': CDS_PINID='DQ18_A';
NET_NAME
'M_I_CPU0_SA_DQ<19>'
 '@T6G_MB_LIB.T6G(SCH_1):M_I_CPU0_SA_DQ'<19>:
 C_SIGNAL='@t6g_mb_lib.t6g(sch_1):m_i_cpu0_sa_dq(19)';
NODE_NAME     U25 W21
 '@T6G_MB_LIB.T6G(SCH_1):PAGE18_I159@PURE_QUANTA.GENOA_SP5(CHIPS)':
 'MIA_DATA19': CDS_PINID='MIA_DATA19';
NODE_NAME     J18 176
 '@T6G_MB_LIB.T6G(SCH_1):PAGE93_I22@PURE_QUANTA.SCONN288_DDR506112002KQ(CHIPS)':
 'DQ19_A': CDS_PINID='DQ19_A';
NET_NAME
'M_I_CPU0_SA_DQ<1>'
 '@T6G_MB_LIB.T6G(SCH_1):M_I_CPU0_SA_DQ'<1>:
 C_SIGNAL='@t6g_mb_lib.t6g(sch_1):m_i_cpu0_sa_dq(1)';
NODE_NAME     U25 F21
 '@T6G_MB_LIB.T6G(SCH_1):PAGE18_I159@PURE_QUANTA.GENOA_SP5(CHIPS)':
 'MIA_DATA1': CDS_PINID='MIA_DATA1';
NODE_NAME     J18 9
 '@T6G_MB_LIB.T6G(SCH_1):PAGE93_I22@PURE_QUANTA.SCONN288_DDR506112002KQ(CHIPS)':
 'DQ1_A': CDS_PINID='DQ1_A';
NET_NAME
'M_I_CPU0_SA_DQ<20>'
 '@T6G_MB_LIB.T6G(SCH_1):M_I_CPU0_SA_DQ'<20>:
 C_SIGNAL='@t6g_mb_lib.t6g(sch_1):m_i_cpu0_sa_dq(20)';
NODE_NAME     U25 AA19
 '@T6G_MB_LIB.T6G(SCH_1):PAGE18_I159@PURE_QUANTA.GENOA_SP5(CHIPS)':
 'MIA_DATA20': CDS_PINID='MIA_DATA20';
NODE_NAME     J18 36
 '@T6G_MB_LIB.T6G(SCH_1):PAGE93_I22@PURE_QUANTA.SCONN288_DDR506112002KQ(CHIPS)':
 'DQ20_A': CDS_PINID='DQ20_A';
NET_NAME
'M_I_CPU0_SA_DQ<21>'
 '@T6G_MB_LIB.T6G(SCH_1):M_I_CPU0_SA_DQ'<21>:
 C_SIGNAL='@t6g_mb_lib.t6g(sch_1):m_i_cpu0_sa_dq(21)';
NODE_NAME     U25 AB21
 '@T6G_MB_LIB.T6G(SCH_1):PAGE18_I159@PURE_QUANTA.GENOA_SP5(CHIPS)':
 'MIA_DATA21': CDS_PINID='MIA_DATA21';
NODE_NAME     J18 38
 '@T6G_MB_LIB.T6G(SCH_1):PAGE93_I22@PURE_QUANTA.SCONN288_DDR506112002KQ(CHIPS)':
 'DQ21_A': CDS_PINID='DQ21_A';
NET_NAME
'M_I_CPU0_SA_DQ<22>'
 '@T6G_MB_LIB.T6G(SCH_1):M_I_CPU0_SA_DQ'<22>:
 C_SIGNAL='@t6g_mb_lib.t6g(sch_1):m_i_cpu0_sa_dq(22)';
NODE_NAME     U25 AB20
 '@T6G_MB_LIB.T6G(SCH_1):PAGE18_I159@PURE_QUANTA.GENOA_SP5(CHIPS)':
 'MIA_DATA22': CDS_PINID='MIA_DATA22';
NODE_NAME     J18 181
 '@T6G_MB_LIB.T6G(SCH_1):PAGE93_I22@PURE_QUANTA.SCONN288_DDR506112002KQ(CHIPS)':
 'DQ22_A': CDS_PINID='DQ22_A';
NET_NAME
'M_I_CPU0_SA_DQ<23>'
 '@T6G_MB_LIB.T6G(SCH_1):M_I_CPU0_SA_DQ'<23>:
 C_SIGNAL='@t6g_mb_lib.t6g(sch_1):m_i_cpu0_sa_dq(23)';
NODE_NAME     U25 AC21
 '@T6G_MB_LIB.T6G(SCH_1):PAGE18_I159@PURE_QUANTA.GENOA_SP5(CHIPS)':
 'MIA_DATA23': CDS_PINID='MIA_DATA23';
NODE_NAME     J18 183
 '@T6G_MB_LIB.T6G(SCH_1):PAGE93_I22@PURE_QUANTA.SCONN288_DDR506112002KQ(CHIPS)':
 'DQ23_A': CDS_PINID='DQ23_A';
NET_NAME
'M_I_CPU0_SA_DQ<24>'
 '@T6G_MB_LIB.T6G(SCH_1):M_I_CPU0_SA_DQ'<24>:
 C_SIGNAL='@t6g_mb_lib.t6g(sch_1):m_i_cpu0_sa_dq(24)';
NODE_NAME     U25 AC19
 '@T6G_MB_LIB.T6G(SCH_1):PAGE18_I159@PURE_QUANTA.GENOA_SP5(CHIPS)':
 'MIA_DATA24': CDS_PINID='MIA_DATA24';
NODE_NAME     J18 40
 '@T6G_MB_LIB.T6G(SCH_1):PAGE93_I22@PURE_QUANTA.SCONN288_DDR506112002KQ(CHIPS)':
 'DQ24_A': CDS_PINID='DQ24_A';
NET_NAME
'M_I_CPU0_SA_DQ<25>'
 '@T6G_MB_LIB.T6G(SCH_1):M_I_CPU0_SA_DQ'<25>:
 C_SIGNAL='@t6g_mb_lib.t6g(sch_1):m_i_cpu0_sa_dq(25)';
NODE_NAME     U25 AD21
 '@T6G_MB_LIB.T6G(SCH_1):PAGE18_I159@PURE_QUANTA.GENOA_SP5(CHIPS)':
 'MIA_DATA25': CDS_PINID='MIA_DATA25';
NODE_NAME     J18 42
 '@T6G_MB_LIB.T6G(SCH_1):PAGE93_I22@PURE_QUANTA.SCONN288_DDR506112002KQ(CHIPS)':
 'DQ25_A': CDS_PINID='DQ25_A';
NET_NAME
'M_I_CPU0_SA_DQ<26>'
 '@T6G_MB_LIB.T6G(SCH_1):M_I_CPU0_SA_DQ'<26>:
 C_SIGNAL='@t6g_mb_lib.t6g(sch_1):m_i_cpu0_sa_dq(26)';
NODE_NAME     U25 AD20
 '@T6G_MB_LIB.T6G(SCH_1):PAGE18_I159@PURE_QUANTA.GENOA_SP5(CHIPS)':
 'MIA_DATA26': CDS_PINID='MIA_DATA26';
NODE_NAME     J18 185
 '@T6G_MB_LIB.T6G(SCH_1):PAGE93_I22@PURE_QUANTA.SCONN288_DDR506112002KQ(CHIPS)':
 'DQ26_A': CDS_PINID='DQ26_A';
NET_NAME
'M_I_CPU0_SA_DQ<27>'
 '@T6G_MB_LIB.T6G(SCH_1):M_I_CPU0_SA_DQ'<27>:
 C_SIGNAL='@t6g_mb_lib.t6g(sch_1):m_i_cpu0_sa_dq(27)';
NODE_NAME     U25 AE21
 '@T6G_MB_LIB.T6G(SCH_1):PAGE18_I159@PURE_QUANTA.GENOA_SP5(CHIPS)':
 'MIA_DATA27': CDS_PINID='MIA_DATA27';
NODE_NAME     J18 187
 '@T6G_MB_LIB.T6G(SCH_1):PAGE93_I22@PURE_QUANTA.SCONN288_DDR506112002KQ(CHIPS)':
 'DQ27_A': CDS_PINID='DQ27_A';
NET_NAME
'M_I_CPU0_SA_DQ<28>'
 '@T6G_MB_LIB.T6G(SCH_1):M_I_CPU0_SA_DQ'<28>:
 C_SIGNAL='@t6g_mb_lib.t6g(sch_1):m_i_cpu0_sa_dq(28)';
NODE_NAME     U25 AG19
 '@T6G_MB_LIB.T6G(SCH_1):PAGE18_I159@PURE_QUANTA.GENOA_SP5(CHIPS)':
 'MIA_DATA28': CDS_PINID='MIA_DATA28';
NODE_NAME     J18 47
 '@T6G_MB_LIB.T6G(SCH_1):PAGE93_I22@PURE_QUANTA.SCONN288_DDR506112002KQ(CHIPS)':
 'DQ28_A': CDS_PINID='DQ28_A';
NET_NAME
'M_I_CPU0_SA_DQ<29>'
 '@T6G_MB_LIB.T6G(SCH_1):M_I_CPU0_SA_DQ'<29>:
 C_SIGNAL='@t6g_mb_lib.t6g(sch_1):m_i_cpu0_sa_dq(29)';
NODE_NAME     U25 AH21
 '@T6G_MB_LIB.T6G(SCH_1):PAGE18_I159@PURE_QUANTA.GENOA_SP5(CHIPS)':
 'MIA_DATA29': CDS_PINID='MIA_DATA29';
NODE_NAME     J18 49
 '@T6G_MB_LIB.T6G(SCH_1):PAGE93_I22@PURE_QUANTA.SCONN288_DDR506112002KQ(CHIPS)':
 'DQ29_A': CDS_PINID='DQ29_A';
NET_NAME
'M_I_CPU0_SA_DQ<2>'
 '@T6G_MB_LIB.T6G(SCH_1):M_I_CPU0_SA_DQ'<2>:
 C_SIGNAL='@t6g_mb_lib.t6g(sch_1):m_i_cpu0_sa_dq(2)';
NODE_NAME     U25 F20
 '@T6G_MB_LIB.T6G(SCH_1):PAGE18_I159@PURE_QUANTA.GENOA_SP5(CHIPS)':
 'MIA_DATA2': CDS_PINID='MIA_DATA2';
NODE_NAME     J18 152
 '@T6G_MB_LIB.T6G(SCH_1):PAGE93_I22@PURE_QUANTA.SCONN288_DDR506112002KQ(CHIPS)':
 'DQ2_A': CDS_PINID='DQ2_A';
NET_NAME
'M_I_CPU0_SA_DQ<30>'
 '@T6G_MB_LIB.T6G(SCH_1):M_I_CPU0_SA_DQ'<30>:
 C_SIGNAL='@t6g_mb_lib.t6g(sch_1):m_i_cpu0_sa_dq(30)';
NODE_NAME     U25 AH20
 '@T6G_MB_LIB.T6G(SCH_1):PAGE18_I159@PURE_QUANTA.GENOA_SP5(CHIPS)':
 'MIA_DATA30': CDS_PINID='MIA_DATA30';
NODE_NAME     J18 192
 '@T6G_MB_LIB.T6G(SCH_1):PAGE93_I22@PURE_QUANTA.SCONN288_DDR506112002KQ(CHIPS)':
 'DQ30_A': CDS_PINID='DQ30_A';
NET_NAME
'M_I_CPU0_SA_DQ<31>'
 '@T6G_MB_LIB.T6G(SCH_1):M_I_CPU0_SA_DQ'<31>:
 C_SIGNAL='@t6g_mb_lib.t6g(sch_1):m_i_cpu0_sa_dq(31)';
NODE_NAME     U25 AJ21
 '@T6G_MB_LIB.T6G(SCH_1):PAGE18_I159@PURE_QUANTA.GENOA_SP5(CHIPS)':
 'MIA_DATA31': CDS_PINID='MIA_DATA31';
NODE_NAME     J18 194
 '@T6G_MB_LIB.T6G(SCH_1):PAGE93_I22@PURE_QUANTA.SCONN288_DDR506112002KQ(CHIPS)':
 'DQ31_A': CDS_PINID='DQ31_A';
NET_NAME
'M_I_CPU0_SA_DQ<3>'
 '@T6G_MB_LIB.T6G(SCH_1):M_I_CPU0_SA_DQ'<3>:
 C_SIGNAL='@t6g_mb_lib.t6g(sch_1):m_i_cpu0_sa_dq(3)';
NODE_NAME     U25 G21
 '@T6G_MB_LIB.T6G(SCH_1):PAGE18_I159@PURE_QUANTA.GENOA_SP5(CHIPS)':
 'MIA_DATA3': CDS_PINID='MIA_DATA3';
NODE_NAME     J18 154
 '@T6G_MB_LIB.T6G(SCH_1):PAGE93_I22@PURE_QUANTA.SCONN288_DDR506112002KQ(CHIPS)':
 'DQ3_A': CDS_PINID='DQ3_A';
NET_NAME
'M_I_CPU0_SA_DQ<4>'
 '@T6G_MB_LIB.T6G(SCH_1):M_I_CPU0_SA_DQ'<4>:
 C_SIGNAL='@t6g_mb_lib.t6g(sch_1):m_i_cpu0_sa_dq(4)';
NODE_NAME     U25 J19
 '@T6G_MB_LIB.T6G(SCH_1):PAGE18_I159@PURE_QUANTA.GENOA_SP5(CHIPS)':
 'MIA_DATA4': CDS_PINID='MIA_DATA4';
NODE_NAME     J18 14
 '@T6G_MB_LIB.T6G(SCH_1):PAGE93_I22@PURE_QUANTA.SCONN288_DDR506112002KQ(CHIPS)':
 'DQ4_A': CDS_PINID='DQ4_A';
NET_NAME
'M_I_CPU0_SA_DQ<5>'
 '@T6G_MB_LIB.T6G(SCH_1):M_I_CPU0_SA_DQ'<5>:
 C_SIGNAL='@t6g_mb_lib.t6g(sch_1):m_i_cpu0_sa_dq(5)';
NODE_NAME     U25 K21
 '@T6G_MB_LIB.T6G(SCH_1):PAGE18_I159@PURE_QUANTA.GENOA_SP5(CHIPS)':
 'MIA_DATA5': CDS_PINID='MIA_DATA5';
NODE_NAME     J18 16
 '@T6G_MB_LIB.T6G(SCH_1):PAGE93_I22@PURE_QUANTA.SCONN288_DDR506112002KQ(CHIPS)':
 'DQ5_A': CDS_PINID='DQ5_A';
NET_NAME
'M_I_CPU0_SA_DQ<6>'
 '@T6G_MB_LIB.T6G(SCH_1):M_I_CPU0_SA_DQ'<6>:
 C_SIGNAL='@t6g_mb_lib.t6g(sch_1):m_i_cpu0_sa_dq(6)';
NODE_NAME     U25 K20
 '@T6G_MB_LIB.T6G(SCH_1):PAGE18_I159@PURE_QUANTA.GENOA_SP5(CHIPS)':
 'MIA_DATA6': CDS_PINID='MIA_DATA6';
NODE_NAME     J18 159
 '@T6G_MB_LIB.T6G(SCH_1):PAGE93_I22@PURE_QUANTA.SCONN288_DDR506112002KQ(CHIPS)':
 'DQ6_A': CDS_PINID='DQ6_A';
NET_NAME
'M_I_CPU0_SA_DQ<7>'
 '@T6G_MB_LIB.T6G(SCH_1):M_I_CPU0_SA_DQ'<7>:
 C_SIGNAL='@t6g_mb_lib.t6g(sch_1):m_i_cpu0_sa_dq(7)';
NODE_NAME     U25 L21
 '@T6G_MB_LIB.T6G(SCH_1):PAGE18_I159@PURE_QUANTA.GENOA_SP5(CHIPS)':
 'MIA_DATA7': CDS_PINID='MIA_DATA7';
NODE_NAME     J18 161
 '@T6G_MB_LIB.T6G(SCH_1):PAGE93_I22@PURE_QUANTA.SCONN288_DDR506112002KQ(CHIPS)':
 'DQ7_A': CDS_PINID='DQ7_A';
NET_NAME
'M_I_CPU0_SA_DQ<8>'
 '@T6G_MB_LIB.T6G(SCH_1):M_I_CPU0_SA_DQ'<8>:
 C_SIGNAL='@t6g_mb_lib.t6g(sch_1):m_i_cpu0_sa_dq(8)';
NODE_NAME     U25 L19
 '@T6G_MB_LIB.T6G(SCH_1):PAGE18_I159@PURE_QUANTA.GENOA_SP5(CHIPS)':
 'MIA_DATA8': CDS_PINID='MIA_DATA8';
NODE_NAME     J18 18
 '@T6G_MB_LIB.T6G(SCH_1):PAGE93_I22@PURE_QUANTA.SCONN288_DDR506112002KQ(CHIPS)':
 'DQ8_A': CDS_PINID='DQ8_A';
NET_NAME
'M_I_CPU0_SA_DQ<9>'
 '@T6G_MB_LIB.T6G(SCH_1):M_I_CPU0_SA_DQ'<9>:
 C_SIGNAL='@t6g_mb_lib.t6g(sch_1):m_i_cpu0_sa_dq(9)';
NODE_NAME     U25 M21
 '@T6G_MB_LIB.T6G(SCH_1):PAGE18_I159@PURE_QUANTA.GENOA_SP5(CHIPS)':
 'MIA_DATA9': CDS_PINID='MIA_DATA9';
NODE_NAME     J18 20
 '@T6G_MB_LIB.T6G(SCH_1):PAGE93_I22@PURE_QUANTA.SCONN288_DDR506112002KQ(CHIPS)':
 'DQ9_A': CDS_PINID='DQ9_A';
NET_NAME
'M_I_CPU0_SA_DQS_DN<0>'
 '@T6G_MB_LIB.T6G(SCH_1):M_I_CPU0_SA_DQS_DN'<0>:
 C_SIGNAL='@t6g_mb_lib.t6g(sch_1):m_i_cpu0_sa_dqs_dn(0)';
NODE_NAME     U25 H20
 '@T6G_MB_LIB.T6G(SCH_1):PAGE18_I159@PURE_QUANTA.GENOA_SP5(CHIPS)':
 'MIA_DQS_L0': CDS_PINID='MIA_DQS_L0';
NODE_NAME     J18 12
 '@T6G_MB_LIB.T6G(SCH_1):PAGE93_I236@PURE_QUANTA.SCONN288_DDR506112002KQ(CHIPS)':
 'DQS0_A_C': CDS_PINID='DQS0_A_C';
NET_NAME
'M_I_CPU0_SA_DQS_DN<1>'
 '@T6G_MB_LIB.T6G(SCH_1):M_I_CPU0_SA_DQS_DN'<1>:
 C_SIGNAL='@t6g_mb_lib.t6g(sch_1):m_i_cpu0_sa_dqs_dn(1)';
NODE_NAME     U25 P20
 '@T6G_MB_LIB.T6G(SCH_1):PAGE18_I159@PURE_QUANTA.GENOA_SP5(CHIPS)':
 'MIA_DQS_L1': CDS_PINID='MIA_DQS_L1';
NODE_NAME     J18 23
 '@T6G_MB_LIB.T6G(SCH_1):PAGE93_I236@PURE_QUANTA.SCONN288_DDR506112002KQ(CHIPS)':
 'DQS1_A_C': CDS_PINID='DQS1_A_C';
NET_NAME
'M_I_CPU0_SA_DQS_DN<2>'
 '@T6G_MB_LIB.T6G(SCH_1):M_I_CPU0_SA_DQS_DN'<2>:
 C_SIGNAL='@t6g_mb_lib.t6g(sch_1):m_i_cpu0_sa_dqs_dn(2)';
NODE_NAME     U25 Y20
 '@T6G_MB_LIB.T6G(SCH_1):PAGE18_I159@PURE_QUANTA.GENOA_SP5(CHIPS)':
 'MIA_DQS_L2': CDS_PINID='MIA_DQS_L2';
NODE_NAME     J18 34
 '@T6G_MB_LIB.T6G(SCH_1):PAGE93_I236@PURE_QUANTA.SCONN288_DDR506112002KQ(CHIPS)':
 'DQS2_A_C': CDS_PINID='DQS2_A_C';
NET_NAME
'M_I_CPU0_SA_DQS_DN<3>'
 '@T6G_MB_LIB.T6G(SCH_1):M_I_CPU0_SA_DQS_DN'<3>:
 C_SIGNAL='@t6g_mb_lib.t6g(sch_1):m_i_cpu0_sa_dqs_dn(3)';
NODE_NAME     U25 AF20
 '@T6G_MB_LIB.T6G(SCH_1):PAGE18_I159@PURE_QUANTA.GENOA_SP5(CHIPS)':
 'MIA_DQS_L3': CDS_PINID='MIA_DQS_L3';
NODE_NAME     J18 45
 '@T6G_MB_LIB.T6G(SCH_1):PAGE93_I236@PURE_QUANTA.SCONN288_DDR506112002KQ(CHIPS)':
 'DQS3_A_C': CDS_PINID='DQS3_A_C';
NET_NAME
'M_I_CPU0_SA_DQS_DN<4>'
 '@T6G_MB_LIB.T6G(SCH_1):M_I_CPU0_SA_DQS_DN'<4>:
 C_SIGNAL='@t6g_mb_lib.t6g(sch_1):m_i_cpu0_sa_dqs_dn(4)';
NODE_NAME     U25 AM20
 '@T6G_MB_LIB.T6G(SCH_1):PAGE18_I159@PURE_QUANTA.GENOA_SP5(CHIPS)':
 'MIA_DQS_L4': CDS_PINID='MIA_DQS_L4';
NODE_NAME     J18 56
 '@T6G_MB_LIB.T6G(SCH_1):PAGE93_I236@PURE_QUANTA.SCONN288_DDR506112002KQ(CHIPS)':
 'DQS4_A_C': CDS_PINID='DQS4_A_C';
NET_NAME
'M_I_CPU0_SA_DQS_DN<5>'
 '@T6G_MB_LIB.T6G(SCH_1):M_I_CPU0_SA_DQS_DN'<5>:
 C_SIGNAL='@t6g_mb_lib.t6g(sch_1):m_i_cpu0_sa_dqs_dn(5)';
NODE_NAME     U25 H21
 '@T6G_MB_LIB.T6G(SCH_1):PAGE18_I159@PURE_QUANTA.GENOA_SP5(CHIPS)':
 'MIA_DQS_L5': CDS_PINID='MIA_DQS_L5';
NODE_NAME     J18 156
 '@T6G_MB_LIB.T6G(SCH_1):PAGE93_I236@PURE_QUANTA.SCONN288_DDR506112002KQ(CHIPS)':
 'DQS5_A_C||TDQS5_A_C||DQS5_A_T||TDQS5_A_T': CDS_PINID='\dqs5_a_c||tdqs5_a_c||dqs5_a_t||tdqs5_a_t\';
NET_NAME
'M_I_CPU0_SA_DQS_DN<6>'
 '@T6G_MB_LIB.T6G(SCH_1):M_I_CPU0_SA_DQS_DN'<6>:
 C_SIGNAL='@t6g_mb_lib.t6g(sch_1):m_i_cpu0_sa_dqs_dn(6)';
NODE_NAME     U25 P21
 '@T6G_MB_LIB.T6G(SCH_1):PAGE18_I159@PURE_QUANTA.GENOA_SP5(CHIPS)':
 'MIA_DQS_L6': CDS_PINID='MIA_DQS_L6';
NODE_NAME     J18 167
 '@T6G_MB_LIB.T6G(SCH_1):PAGE93_I236@PURE_QUANTA.SCONN288_DDR506112002KQ(CHIPS)':
 'DQS6_A_C||TDQS6_A_C||DQS6_A_T||TDQS6_A_T': CDS_PINID='\dqs6_a_c||tdqs6_a_c||dqs6_a_t||tdqs6_a_t\';
NET_NAME
'M_I_CPU0_SA_DQS_DN<7>'
 '@T6G_MB_LIB.T6G(SCH_1):M_I_CPU0_SA_DQS_DN'<7>:
 C_SIGNAL='@t6g_mb_lib.t6g(sch_1):m_i_cpu0_sa_dqs_dn(7)';
NODE_NAME     U25 Y21
 '@T6G_MB_LIB.T6G(SCH_1):PAGE18_I159@PURE_QUANTA.GENOA_SP5(CHIPS)':
 'MIA_DQS_L7': CDS_PINID='MIA_DQS_L7';
NODE_NAME     J18 178
 '@T6G_MB_LIB.T6G(SCH_1):PAGE93_I236@PURE_QUANTA.SCONN288_DDR506112002KQ(CHIPS)':
 'DQS7_A_C||TDQS7_A_C': CDS_PINID='\dqs7_a_c||tdqs7_a_c\';
NET_NAME
'M_I_CPU0_SA_DQS_DN<8>'
 '@T6G_MB_LIB.T6G(SCH_1):M_I_CPU0_SA_DQS_DN'<8>:
 C_SIGNAL='@t6g_mb_lib.t6g(sch_1):m_i_cpu0_sa_dqs_dn(8)';
NODE_NAME     U25 AF21
 '@T6G_MB_LIB.T6G(SCH_1):PAGE18_I159@PURE_QUANTA.GENOA_SP5(CHIPS)':
 'MIA_DQS_L8': CDS_PINID='MIA_DQS_L8';
NODE_NAME     J18 189
 '@T6G_MB_LIB.T6G(SCH_1):PAGE93_I236@PURE_QUANTA.SCONN288_DDR506112002KQ(CHIPS)':
 'DQS8_A_C||TDQS8_A_C': CDS_PINID='\dqs8_a_c||tdqs8_a_c\';
NET_NAME
'M_I_CPU0_SA_DQS_DN<9>'
 '@T6G_MB_LIB.T6G(SCH_1):M_I_CPU0_SA_DQS_DN'<9>:
 C_SIGNAL='@t6g_mb_lib.t6g(sch_1):m_i_cpu0_sa_dqs_dn(9)';
NODE_NAME     U25 AM21
 '@T6G_MB_LIB.T6G(SCH_1):PAGE18_I159@PURE_QUANTA.GENOA_SP5(CHIPS)':
 'MIA_DQS_L9': CDS_PINID='MIA_DQS_L9';
NODE_NAME     J18 200
 '@T6G_MB_LIB.T6G(SCH_1):PAGE93_I236@PURE_QUANTA.SCONN288_DDR506112002KQ(CHIPS)':
 'DQS9_A_C||TDQS9_A_C': CDS_PINID='\dqs9_a_c||tdqs9_a_c\';
NET_NAME
'M_I_CPU0_SA_DQS_DP<0>'
 '@T6G_MB_LIB.T6G(SCH_1):M_I_CPU0_SA_DQS_DP'<0>:
 C_SIGNAL='@t6g_mb_lib.t6g(sch_1):m_i_cpu0_sa_dqs_dp(0)';
NODE_NAME     U25 G19
 '@T6G_MB_LIB.T6G(SCH_1):PAGE18_I159@PURE_QUANTA.GENOA_SP5(CHIPS)':
 'MIA_DQS_H0': CDS_PINID='MIA_DQS_H0';
NODE_NAME     J18 11
 '@T6G_MB_LIB.T6G(SCH_1):PAGE93_I236@PURE_QUANTA.SCONN288_DDR506112002KQ(CHIPS)':
 'DQS0_A_T': CDS_PINID='DQS0_A_T';
NET_NAME
'M_I_CPU0_SA_DQS_DP<1>'
 '@T6G_MB_LIB.T6G(SCH_1):M_I_CPU0_SA_DQS_DP'<1>:
 C_SIGNAL='@t6g_mb_lib.t6g(sch_1):m_i_cpu0_sa_dqs_dp(1)';
NODE_NAME     U25 N19
 '@T6G_MB_LIB.T6G(SCH_1):PAGE18_I159@PURE_QUANTA.GENOA_SP5(CHIPS)':
 'MIA_DQS_H1': CDS_PINID='MIA_DQS_H1';
NODE_NAME     J18 22
 '@T6G_MB_LIB.T6G(SCH_1):PAGE93_I236@PURE_QUANTA.SCONN288_DDR506112002KQ(CHIPS)':
 'DQS1_A_T': CDS_PINID='DQS1_A_T';
NET_NAME
'M_I_CPU0_SA_DQS_DP<2>'
 '@T6G_MB_LIB.T6G(SCH_1):M_I_CPU0_SA_DQS_DP'<2>:
 C_SIGNAL='@t6g_mb_lib.t6g(sch_1):m_i_cpu0_sa_dqs_dp(2)';
NODE_NAME     U25 W19
 '@T6G_MB_LIB.T6G(SCH_1):PAGE18_I159@PURE_QUANTA.GENOA_SP5(CHIPS)':
 'MIA_DQS_H2': CDS_PINID='MIA_DQS_H2';
NODE_NAME     J18 33
 '@T6G_MB_LIB.T6G(SCH_1):PAGE93_I236@PURE_QUANTA.SCONN288_DDR506112002KQ(CHIPS)':
 'DQS2_A_T': CDS_PINID='DQS2_A_T';
NET_NAME
'M_I_CPU0_SA_DQS_DP<3>'
 '@T6G_MB_LIB.T6G(SCH_1):M_I_CPU0_SA_DQS_DP'<3>:
 C_SIGNAL='@t6g_mb_lib.t6g(sch_1):m_i_cpu0_sa_dqs_dp(3)';
NODE_NAME     U25 AE19
 '@T6G_MB_LIB.T6G(SCH_1):PAGE18_I159@PURE_QUANTA.GENOA_SP5(CHIPS)':
 'MIA_DQS_H3': CDS_PINID='MIA_DQS_H3';
NODE_NAME     J18 44
 '@T6G_MB_LIB.T6G(SCH_1):PAGE93_I236@PURE_QUANTA.SCONN288_DDR506112002KQ(CHIPS)':
 'DQS3_A_T': CDS_PINID='DQS3_A_T';
NET_NAME
'M_I_CPU0_SA_DQS_DP<4>'
 '@T6G_MB_LIB.T6G(SCH_1):M_I_CPU0_SA_DQS_DP'<4>:
 C_SIGNAL='@t6g_mb_lib.t6g(sch_1):m_i_cpu0_sa_dqs_dp(4)';
NODE_NAME     U25 AL19
 '@T6G_MB_LIB.T6G(SCH_1):PAGE18_I159@PURE_QUANTA.GENOA_SP5(CHIPS)':
 'MIA_DQS_H4': CDS_PINID='MIA_DQS_H4';
NODE_NAME     J18 55
 '@T6G_MB_LIB.T6G(SCH_1):PAGE93_I236@PURE_QUANTA.SCONN288_DDR506112002KQ(CHIPS)':
 'DQS4_A_T': CDS_PINID='DQS4_A_T';
NET_NAME
'M_I_CPU0_SA_DQS_DP<5>'
 '@T6G_MB_LIB.T6G(SCH_1):M_I_CPU0_SA_DQS_DP'<5>:
 C_SIGNAL='@t6g_mb_lib.t6g(sch_1):m_i_cpu0_sa_dqs_dp(5)';
NODE_NAME     U25 J21
 '@T6G_MB_LIB.T6G(SCH_1):PAGE18_I159@PURE_QUANTA.GENOA_SP5(CHIPS)':
 'MIA_DQS_H5': CDS_PINID='MIA_DQS_H5';
NODE_NAME     J18 157
 '@T6G_MB_LIB.T6G(SCH_1):PAGE93_I236@PURE_QUANTA.SCONN288_DDR506112002KQ(CHIPS)':
 'DQS5_A_T||TDQS5_A_T': CDS_PINID='\dqs5_a_t||tdqs5_a_t\';
NET_NAME
'M_I_CPU0_SA_DQS_DP<6>'
 '@T6G_MB_LIB.T6G(SCH_1):M_I_CPU0_SA_DQS_DP'<6>:
 C_SIGNAL='@t6g_mb_lib.t6g(sch_1):m_i_cpu0_sa_dqs_dp(6)';
NODE_NAME     U25 R21
 '@T6G_MB_LIB.T6G(SCH_1):PAGE18_I159@PURE_QUANTA.GENOA_SP5(CHIPS)':
 'MIA_DQS_H6': CDS_PINID='MIA_DQS_H6';
NODE_NAME     J18 168
 '@T6G_MB_LIB.T6G(SCH_1):PAGE93_I236@PURE_QUANTA.SCONN288_DDR506112002KQ(CHIPS)':
 'DQS6_A_T||TDQS6_A_T': CDS_PINID='\dqs6_a_t||tdqs6_a_t\';
NET_NAME
'M_I_CPU0_SA_DQS_DP<7>'
 '@T6G_MB_LIB.T6G(SCH_1):M_I_CPU0_SA_DQS_DP'<7>:
 C_SIGNAL='@t6g_mb_lib.t6g(sch_1):m_i_cpu0_sa_dqs_dp(7)';
NODE_NAME     U25 AA21
 '@T6G_MB_LIB.T6G(SCH_1):PAGE18_I159@PURE_QUANTA.GENOA_SP5(CHIPS)':
 'MIA_DQS_H7': CDS_PINID='MIA_DQS_H7';
NODE_NAME     J18 179
 '@T6G_MB_LIB.T6G(SCH_1):PAGE93_I236@PURE_QUANTA.SCONN288_DDR506112002KQ(CHIPS)':
 'DQS7_A_T||TDQS7_A_T': CDS_PINID='\dqs7_a_t||tdqs7_a_t\';
NET_NAME
'M_I_CPU0_SA_DQS_DP<8>'
 '@T6G_MB_LIB.T6G(SCH_1):M_I_CPU0_SA_DQS_DP'<8>:
 C_SIGNAL='@t6g_mb_lib.t6g(sch_1):m_i_cpu0_sa_dqs_dp(8)';
NODE_NAME     U25 AG21
 '@T6G_MB_LIB.T6G(SCH_1):PAGE18_I159@PURE_QUANTA.GENOA_SP5(CHIPS)':
 'MIA_DQS_H8': CDS_PINID='MIA_DQS_H8';
NODE_NAME     J18 190
 '@T6G_MB_LIB.T6G(SCH_1):PAGE93_I236@PURE_QUANTA.SCONN288_DDR506112002KQ(CHIPS)':
 'DQS8_A_T||TDQS8_A_T': CDS_PINID='\dqs8_a_t||tdqs8_a_t\';
NET_NAME
'M_I_CPU0_SA_DQS_DP<9>'
 '@T6G_MB_LIB.T6G(SCH_1):M_I_CPU0_SA_DQS_DP'<9>:
 C_SIGNAL='@t6g_mb_lib.t6g(sch_1):m_i_cpu0_sa_dqs_dp(9)';
NODE_NAME     U25 AN21
 '@T6G_MB_LIB.T6G(SCH_1):PAGE18_I159@PURE_QUANTA.GENOA_SP5(CHIPS)':
 'MIA_DQS_H9': CDS_PINID='MIA_DQS_H9';
NODE_NAME     J18 201
 '@T6G_MB_LIB.T6G(SCH_1):PAGE93_I236@PURE_QUANTA.SCONN288_DDR506112002KQ(CHIPS)':
 'DQS9_A_T||TDQS9_A_T': CDS_PINID='\dqs9_a_t||tdqs9_a_t\';
NET_NAME
'M_I_CPU0_SA_PAR'
 '@T6G_MB_LIB.T6G(SCH_1):M_I_CPU0_SA_PAR':
 C_SIGNAL='@t6g_mb_lib.t6g(sch_1):m_i_cpu0_sa_par';
NODE_NAME     U25 BC21
 '@T6G_MB_LIB.T6G(SCH_1):PAGE18_I159@PURE_QUANTA.GENOA_SP5(CHIPS)':
 'MIA_PAR': CDS_PINID='MIA_PAR';
NODE_NAME     J18 74
 '@T6G_MB_LIB.T6G(SCH_1):PAGE93_I22@PURE_QUANTA.SCONN288_DDR506112002KQ(CHIPS)':
 'PAR_A': CDS_PINID='PAR_A';
NET_NAME
'M_I_CPU0_SA_RSP<0>'
 '@T6G_MB_LIB.T6G(SCH_1):M_I_CPU0_SA_RSP'<0>:
 C_SIGNAL='@t6g_mb_lib.t6g(sch_1):m_i_cpu0_sa_rsp(0)';
NODE_NAME     U25 BN21
 '@T6G_MB_LIB.T6G(SCH_1):PAGE18_I159@PURE_QUANTA.GENOA_SP5(CHIPS)':
 'MIA0_RSP_L': CDS_PINID='MIA0_RSP_L';
NODE_NAME     J18 86
 '@T6G_MB_LIB.T6G(SCH_1):PAGE93_I22@PURE_QUANTA.SCONN288_DDR506112002KQ(CHIPS)':
 'LBD||RSP_A_N': CDS_PINID='\lbd||rsp_a_n\';
NET_NAME
'M_I_CPU0_SB_CA<0>'
 '@T6G_MB_LIB.T6G(SCH_1):M_I_CPU0_SB_CA'<0>:
 C_SIGNAL='@t6g_mb_lib.t6g(sch_1):m_i_cpu0_sb_ca(0)';
NODE_NAME     U25 BG21
 '@T6G_MB_LIB.T6G(SCH_1):PAGE18_I159@PURE_QUANTA.GENOA_SP5(CHIPS)':
 'MIB_CA0': CDS_PINID='MIB_CA0';
NODE_NAME     J18 76
 '@T6G_MB_LIB.T6G(SCH_1):PAGE93_I22@PURE_QUANTA.SCONN288_DDR506112002KQ(CHIPS)':
 'CA0_B': CDS_PINID='CA0_B';
NET_NAME
'M_I_CPU0_SB_CA<1>'
 '@T6G_MB_LIB.T6G(SCH_1):M_I_CPU0_SB_CA'<1>:
 C_SIGNAL='@t6g_mb_lib.t6g(sch_1):m_i_cpu0_sb_ca(1)';
NODE_NAME     U25 BH21
 '@T6G_MB_LIB.T6G(SCH_1):PAGE18_I159@PURE_QUANTA.GENOA_SP5(CHIPS)':
 'MIB_CA1': CDS_PINID='MIB_CA1';
NODE_NAME     J18 221
 '@T6G_MB_LIB.T6G(SCH_1):PAGE93_I22@PURE_QUANTA.SCONN288_DDR506112002KQ(CHIPS)':
 'CA1_B': CDS_PINID='CA1_B';
NET_NAME
'M_I_CPU0_SB_CA<2>'
 '@T6G_MB_LIB.T6G(SCH_1):M_I_CPU0_SB_CA'<2>:
 C_SIGNAL='@t6g_mb_lib.t6g(sch_1):m_i_cpu0_sb_ca(2)';
NODE_NAME     U25 BH20
 '@T6G_MB_LIB.T6G(SCH_1):PAGE18_I159@PURE_QUANTA.GENOA_SP5(CHIPS)':
 'MIB_CA2': CDS_PINID='MIB_CA2';
NODE_NAME     J18 78
 '@T6G_MB_LIB.T6G(SCH_1):PAGE93_I22@PURE_QUANTA.SCONN288_DDR506112002KQ(CHIPS)':
 'CA2_B': CDS_PINID='CA2_B';
NET_NAME
'M_I_CPU0_SB_CA<3>'
 '@T6G_MB_LIB.T6G(SCH_1):M_I_CPU0_SB_CA'<3>:
 C_SIGNAL='@t6g_mb_lib.t6g(sch_1):m_i_cpu0_sb_ca(3)';
NODE_NAME     U25 BJ19
 '@T6G_MB_LIB.T6G(SCH_1):PAGE18_I159@PURE_QUANTA.GENOA_SP5(CHIPS)':
 'MIB_CA3': CDS_PINID='MIB_CA3';
NODE_NAME     J18 223
 '@T6G_MB_LIB.T6G(SCH_1):PAGE93_I22@PURE_QUANTA.SCONN288_DDR506112002KQ(CHIPS)':
 'CA3_B': CDS_PINID='CA3_B';
NET_NAME
'M_I_CPU0_SB_CA<4>'
 '@T6G_MB_LIB.T6G(SCH_1):M_I_CPU0_SB_CA'<4>:
 C_SIGNAL='@t6g_mb_lib.t6g(sch_1):m_i_cpu0_sb_ca(4)';
NODE_NAME     U25 BJ21
 '@T6G_MB_LIB.T6G(SCH_1):PAGE18_I159@PURE_QUANTA.GENOA_SP5(CHIPS)':
 'MIB_CA4': CDS_PINID='MIB_CA4';
NODE_NAME     J18 80
 '@T6G_MB_LIB.T6G(SCH_1):PAGE93_I22@PURE_QUANTA.SCONN288_DDR506112002KQ(CHIPS)':
 'CA4_B': CDS_PINID='CA4_B';
NET_NAME
'M_I_CPU0_SB_CA<5>'
 '@T6G_MB_LIB.T6G(SCH_1):M_I_CPU0_SB_CA'<5>:
 C_SIGNAL='@t6g_mb_lib.t6g(sch_1):m_i_cpu0_sb_ca(5)';
NODE_NAME     U25 BK21
 '@T6G_MB_LIB.T6G(SCH_1):PAGE18_I159@PURE_QUANTA.GENOA_SP5(CHIPS)':
 'MIB_CA5': CDS_PINID='MIB_CA5';
NODE_NAME     J18 225
 '@T6G_MB_LIB.T6G(SCH_1):PAGE93_I22@PURE_QUANTA.SCONN288_DDR506112002KQ(CHIPS)':
 'CA5_B': CDS_PINID='CA5_B';
NET_NAME
'M_I_CPU0_SB_CA<6>'
 '@T6G_MB_LIB.T6G(SCH_1):M_I_CPU0_SB_CA'<6>:
 C_SIGNAL='@t6g_mb_lib.t6g(sch_1):m_i_cpu0_sb_ca(6)';
NODE_NAME     U25 BK20
 '@T6G_MB_LIB.T6G(SCH_1):PAGE18_I159@PURE_QUANTA.GENOA_SP5(CHIPS)':
 'MIB_CA6': CDS_PINID='MIB_CA6';
NODE_NAME     J18 82
 '@T6G_MB_LIB.T6G(SCH_1):PAGE93_I22@PURE_QUANTA.SCONN288_DDR506112002KQ(CHIPS)':
 'CA6_B': CDS_PINID='CA6_B';
NET_NAME
'M_I_CPU0_SB_CB<0>'
 '@T6G_MB_LIB.T6G(SCH_1):M_I_CPU0_SB_CB'<0>:
 C_SIGNAL='@t6g_mb_lib.t6g(sch_1):m_i_cpu0_sb_cb(0)';
NODE_NAME     U25 BY20
 '@T6G_MB_LIB.T6G(SCH_1):PAGE18_I159@PURE_QUANTA.GENOA_SP5(CHIPS)':
 'MIB_CHECK0': CDS_PINID='MIB_CHECK0';
NODE_NAME     J18 96
 '@T6G_MB_LIB.T6G(SCH_1):PAGE93_I22@PURE_QUANTA.SCONN288_DDR506112002KQ(CHIPS)':
 'CB0_B': CDS_PINID='CB0_B';
NET_NAME
'M_I_CPU0_SB_CB<1>'
 '@T6G_MB_LIB.T6G(SCH_1):M_I_CPU0_SB_CB'<1>:
 C_SIGNAL='@t6g_mb_lib.t6g(sch_1):m_i_cpu0_sb_cb(1)';
NODE_NAME     U25 CA21
 '@T6G_MB_LIB.T6G(SCH_1):PAGE18_I159@PURE_QUANTA.GENOA_SP5(CHIPS)':
 'MIB_CHECK1': CDS_PINID='MIB_CHECK1';
NODE_NAME     J18 98
 '@T6G_MB_LIB.T6G(SCH_1):PAGE93_I22@PURE_QUANTA.SCONN288_DDR506112002KQ(CHIPS)':
 'CB1_B': CDS_PINID='CB1_B';
NET_NAME
'M_I_CPU0_SB_CB<2>'
 '@T6G_MB_LIB.T6G(SCH_1):M_I_CPU0_SB_CB'<2>:
 C_SIGNAL='@t6g_mb_lib.t6g(sch_1):m_i_cpu0_sb_cb(2)';
NODE_NAME     U25 CA19
 '@T6G_MB_LIB.T6G(SCH_1):PAGE18_I159@PURE_QUANTA.GENOA_SP5(CHIPS)':
 'MIB_CHECK2': CDS_PINID='MIB_CHECK2';
NODE_NAME     J18 241
 '@T6G_MB_LIB.T6G(SCH_1):PAGE93_I22@PURE_QUANTA.SCONN288_DDR506112002KQ(CHIPS)':
 'CB2_B': CDS_PINID='CB2_B';
NET_NAME
'M_I_CPU0_SB_CB<3>'
 '@T6G_MB_LIB.T6G(SCH_1):M_I_CPU0_SB_CB'<3>:
 C_SIGNAL='@t6g_mb_lib.t6g(sch_1):m_i_cpu0_sb_cb(3)';
NODE_NAME     U25 CB21
 '@T6G_MB_LIB.T6G(SCH_1):PAGE18_I159@PURE_QUANTA.GENOA_SP5(CHIPS)':
 'MIB_CHECK3': CDS_PINID='MIB_CHECK3';
NODE_NAME     J18 243
 '@T6G_MB_LIB.T6G(SCH_1):PAGE93_I22@PURE_QUANTA.SCONN288_DDR506112002KQ(CHIPS)':
 'CB3_B': CDS_PINID='CB3_B';
NET_NAME
'M_I_CPU0_SB_CB<4>'
 '@T6G_MB_LIB.T6G(SCH_1):M_I_CPU0_SB_CB'<4>:
 C_SIGNAL='@t6g_mb_lib.t6g(sch_1):m_i_cpu0_sb_cb(4)';
NODE_NAME     U25 BT20
 '@T6G_MB_LIB.T6G(SCH_1):PAGE18_I159@PURE_QUANTA.GENOA_SP5(CHIPS)':
 'MIB_CHECK4': CDS_PINID='MIB_CHECK4';
NODE_NAME     J18 89
 '@T6G_MB_LIB.T6G(SCH_1):PAGE93_I22@PURE_QUANTA.SCONN288_DDR506112002KQ(CHIPS)':
 'CB4_B': CDS_PINID='CB4_B';
NET_NAME
'M_I_CPU0_SB_CB<5>'
 '@T6G_MB_LIB.T6G(SCH_1):M_I_CPU0_SB_CB'<5>:
 C_SIGNAL='@t6g_mb_lib.t6g(sch_1):m_i_cpu0_sb_cb(5)';
NODE_NAME     U25 BU21
 '@T6G_MB_LIB.T6G(SCH_1):PAGE18_I159@PURE_QUANTA.GENOA_SP5(CHIPS)':
 'MIB_CHECK5': CDS_PINID='MIB_CHECK5';
NODE_NAME     J18 91
 '@T6G_MB_LIB.T6G(SCH_1):PAGE93_I22@PURE_QUANTA.SCONN288_DDR506112002KQ(CHIPS)':
 'CB5_B': CDS_PINID='CB5_B';
NET_NAME
'M_I_CPU0_SB_CB<6>'
 '@T6G_MB_LIB.T6G(SCH_1):M_I_CPU0_SB_CB'<6>:
 C_SIGNAL='@t6g_mb_lib.t6g(sch_1):m_i_cpu0_sb_cb(6)';
NODE_NAME     U25 BU19
 '@T6G_MB_LIB.T6G(SCH_1):PAGE18_I159@PURE_QUANTA.GENOA_SP5(CHIPS)':
 'MIB_CHECK6': CDS_PINID='MIB_CHECK6';
NODE_NAME     J18 234
 '@T6G_MB_LIB.T6G(SCH_1):PAGE93_I22@PURE_QUANTA.SCONN288_DDR506112002KQ(CHIPS)':
 'CB6_B': CDS_PINID='CB6_B';
NET_NAME
'M_I_CPU0_SB_CB<7>'
 '@T6G_MB_LIB.T6G(SCH_1):M_I_CPU0_SB_CB'<7>:
 C_SIGNAL='@t6g_mb_lib.t6g(sch_1):m_i_cpu0_sb_cb(7)';
NODE_NAME     U25 BV21
 '@T6G_MB_LIB.T6G(SCH_1):PAGE18_I159@PURE_QUANTA.GENOA_SP5(CHIPS)':
 'MIB_CHECK7': CDS_PINID='MIB_CHECK7';
NODE_NAME     J18 236
 '@T6G_MB_LIB.T6G(SCH_1):PAGE93_I22@PURE_QUANTA.SCONN288_DDR506112002KQ(CHIPS)':
 'CB7_B': CDS_PINID='CB7_B';
NET_NAME
'M_I_CPU0_SB_CS_N<0>'
 '@T6G_MB_LIB.T6G(SCH_1):M_I_CPU0_SB_CS_N'<0>:
 C_SIGNAL='@t6g_mb_lib.t6g(sch_1):m_i_cpu0_sb_cs_n(0)';
NODE_NAME     U25 BM21
 '@T6G_MB_LIB.T6G(SCH_1):PAGE18_I159@PURE_QUANTA.GENOA_SP5(CHIPS)':
 'MIB0_CS_L0': CDS_PINID='MIB0_CS_L0';
NODE_NAME     J18 84
 '@T6G_MB_LIB.T6G(SCH_1):PAGE93_I22@PURE_QUANTA.SCONN288_DDR506112002KQ(CHIPS)':
 'CS0_B_N': CDS_PINID='CS0_B_N';
NET_NAME
'M_I_CPU0_SB_CS_N<1>'
 '@T6G_MB_LIB.T6G(SCH_1):M_I_CPU0_SB_CS_N'<1>:
 C_SIGNAL='@t6g_mb_lib.t6g(sch_1):m_i_cpu0_sb_cs_n(1)';
NODE_NAME     U25 BN19
 '@T6G_MB_LIB.T6G(SCH_1):PAGE18_I159@PURE_QUANTA.GENOA_SP5(CHIPS)':
 'MIB0_CS_L1': CDS_PINID='MIB0_CS_L1';
NODE_NAME     J18 229
 '@T6G_MB_LIB.T6G(SCH_1):PAGE93_I22@PURE_QUANTA.SCONN288_DDR506112002KQ(CHIPS)':
 'CS1_B_N': CDS_PINID='CS1_B_N';
NET_NAME
'M_I_CPU0_SB_DQ<0>'
 '@T6G_MB_LIB.T6G(SCH_1):M_I_CPU0_SB_DQ'<0>:
 C_SIGNAL='@t6g_mb_lib.t6g(sch_1):m_i_cpu0_sb_dq(0)';
NODE_NAME     U25 CB20
 '@T6G_MB_LIB.T6G(SCH_1):PAGE18_I159@PURE_QUANTA.GENOA_SP5(CHIPS)':
 'MIB_DATA0': CDS_PINID='MIB_DATA0';
NODE_NAME     J18 100
 '@T6G_MB_LIB.T6G(SCH_1):PAGE93_I22@PURE_QUANTA.SCONN288_DDR506112002KQ(CHIPS)':
 'DQ0_B': CDS_PINID='DQ0_B';
NET_NAME
'M_I_CPU0_SB_DQ<10>'
 '@T6G_MB_LIB.T6G(SCH_1):M_I_CPU0_SB_DQ'<10>:
 C_SIGNAL='@t6g_mb_lib.t6g(sch_1):m_i_cpu0_sb_dq(10)';
NODE_NAME     U25 CJ19
 '@T6G_MB_LIB.T6G(SCH_1):PAGE18_I159@PURE_QUANTA.GENOA_SP5(CHIPS)':
 'MIB_DATA10': CDS_PINID='MIB_DATA10';
NODE_NAME     J18 256
 '@T6G_MB_LIB.T6G(SCH_1):PAGE93_I22@PURE_QUANTA.SCONN288_DDR506112002KQ(CHIPS)':
 'DQ10_B': CDS_PINID='DQ10_B';
NET_NAME
'M_I_CPU0_SB_DQ<11>'
 '@T6G_MB_LIB.T6G(SCH_1):M_I_CPU0_SB_DQ'<11>:
 C_SIGNAL='@t6g_mb_lib.t6g(sch_1):m_i_cpu0_sb_dq(11)';
NODE_NAME     U25 CK21
 '@T6G_MB_LIB.T6G(SCH_1):PAGE18_I159@PURE_QUANTA.GENOA_SP5(CHIPS)':
 'MIB_DATA11': CDS_PINID='MIB_DATA11';
NODE_NAME     J18 258
 '@T6G_MB_LIB.T6G(SCH_1):PAGE93_I22@PURE_QUANTA.SCONN288_DDR506112002KQ(CHIPS)':
 'DQ11_B': CDS_PINID='DQ11_B';
NET_NAME
'M_I_CPU0_SB_DQ<12>'
 '@T6G_MB_LIB.T6G(SCH_1):M_I_CPU0_SB_DQ'<12>:
 C_SIGNAL='@t6g_mb_lib.t6g(sch_1):m_i_cpu0_sb_dq(12)';
NODE_NAME     U25 CM20
 '@T6G_MB_LIB.T6G(SCH_1):PAGE18_I159@PURE_QUANTA.GENOA_SP5(CHIPS)':
 'MIB_DATA12': CDS_PINID='MIB_DATA12';
NODE_NAME     J18 118
 '@T6G_MB_LIB.T6G(SCH_1):PAGE93_I22@PURE_QUANTA.SCONN288_DDR506112002KQ(CHIPS)':
 'DQ12_B': CDS_PINID='DQ12_B';
NET_NAME
'M_I_CPU0_SB_DQ<13>'
 '@T6G_MB_LIB.T6G(SCH_1):M_I_CPU0_SB_DQ'<13>:
 C_SIGNAL='@t6g_mb_lib.t6g(sch_1):m_i_cpu0_sb_dq(13)';
NODE_NAME     U25 CN21
 '@T6G_MB_LIB.T6G(SCH_1):PAGE18_I159@PURE_QUANTA.GENOA_SP5(CHIPS)':
 'MIB_DATA13': CDS_PINID='MIB_DATA13';
NODE_NAME     J18 120
 '@T6G_MB_LIB.T6G(SCH_1):PAGE93_I22@PURE_QUANTA.SCONN288_DDR506112002KQ(CHIPS)':
 'DQ13_B': CDS_PINID='DQ13_B';
NET_NAME
'M_I_CPU0_SB_DQ<14>'
 '@T6G_MB_LIB.T6G(SCH_1):M_I_CPU0_SB_DQ'<14>:
 C_SIGNAL='@t6g_mb_lib.t6g(sch_1):m_i_cpu0_sb_dq(14)';
NODE_NAME     U25 CN19
 '@T6G_MB_LIB.T6G(SCH_1):PAGE18_I159@PURE_QUANTA.GENOA_SP5(CHIPS)':
 'MIB_DATA14': CDS_PINID='MIB_DATA14';
NODE_NAME     J18 263
 '@T6G_MB_LIB.T6G(SCH_1):PAGE93_I22@PURE_QUANTA.SCONN288_DDR506112002KQ(CHIPS)':
 'DQ14_B': CDS_PINID='DQ14_B';
NET_NAME
'M_I_CPU0_SB_DQ<15>'
 '@T6G_MB_LIB.T6G(SCH_1):M_I_CPU0_SB_DQ'<15>:
 C_SIGNAL='@t6g_mb_lib.t6g(sch_1):m_i_cpu0_sb_dq(15)';
NODE_NAME     U25 CP21
 '@T6G_MB_LIB.T6G(SCH_1):PAGE18_I159@PURE_QUANTA.GENOA_SP5(CHIPS)':
 'MIB_DATA15': CDS_PINID='MIB_DATA15';
NODE_NAME     J18 265
 '@T6G_MB_LIB.T6G(SCH_1):PAGE93_I22@PURE_QUANTA.SCONN288_DDR506112002KQ(CHIPS)':
 'DQ15_B': CDS_PINID='DQ15_B';
NET_NAME
'M_I_CPU0_SB_DQ<16>'
 '@T6G_MB_LIB.T6G(SCH_1):M_I_CPU0_SB_DQ'<16>:
 C_SIGNAL='@t6g_mb_lib.t6g(sch_1):m_i_cpu0_sb_dq(16)';
NODE_NAME     U25 CP20
 '@T6G_MB_LIB.T6G(SCH_1):PAGE18_I159@PURE_QUANTA.GENOA_SP5(CHIPS)':
 'MIB_DATA16': CDS_PINID='MIB_DATA16';
NODE_NAME     J18 122
 '@T6G_MB_LIB.T6G(SCH_1):PAGE93_I22@PURE_QUANTA.SCONN288_DDR506112002KQ(CHIPS)':
 'DQ16_B': CDS_PINID='DQ16_B';
NET_NAME
'M_I_CPU0_SB_DQ<17>'
 '@T6G_MB_LIB.T6G(SCH_1):M_I_CPU0_SB_DQ'<17>:
 C_SIGNAL='@t6g_mb_lib.t6g(sch_1):m_i_cpu0_sb_dq(17)';
NODE_NAME     U25 CR21
 '@T6G_MB_LIB.T6G(SCH_1):PAGE18_I159@PURE_QUANTA.GENOA_SP5(CHIPS)':
 'MIB_DATA17': CDS_PINID='MIB_DATA17';
NODE_NAME     J18 124
 '@T6G_MB_LIB.T6G(SCH_1):PAGE93_I22@PURE_QUANTA.SCONN288_DDR506112002KQ(CHIPS)':
 'DQ17_B': CDS_PINID='DQ17_B';
NET_NAME
'M_I_CPU0_SB_DQ<18>'
 '@T6G_MB_LIB.T6G(SCH_1):M_I_CPU0_SB_DQ'<18>:
 C_SIGNAL='@t6g_mb_lib.t6g(sch_1):m_i_cpu0_sb_dq(18)';
NODE_NAME     U25 CR19
 '@T6G_MB_LIB.T6G(SCH_1):PAGE18_I159@PURE_QUANTA.GENOA_SP5(CHIPS)':
 'MIB_DATA18': CDS_PINID='MIB_DATA18';
NODE_NAME     J18 267
 '@T6G_MB_LIB.T6G(SCH_1):PAGE93_I22@PURE_QUANTA.SCONN288_DDR506112002KQ(CHIPS)':
 'DQ18_B': CDS_PINID='DQ18_B';
NET_NAME
'M_I_CPU0_SB_DQ<19>'
 '@T6G_MB_LIB.T6G(SCH_1):M_I_CPU0_SB_DQ'<19>:
 C_SIGNAL='@t6g_mb_lib.t6g(sch_1):m_i_cpu0_sb_dq(19)';
NODE_NAME     U25 CT21
 '@T6G_MB_LIB.T6G(SCH_1):PAGE18_I159@PURE_QUANTA.GENOA_SP5(CHIPS)':
 'MIB_DATA19': CDS_PINID='MIB_DATA19';
NODE_NAME     J18 269
 '@T6G_MB_LIB.T6G(SCH_1):PAGE93_I22@PURE_QUANTA.SCONN288_DDR506112002KQ(CHIPS)':
 'DQ19_B': CDS_PINID='DQ19_B';
NET_NAME
'M_I_CPU0_SB_DQ<1>'
 '@T6G_MB_LIB.T6G(SCH_1):M_I_CPU0_SB_DQ'<1>:
 C_SIGNAL='@t6g_mb_lib.t6g(sch_1):m_i_cpu0_sb_dq(1)';
NODE_NAME     U25 CC21
 '@T6G_MB_LIB.T6G(SCH_1):PAGE18_I159@PURE_QUANTA.GENOA_SP5(CHIPS)':
 'MIB_DATA1': CDS_PINID='MIB_DATA1';
NODE_NAME     J18 102
 '@T6G_MB_LIB.T6G(SCH_1):PAGE93_I22@PURE_QUANTA.SCONN288_DDR506112002KQ(CHIPS)':
 'DQ1_B': CDS_PINID='DQ1_B';
NET_NAME
'M_I_CPU0_SB_DQ<20>'
 '@T6G_MB_LIB.T6G(SCH_1):M_I_CPU0_SB_DQ'<20>:
 C_SIGNAL='@t6g_mb_lib.t6g(sch_1):m_i_cpu0_sb_dq(20)';
NODE_NAME     U25 CV20
 '@T6G_MB_LIB.T6G(SCH_1):PAGE18_I159@PURE_QUANTA.GENOA_SP5(CHIPS)':
 'MIB_DATA20': CDS_PINID='MIB_DATA20';
NODE_NAME     J18 129
 '@T6G_MB_LIB.T6G(SCH_1):PAGE93_I22@PURE_QUANTA.SCONN288_DDR506112002KQ(CHIPS)':
 'DQ20_B': CDS_PINID='DQ20_B';
NET_NAME
'M_I_CPU0_SB_DQ<21>'
 '@T6G_MB_LIB.T6G(SCH_1):M_I_CPU0_SB_DQ'<21>:
 C_SIGNAL='@t6g_mb_lib.t6g(sch_1):m_i_cpu0_sb_dq(21)';
NODE_NAME     U25 CW21
 '@T6G_MB_LIB.T6G(SCH_1):PAGE18_I159@PURE_QUANTA.GENOA_SP5(CHIPS)':
 'MIB_DATA21': CDS_PINID='MIB_DATA21';
NODE_NAME     J18 131
 '@T6G_MB_LIB.T6G(SCH_1):PAGE93_I22@PURE_QUANTA.SCONN288_DDR506112002KQ(CHIPS)':
 'DQ21_B': CDS_PINID='DQ21_B';
NET_NAME
'M_I_CPU0_SB_DQ<22>'
 '@T6G_MB_LIB.T6G(SCH_1):M_I_CPU0_SB_DQ'<22>:
 C_SIGNAL='@t6g_mb_lib.t6g(sch_1):m_i_cpu0_sb_dq(22)';
NODE_NAME     U25 CW19
 '@T6G_MB_LIB.T6G(SCH_1):PAGE18_I159@PURE_QUANTA.GENOA_SP5(CHIPS)':
 'MIB_DATA22': CDS_PINID='MIB_DATA22';
NODE_NAME     J18 274
 '@T6G_MB_LIB.T6G(SCH_1):PAGE93_I22@PURE_QUANTA.SCONN288_DDR506112002KQ(CHIPS)':
 'DQ22_B': CDS_PINID='DQ22_B';
NET_NAME
'M_I_CPU0_SB_DQ<23>'
 '@T6G_MB_LIB.T6G(SCH_1):M_I_CPU0_SB_DQ'<23>:
 C_SIGNAL='@t6g_mb_lib.t6g(sch_1):m_i_cpu0_sb_dq(23)';
NODE_NAME     U25 CY21
 '@T6G_MB_LIB.T6G(SCH_1):PAGE18_I159@PURE_QUANTA.GENOA_SP5(CHIPS)':
 'MIB_DATA23': CDS_PINID='MIB_DATA23';
NODE_NAME     J18 276
 '@T6G_MB_LIB.T6G(SCH_1):PAGE93_I22@PURE_QUANTA.SCONN288_DDR506112002KQ(CHIPS)':
 'DQ23_B': CDS_PINID='DQ23_B';
NET_NAME
'M_I_CPU0_SB_DQ<24>'
 '@T6G_MB_LIB.T6G(SCH_1):M_I_CPU0_SB_DQ'<24>:
 C_SIGNAL='@t6g_mb_lib.t6g(sch_1):m_i_cpu0_sb_dq(24)';
NODE_NAME     U25 CY20
 '@T6G_MB_LIB.T6G(SCH_1):PAGE18_I159@PURE_QUANTA.GENOA_SP5(CHIPS)':
 'MIB_DATA24': CDS_PINID='MIB_DATA24';
NODE_NAME     J18 133
 '@T6G_MB_LIB.T6G(SCH_1):PAGE93_I22@PURE_QUANTA.SCONN288_DDR506112002KQ(CHIPS)':
 'DQ24_B': CDS_PINID='DQ24_B';
NET_NAME
'M_I_CPU0_SB_DQ<25>'
 '@T6G_MB_LIB.T6G(SCH_1):M_I_CPU0_SB_DQ'<25>:
 C_SIGNAL='@t6g_mb_lib.t6g(sch_1):m_i_cpu0_sb_dq(25)';
NODE_NAME     U25 DA21
 '@T6G_MB_LIB.T6G(SCH_1):PAGE18_I159@PURE_QUANTA.GENOA_SP5(CHIPS)':
 'MIB_DATA25': CDS_PINID='MIB_DATA25';
NODE_NAME     J18 135
 '@T6G_MB_LIB.T6G(SCH_1):PAGE93_I22@PURE_QUANTA.SCONN288_DDR506112002KQ(CHIPS)':
 'DQ25_B': CDS_PINID='DQ25_B';
NET_NAME
'M_I_CPU0_SB_DQ<26>'
 '@T6G_MB_LIB.T6G(SCH_1):M_I_CPU0_SB_DQ'<26>:
 C_SIGNAL='@t6g_mb_lib.t6g(sch_1):m_i_cpu0_sb_dq(26)';
NODE_NAME     U25 DA19
 '@T6G_MB_LIB.T6G(SCH_1):PAGE18_I159@PURE_QUANTA.GENOA_SP5(CHIPS)':
 'MIB_DATA26': CDS_PINID='MIB_DATA26';
NODE_NAME     J18 278
 '@T6G_MB_LIB.T6G(SCH_1):PAGE93_I22@PURE_QUANTA.SCONN288_DDR506112002KQ(CHIPS)':
 'DQ26_B': CDS_PINID='DQ26_B';
NET_NAME
'M_I_CPU0_SB_DQ<27>'
 '@T6G_MB_LIB.T6G(SCH_1):M_I_CPU0_SB_DQ'<27>:
 C_SIGNAL='@t6g_mb_lib.t6g(sch_1):m_i_cpu0_sb_dq(27)';
NODE_NAME     U25 DB21
 '@T6G_MB_LIB.T6G(SCH_1):PAGE18_I159@PURE_QUANTA.GENOA_SP5(CHIPS)':
 'MIB_DATA27': CDS_PINID='MIB_DATA27';
NODE_NAME     J18 280
 '@T6G_MB_LIB.T6G(SCH_1):PAGE93_I22@PURE_QUANTA.SCONN288_DDR506112002KQ(CHIPS)':
 'DQ27_B': CDS_PINID='DQ27_B';
NET_NAME
'M_I_CPU0_SB_DQ<28>'
 '@T6G_MB_LIB.T6G(SCH_1):M_I_CPU0_SB_DQ'<28>:
 C_SIGNAL='@t6g_mb_lib.t6g(sch_1):m_i_cpu0_sb_dq(28)';
NODE_NAME     U25 DD20
 '@T6G_MB_LIB.T6G(SCH_1):PAGE18_I159@PURE_QUANTA.GENOA_SP5(CHIPS)':
 'MIB_DATA28': CDS_PINID='MIB_DATA28';
NODE_NAME     J18 140
 '@T6G_MB_LIB.T6G(SCH_1):PAGE93_I22@PURE_QUANTA.SCONN288_DDR506112002KQ(CHIPS)':
 'DQ28_B': CDS_PINID='DQ28_B';
NET_NAME
'M_I_CPU0_SB_DQ<29>'
 '@T6G_MB_LIB.T6G(SCH_1):M_I_CPU0_SB_DQ'<29>:
 C_SIGNAL='@t6g_mb_lib.t6g(sch_1):m_i_cpu0_sb_dq(29)';
NODE_NAME     U25 DE21
 '@T6G_MB_LIB.T6G(SCH_1):PAGE18_I159@PURE_QUANTA.GENOA_SP5(CHIPS)':
 'MIB_DATA29': CDS_PINID='MIB_DATA29';
NODE_NAME     J18 142
 '@T6G_MB_LIB.T6G(SCH_1):PAGE93_I22@PURE_QUANTA.SCONN288_DDR506112002KQ(CHIPS)':
 'DQ29_B': CDS_PINID='DQ29_B';
NET_NAME
'M_I_CPU0_SB_DQ<2>'
 '@T6G_MB_LIB.T6G(SCH_1):M_I_CPU0_SB_DQ'<2>:
 C_SIGNAL='@t6g_mb_lib.t6g(sch_1):m_i_cpu0_sb_dq(2)';
NODE_NAME     U25 CC19
 '@T6G_MB_LIB.T6G(SCH_1):PAGE18_I159@PURE_QUANTA.GENOA_SP5(CHIPS)':
 'MIB_DATA2': CDS_PINID='MIB_DATA2';
NODE_NAME     J18 245
 '@T6G_MB_LIB.T6G(SCH_1):PAGE93_I22@PURE_QUANTA.SCONN288_DDR506112002KQ(CHIPS)':
 'DQ2_B': CDS_PINID='DQ2_B';
NET_NAME
'M_I_CPU0_SB_DQ<30>'
 '@T6G_MB_LIB.T6G(SCH_1):M_I_CPU0_SB_DQ'<30>:
 C_SIGNAL='@t6g_mb_lib.t6g(sch_1):m_i_cpu0_sb_dq(30)';
NODE_NAME     U25 DE19
 '@T6G_MB_LIB.T6G(SCH_1):PAGE18_I159@PURE_QUANTA.GENOA_SP5(CHIPS)':
 'MIB_DATA30': CDS_PINID='MIB_DATA30';
NODE_NAME     J18 285
 '@T6G_MB_LIB.T6G(SCH_1):PAGE93_I22@PURE_QUANTA.SCONN288_DDR506112002KQ(CHIPS)':
 'DQ30_B': CDS_PINID='DQ30_B';
NET_NAME
'M_I_CPU0_SB_DQ<31>'
 '@T6G_MB_LIB.T6G(SCH_1):M_I_CPU0_SB_DQ'<31>:
 C_SIGNAL='@t6g_mb_lib.t6g(sch_1):m_i_cpu0_sb_dq(31)';
NODE_NAME     U25 DF21
 '@T6G_MB_LIB.T6G(SCH_1):PAGE18_I159@PURE_QUANTA.GENOA_SP5(CHIPS)':
 'MIB_DATA31': CDS_PINID='MIB_DATA31';
NODE_NAME     J18 287
 '@T6G_MB_LIB.T6G(SCH_1):PAGE93_I22@PURE_QUANTA.SCONN288_DDR506112002KQ(CHIPS)':
 'DQ31_B': CDS_PINID='DQ31_B';
NET_NAME
'M_I_CPU0_SB_DQ<3>'
 '@T6G_MB_LIB.T6G(SCH_1):M_I_CPU0_SB_DQ'<3>:
 C_SIGNAL='@t6g_mb_lib.t6g(sch_1):m_i_cpu0_sb_dq(3)';
NODE_NAME     U25 CD21
 '@T6G_MB_LIB.T6G(SCH_1):PAGE18_I159@PURE_QUANTA.GENOA_SP5(CHIPS)':
 'MIB_DATA3': CDS_PINID='MIB_DATA3';
NODE_NAME     J18 247
 '@T6G_MB_LIB.T6G(SCH_1):PAGE93_I22@PURE_QUANTA.SCONN288_DDR506112002KQ(CHIPS)':
 'DQ3_B': CDS_PINID='DQ3_B';
NET_NAME
'M_I_CPU0_SB_DQ<4>'
 '@T6G_MB_LIB.T6G(SCH_1):M_I_CPU0_SB_DQ'<4>:
 C_SIGNAL='@t6g_mb_lib.t6g(sch_1):m_i_cpu0_sb_dq(4)';
NODE_NAME     U25 CF20
 '@T6G_MB_LIB.T6G(SCH_1):PAGE18_I159@PURE_QUANTA.GENOA_SP5(CHIPS)':
 'MIB_DATA4': CDS_PINID='MIB_DATA4';
NODE_NAME     J18 107
 '@T6G_MB_LIB.T6G(SCH_1):PAGE93_I22@PURE_QUANTA.SCONN288_DDR506112002KQ(CHIPS)':
 'DQ4_B': CDS_PINID='DQ4_B';
NET_NAME
'M_I_CPU0_SB_DQ<5>'
 '@T6G_MB_LIB.T6G(SCH_1):M_I_CPU0_SB_DQ'<5>:
 C_SIGNAL='@t6g_mb_lib.t6g(sch_1):m_i_cpu0_sb_dq(5)';
NODE_NAME     U25 CG21
 '@T6G_MB_LIB.T6G(SCH_1):PAGE18_I159@PURE_QUANTA.GENOA_SP5(CHIPS)':
 'MIB_DATA5': CDS_PINID='MIB_DATA5';
NODE_NAME     J18 109
 '@T6G_MB_LIB.T6G(SCH_1):PAGE93_I22@PURE_QUANTA.SCONN288_DDR506112002KQ(CHIPS)':
 'DQ5_B': CDS_PINID='DQ5_B';
NET_NAME
'M_I_CPU0_SB_DQ<6>'
 '@T6G_MB_LIB.T6G(SCH_1):M_I_CPU0_SB_DQ'<6>:
 C_SIGNAL='@t6g_mb_lib.t6g(sch_1):m_i_cpu0_sb_dq(6)';
NODE_NAME     U25 CG19
 '@T6G_MB_LIB.T6G(SCH_1):PAGE18_I159@PURE_QUANTA.GENOA_SP5(CHIPS)':
 'MIB_DATA6': CDS_PINID='MIB_DATA6';
NODE_NAME     J18 252
 '@T6G_MB_LIB.T6G(SCH_1):PAGE93_I22@PURE_QUANTA.SCONN288_DDR506112002KQ(CHIPS)':
 'DQ6_B': CDS_PINID='DQ6_B';
NET_NAME
'M_I_CPU0_SB_DQ<7>'
 '@T6G_MB_LIB.T6G(SCH_1):M_I_CPU0_SB_DQ'<7>:
 C_SIGNAL='@t6g_mb_lib.t6g(sch_1):m_i_cpu0_sb_dq(7)';
NODE_NAME     U25 CH21
 '@T6G_MB_LIB.T6G(SCH_1):PAGE18_I159@PURE_QUANTA.GENOA_SP5(CHIPS)':
 'MIB_DATA7': CDS_PINID='MIB_DATA7';
NODE_NAME     J18 254
 '@T6G_MB_LIB.T6G(SCH_1):PAGE93_I22@PURE_QUANTA.SCONN288_DDR506112002KQ(CHIPS)':
 'DQ7_B': CDS_PINID='DQ7_B';
NET_NAME
'M_I_CPU0_SB_DQ<8>'
 '@T6G_MB_LIB.T6G(SCH_1):M_I_CPU0_SB_DQ'<8>:
 C_SIGNAL='@t6g_mb_lib.t6g(sch_1):m_i_cpu0_sb_dq(8)';
NODE_NAME     U25 CH20
 '@T6G_MB_LIB.T6G(SCH_1):PAGE18_I159@PURE_QUANTA.GENOA_SP5(CHIPS)':
 'MIB_DATA8': CDS_PINID='MIB_DATA8';
NODE_NAME     J18 111
 '@T6G_MB_LIB.T6G(SCH_1):PAGE93_I22@PURE_QUANTA.SCONN288_DDR506112002KQ(CHIPS)':
 'DQ8_B': CDS_PINID='DQ8_B';
NET_NAME
'M_I_CPU0_SB_DQ<9>'
 '@T6G_MB_LIB.T6G(SCH_1):M_I_CPU0_SB_DQ'<9>:
 C_SIGNAL='@t6g_mb_lib.t6g(sch_1):m_i_cpu0_sb_dq(9)';
NODE_NAME     U25 CJ21
 '@T6G_MB_LIB.T6G(SCH_1):PAGE18_I159@PURE_QUANTA.GENOA_SP5(CHIPS)':
 'MIB_DATA9': CDS_PINID='MIB_DATA9';
NODE_NAME     J18 113
 '@T6G_MB_LIB.T6G(SCH_1):PAGE93_I22@PURE_QUANTA.SCONN288_DDR506112002KQ(CHIPS)':
 'DQ9_B': CDS_PINID='DQ9_B';
NET_NAME
'M_I_CPU0_SB_DQS_DN<0>'
 '@T6G_MB_LIB.T6G(SCH_1):M_I_CPU0_SB_DQS_DN'<0>:
 C_SIGNAL='@t6g_mb_lib.t6g(sch_1):m_i_cpu0_sb_dqs_dn(0)';
NODE_NAME     U25 CE19
 '@T6G_MB_LIB.T6G(SCH_1):PAGE18_I159@PURE_QUANTA.GENOA_SP5(CHIPS)':
 'MIB_DQS_L0': CDS_PINID='MIB_DQS_L0';
NODE_NAME     J18 105
 '@T6G_MB_LIB.T6G(SCH_1):PAGE93_I236@PURE_QUANTA.SCONN288_DDR506112002KQ(CHIPS)':
 'DQS0_B_C': CDS_PINID='DQS0_B_C';
NET_NAME
'M_I_CPU0_SB_DQS_DN<1>'
 '@T6G_MB_LIB.T6G(SCH_1):M_I_CPU0_SB_DQS_DN'<1>:
 C_SIGNAL='@t6g_mb_lib.t6g(sch_1):m_i_cpu0_sb_dqs_dn(1)';
NODE_NAME     U25 CL19
 '@T6G_MB_LIB.T6G(SCH_1):PAGE18_I159@PURE_QUANTA.GENOA_SP5(CHIPS)':
 'MIB_DQS_L1': CDS_PINID='MIB_DQS_L1';
NODE_NAME     J18 116
 '@T6G_MB_LIB.T6G(SCH_1):PAGE93_I236@PURE_QUANTA.SCONN288_DDR506112002KQ(CHIPS)':
 'DQS1_B_C': CDS_PINID='DQS1_B_C';
NET_NAME
'M_I_CPU0_SB_DQS_DN<2>'
 '@T6G_MB_LIB.T6G(SCH_1):M_I_CPU0_SB_DQS_DN'<2>:
 C_SIGNAL='@t6g_mb_lib.t6g(sch_1):m_i_cpu0_sb_dqs_dn(2)';
NODE_NAME     U25 CU19
 '@T6G_MB_LIB.T6G(SCH_1):PAGE18_I159@PURE_QUANTA.GENOA_SP5(CHIPS)':
 'MIB_DQS_L2': CDS_PINID='MIB_DQS_L2';
NODE_NAME     J18 127
 '@T6G_MB_LIB.T6G(SCH_1):PAGE93_I236@PURE_QUANTA.SCONN288_DDR506112002KQ(CHIPS)':
 'DQS2_B_C': CDS_PINID='DQS2_B_C';
NET_NAME
'M_I_CPU0_SB_DQS_DN<3>'
 '@T6G_MB_LIB.T6G(SCH_1):M_I_CPU0_SB_DQS_DN'<3>:
 C_SIGNAL='@t6g_mb_lib.t6g(sch_1):m_i_cpu0_sb_dqs_dn(3)';
NODE_NAME     U25 DC19
 '@T6G_MB_LIB.T6G(SCH_1):PAGE18_I159@PURE_QUANTA.GENOA_SP5(CHIPS)':
 'MIB_DQS_L3': CDS_PINID='MIB_DQS_L3';
NODE_NAME     J18 138
 '@T6G_MB_LIB.T6G(SCH_1):PAGE93_I236@PURE_QUANTA.SCONN288_DDR506112002KQ(CHIPS)':
 'DQS3_B_C': CDS_PINID='DQS3_B_C';
NET_NAME
'M_I_CPU0_SB_DQS_DN<4>'
 '@T6G_MB_LIB.T6G(SCH_1):M_I_CPU0_SB_DQS_DN'<4>:
 C_SIGNAL='@t6g_mb_lib.t6g(sch_1):m_i_cpu0_sb_dqs_dn(4)';
NODE_NAME     U25 BW21
 '@T6G_MB_LIB.T6G(SCH_1):PAGE18_I159@PURE_QUANTA.GENOA_SP5(CHIPS)':
 'MIB_DQS_L4': CDS_PINID='MIB_DQS_L4';
NODE_NAME     J18 238
 '@T6G_MB_LIB.T6G(SCH_1):PAGE93_I236@PURE_QUANTA.SCONN288_DDR506112002KQ(CHIPS)':
 'DQS4_B_C': CDS_PINID='DQS4_B_C';
NET_NAME
'M_I_CPU0_SB_DQS_DN<5>'
 '@T6G_MB_LIB.T6G(SCH_1):M_I_CPU0_SB_DQS_DN'<5>:
 C_SIGNAL='@t6g_mb_lib.t6g(sch_1):m_i_cpu0_sb_dqs_dn(5)';
NODE_NAME     U25 CE21
 '@T6G_MB_LIB.T6G(SCH_1):PAGE18_I159@PURE_QUANTA.GENOA_SP5(CHIPS)':
 'MIB_DQS_L5': CDS_PINID='MIB_DQS_L5';
NODE_NAME     J18 249
 '@T6G_MB_LIB.T6G(SCH_1):PAGE93_I236@PURE_QUANTA.SCONN288_DDR506112002KQ(CHIPS)':
 'DQS5_B_C||TDQS5_B_C': CDS_PINID='\dqs5_b_c||tdqs5_b_c\';
NET_NAME
'M_I_CPU0_SB_DQS_DN<6>'
 '@T6G_MB_LIB.T6G(SCH_1):M_I_CPU0_SB_DQS_DN'<6>:
 C_SIGNAL='@t6g_mb_lib.t6g(sch_1):m_i_cpu0_sb_dqs_dn(6)';
NODE_NAME     U25 CL21
 '@T6G_MB_LIB.T6G(SCH_1):PAGE18_I159@PURE_QUANTA.GENOA_SP5(CHIPS)':
 'MIB_DQS_L6': CDS_PINID='MIB_DQS_L6';
NODE_NAME     J18 260
 '@T6G_MB_LIB.T6G(SCH_1):PAGE93_I236@PURE_QUANTA.SCONN288_DDR506112002KQ(CHIPS)':
 'DQS6_B_C||TDQS6_B_C': CDS_PINID='\dqs6_b_c||tdqs6_b_c\';
NET_NAME
'M_I_CPU0_SB_DQS_DN<7>'
 '@T6G_MB_LIB.T6G(SCH_1):M_I_CPU0_SB_DQS_DN'<7>:
 C_SIGNAL='@t6g_mb_lib.t6g(sch_1):m_i_cpu0_sb_dqs_dn(7)';
NODE_NAME     U25 CU21
 '@T6G_MB_LIB.T6G(SCH_1):PAGE18_I159@PURE_QUANTA.GENOA_SP5(CHIPS)':
 'MIB_DQS_L7': CDS_PINID='MIB_DQS_L7';
NODE_NAME     J18 271
 '@T6G_MB_LIB.T6G(SCH_1):PAGE93_I236@PURE_QUANTA.SCONN288_DDR506112002KQ(CHIPS)':
 'DQS7_B_C||TDQS7_B_C': CDS_PINID='\dqs7_b_c||tdqs7_b_c\';
NET_NAME
'M_I_CPU0_SB_DQS_DN<8>'
 '@T6G_MB_LIB.T6G(SCH_1):M_I_CPU0_SB_DQS_DN'<8>:
 C_SIGNAL='@t6g_mb_lib.t6g(sch_1):m_i_cpu0_sb_dqs_dn(8)';
NODE_NAME     U25 DC21
 '@T6G_MB_LIB.T6G(SCH_1):PAGE18_I159@PURE_QUANTA.GENOA_SP5(CHIPS)':
 'MIB_DQS_L8': CDS_PINID='MIB_DQS_L8';
NODE_NAME     J18 282
 '@T6G_MB_LIB.T6G(SCH_1):PAGE93_I236@PURE_QUANTA.SCONN288_DDR506112002KQ(CHIPS)':
 'DQS8_B_C||TDQS8_B_C': CDS_PINID='\dqs8_b_c||tdqs8_b_c\';
NET_NAME
'M_I_CPU0_SB_DQS_DN<9>'
 '@T6G_MB_LIB.T6G(SCH_1):M_I_CPU0_SB_DQS_DN'<9>:
 C_SIGNAL='@t6g_mb_lib.t6g(sch_1):m_i_cpu0_sb_dqs_dn(9)';
NODE_NAME     U25 BW19
 '@T6G_MB_LIB.T6G(SCH_1):PAGE18_I159@PURE_QUANTA.GENOA_SP5(CHIPS)':
 'MIB_DQS_L9': CDS_PINID='MIB_DQS_L9';
NODE_NAME     J18 94
 '@T6G_MB_LIB.T6G(SCH_1):PAGE93_I236@PURE_QUANTA.SCONN288_DDR506112002KQ(CHIPS)':
 'DQS9_B_C||TDQS9_B_C': CDS_PINID='\dqs9_b_c||tdqs9_b_c\';
NET_NAME
'M_I_CPU0_SB_DQS_DP<0>'
 '@T6G_MB_LIB.T6G(SCH_1):M_I_CPU0_SB_DQS_DP'<0>:
 C_SIGNAL='@t6g_mb_lib.t6g(sch_1):m_i_cpu0_sb_dqs_dp(0)';
NODE_NAME     U25 CD20
 '@T6G_MB_LIB.T6G(SCH_1):PAGE18_I159@PURE_QUANTA.GENOA_SP5(CHIPS)':
 'MIB_DQS_H0': CDS_PINID='MIB_DQS_H0';
NODE_NAME     J18 104
 '@T6G_MB_LIB.T6G(SCH_1):PAGE93_I236@PURE_QUANTA.SCONN288_DDR506112002KQ(CHIPS)':
 'DQS0_B_T': CDS_PINID='DQS0_B_T';
NET_NAME
'M_I_CPU0_SB_DQS_DP<1>'
 '@T6G_MB_LIB.T6G(SCH_1):M_I_CPU0_SB_DQS_DP'<1>:
 C_SIGNAL='@t6g_mb_lib.t6g(sch_1):m_i_cpu0_sb_dqs_dp(1)';
NODE_NAME     U25 CK20
 '@T6G_MB_LIB.T6G(SCH_1):PAGE18_I159@PURE_QUANTA.GENOA_SP5(CHIPS)':
 'MIB_DQS_H1': CDS_PINID='MIB_DQS_H1';
NODE_NAME     J18 115
 '@T6G_MB_LIB.T6G(SCH_1):PAGE93_I236@PURE_QUANTA.SCONN288_DDR506112002KQ(CHIPS)':
 'DQS1_B_T': CDS_PINID='DQS1_B_T';
NET_NAME
'M_I_CPU0_SB_DQS_DP<2>'
 '@T6G_MB_LIB.T6G(SCH_1):M_I_CPU0_SB_DQS_DP'<2>:
 C_SIGNAL='@t6g_mb_lib.t6g(sch_1):m_i_cpu0_sb_dqs_dp(2)';
NODE_NAME     U25 CT20
 '@T6G_MB_LIB.T6G(SCH_1):PAGE18_I159@PURE_QUANTA.GENOA_SP5(CHIPS)':
 'MIB_DQS_H2': CDS_PINID='MIB_DQS_H2';
NODE_NAME     J18 126
 '@T6G_MB_LIB.T6G(SCH_1):PAGE93_I236@PURE_QUANTA.SCONN288_DDR506112002KQ(CHIPS)':
 'DQS2_B_T': CDS_PINID='DQS2_B_T';
NET_NAME
'M_I_CPU0_SB_DQS_DP<3>'
 '@T6G_MB_LIB.T6G(SCH_1):M_I_CPU0_SB_DQS_DP'<3>:
 C_SIGNAL='@t6g_mb_lib.t6g(sch_1):m_i_cpu0_sb_dqs_dp(3)';
NODE_NAME     U25 DB20
 '@T6G_MB_LIB.T6G(SCH_1):PAGE18_I159@PURE_QUANTA.GENOA_SP5(CHIPS)':
 'MIB_DQS_H3': CDS_PINID='MIB_DQS_H3';
NODE_NAME     J18 137
 '@T6G_MB_LIB.T6G(SCH_1):PAGE93_I236@PURE_QUANTA.SCONN288_DDR506112002KQ(CHIPS)':
 'DQS3_B_T': CDS_PINID='DQS3_B_T';
NET_NAME
'M_I_CPU0_SB_DQS_DP<4>'
 '@T6G_MB_LIB.T6G(SCH_1):M_I_CPU0_SB_DQS_DP'<4>:
 C_SIGNAL='@t6g_mb_lib.t6g(sch_1):m_i_cpu0_sb_dqs_dp(4)';
NODE_NAME     U25 BY21
 '@T6G_MB_LIB.T6G(SCH_1):PAGE18_I159@PURE_QUANTA.GENOA_SP5(CHIPS)':
 'MIB_DQS_H4': CDS_PINID='MIB_DQS_H4';
NODE_NAME     J18 239
 '@T6G_MB_LIB.T6G(SCH_1):PAGE93_I236@PURE_QUANTA.SCONN288_DDR506112002KQ(CHIPS)':
 'DQS4_B_T': CDS_PINID='DQS4_B_T';
NET_NAME
'M_I_CPU0_SB_DQS_DP<5>'
 '@T6G_MB_LIB.T6G(SCH_1):M_I_CPU0_SB_DQS_DP'<5>:
 C_SIGNAL='@t6g_mb_lib.t6g(sch_1):m_i_cpu0_sb_dqs_dp(5)';
NODE_NAME     U25 CF21
 '@T6G_MB_LIB.T6G(SCH_1):PAGE18_I159@PURE_QUANTA.GENOA_SP5(CHIPS)':
 'MIB_DQS_H5': CDS_PINID='MIB_DQS_H5';
NODE_NAME     J18 250
 '@T6G_MB_LIB.T6G(SCH_1):PAGE93_I236@PURE_QUANTA.SCONN288_DDR506112002KQ(CHIPS)':
 'DQS5_B_T||TDQS5_B_T': CDS_PINID='\dqs5_b_t||tdqs5_b_t\';
NET_NAME
'M_I_CPU0_SB_DQS_DP<6>'
 '@T6G_MB_LIB.T6G(SCH_1):M_I_CPU0_SB_DQS_DP'<6>:
 C_SIGNAL='@t6g_mb_lib.t6g(sch_1):m_i_cpu0_sb_dqs_dp(6)';
NODE_NAME     U25 CM21
 '@T6G_MB_LIB.T6G(SCH_1):PAGE18_I159@PURE_QUANTA.GENOA_SP5(CHIPS)':
 'MIB_DQS_H6': CDS_PINID='MIB_DQS_H6';
NODE_NAME     J18 261
 '@T6G_MB_LIB.T6G(SCH_1):PAGE93_I236@PURE_QUANTA.SCONN288_DDR506112002KQ(CHIPS)':
 'DQS6_B_T||TDQS6_B_T': CDS_PINID='\dqs6_b_t||tdqs6_b_t\';
NET_NAME
'M_I_CPU0_SB_DQS_DP<7>'
 '@T6G_MB_LIB.T6G(SCH_1):M_I_CPU0_SB_DQS_DP'<7>:
 C_SIGNAL='@t6g_mb_lib.t6g(sch_1):m_i_cpu0_sb_dqs_dp(7)';
NODE_NAME     U25 CV21
 '@T6G_MB_LIB.T6G(SCH_1):PAGE18_I159@PURE_QUANTA.GENOA_SP5(CHIPS)':
 'MIB_DQS_H7': CDS_PINID='MIB_DQS_H7';
NODE_NAME     J18 272
 '@T6G_MB_LIB.T6G(SCH_1):PAGE93_I236@PURE_QUANTA.SCONN288_DDR506112002KQ(CHIPS)':
 'DQS7_B_T||TDQS7_B_T': CDS_PINID='\dqs7_b_t||tdqs7_b_t\';
NET_NAME
'M_I_CPU0_SB_DQS_DP<8>'
 '@T6G_MB_LIB.T6G(SCH_1):M_I_CPU0_SB_DQS_DP'<8>:
 C_SIGNAL='@t6g_mb_lib.t6g(sch_1):m_i_cpu0_sb_dqs_dp(8)';
NODE_NAME     U25 DD21
 '@T6G_MB_LIB.T6G(SCH_1):PAGE18_I159@PURE_QUANTA.GENOA_SP5(CHIPS)':
 'MIB_DQS_H8': CDS_PINID='MIB_DQS_H8';
NODE_NAME     J18 283
 '@T6G_MB_LIB.T6G(SCH_1):PAGE93_I236@PURE_QUANTA.SCONN288_DDR506112002KQ(CHIPS)':
 'DQS8_B_T||TDQS8_B_T': CDS_PINID='\dqs8_b_t||tdqs8_b_t\';
NET_NAME
'M_I_CPU0_SB_DQS_DP<9>'
 '@T6G_MB_LIB.T6G(SCH_1):M_I_CPU0_SB_DQS_DP'<9>:
 C_SIGNAL='@t6g_mb_lib.t6g(sch_1):m_i_cpu0_sb_dqs_dp(9)';
NODE_NAME     U25 BV20
 '@T6G_MB_LIB.T6G(SCH_1):PAGE18_I159@PURE_QUANTA.GENOA_SP5(CHIPS)':
 'MIB_DQS_H9': CDS_PINID='MIB_DQS_H9';
NODE_NAME     J18 93
 '@T6G_MB_LIB.T6G(SCH_1):PAGE93_I236@PURE_QUANTA.SCONN288_DDR506112002KQ(CHIPS)':
 'DQS9_B_T||TDQS9_B_T||DBI4_B_N': CDS_PINID='\dqs9_b_t||tdqs9_b_t||dbi4_b_n\';
NET_NAME
'M_I_CPU0_SB_PAR'
 '@T6G_MB_LIB.T6G(SCH_1):M_I_CPU0_SB_PAR':
 C_SIGNAL='@t6g_mb_lib.t6g(sch_1):m_i_cpu0_sb_par';
NODE_NAME     U25 BL21
 '@T6G_MB_LIB.T6G(SCH_1):PAGE18_I159@PURE_QUANTA.GENOA_SP5(CHIPS)':
 'MIB_PAR': CDS_PINID='MIB_PAR';
NODE_NAME     J18 227
 '@T6G_MB_LIB.T6G(SCH_1):PAGE93_I22@PURE_QUANTA.SCONN288_DDR506112002KQ(CHIPS)':
 'PAR_B': CDS_PINID='PAR_B';
NET_NAME
'M_I_CPU0_SB_RSP<0>'
 '@T6G_MB_LIB.T6G(SCH_1):M_I_CPU0_SB_RSP'<0>:
 C_SIGNAL='@t6g_mb_lib.t6g(sch_1):m_i_cpu0_sb_rsp(0)';
NODE_NAME     U25 BP20
 '@T6G_MB_LIB.T6G(SCH_1):PAGE18_I159@PURE_QUANTA.GENOA_SP5(CHIPS)':
 'MIB0_RSP_L': CDS_PINID='MIB0_RSP_L';
NODE_NAME     J18 87
 '@T6G_MB_LIB.T6G(SCH_1):PAGE93_I22@PURE_QUANTA.SCONN288_DDR506112002KQ(CHIPS)':
 'LBS||RSP_B_N': CDS_PINID='\lbs||rsp_b_n\';
NET_NAME
'M_I_CPU1_ALERT_N'
 '@T6G_MB_LIB.T6G(SCH_1):M_I_CPU1_ALERT_N':
 C_SIGNAL='@t6g_mb_lib.t6g(sch_1):m_i_cpu1_alert_n';
NODE_NAME     R508 1
 '@T6G_MB_LIB.T6G(SCH_1):PAGE45_I314@PURE_QUANTA.Q_RES(CHIPS)':
 'A': CDS_PINID='A';
NODE_NAME     J100 62
 '@T6G_MB_LIB.T6G(SCH_1):PAGE105_I22@PURE_QUANTA.SCONN288_DDR506112002KQ(CHIPS)':
 'ALERT_N': CDS_PINID='ALERT_N';
NET_NAME
'M_I_CPU1_ALERT_R_N'
 '@T6G_MB_LIB.T6G(SCH_1):M_I_CPU1_ALERT_R_N':
 C_SIGNAL='@t6g_mb_lib.t6g(sch_1):m_i_cpu1_alert_r_n';
NODE_NAME     U26 AT21
 '@T6G_MB_LIB.T6G(SCH_1):PAGE45_I159@PURE_QUANTA.GENOA_SP5(CHIPS)':
 'MI_ALERT_L': CDS_PINID='MI_ALERT_L';
NODE_NAME     R508 2
 '@T6G_MB_LIB.T6G(SCH_1):PAGE45_I314@PURE_QUANTA.Q_RES(CHIPS)':
 'B': CDS_PINID='B';
NET_NAME
'M_I_CPU1_CLK_DN<0>'
 '@T6G_MB_LIB.T6G(SCH_1):M_I_CPU1_CLK_DN'<0>:
 C_SIGNAL='@t6g_mb_lib.t6g(sch_1):m_i_cpu1_clk_dn(0)';
NODE_NAME     U26 BD20
 '@T6G_MB_LIB.T6G(SCH_1):PAGE45_I159@PURE_QUANTA.GENOA_SP5(CHIPS)':
 'MI0_CLK_L': CDS_PINID='MI0_CLK_L';
NODE_NAME     J100 218
 '@T6G_MB_LIB.T6G(SCH_1):PAGE105_I22@PURE_QUANTA.SCONN288_DDR506112002KQ(CHIPS)':
 'CK_C': CDS_PINID='CK_C';
NET_NAME
'M_I_CPU1_CLK_DP<0>'
 '@T6G_MB_LIB.T6G(SCH_1):M_I_CPU1_CLK_DP'<0>:
 C_SIGNAL='@t6g_mb_lib.t6g(sch_1):m_i_cpu1_clk_dp(0)';
NODE_NAME     U26 BC19
 '@T6G_MB_LIB.T6G(SCH_1):PAGE45_I159@PURE_QUANTA.GENOA_SP5(CHIPS)':
 'MI0_CLK_H': CDS_PINID='MI0_CLK_H';
NODE_NAME     J100 217
 '@T6G_MB_LIB.T6G(SCH_1):PAGE105_I22@PURE_QUANTA.SCONN288_DDR506112002KQ(CHIPS)':
 'CK_T': CDS_PINID='CK_T';
NET_NAME
'M_I_CPU1_RESET_N'
 '@T6G_MB_LIB.T6G(SCH_1):M_I_CPU1_RESET_N':
 C_SIGNAL='@t6g_mb_lib.t6g(sch_1):m_i_cpu1_reset_n';
NODE_NAME     U26 AU21
 '@T6G_MB_LIB.T6G(SCH_1):PAGE45_I159@PURE_QUANTA.GENOA_SP5(CHIPS)':
 'MI_RESET_L': CDS_PINID='MI_RESET_L';
NODE_NAME     J100 207
 '@T6G_MB_LIB.T6G(SCH_1):PAGE105_I22@PURE_QUANTA.SCONN288_DDR506112002KQ(CHIPS)':
 'RESET_N': CDS_PINID='RESET_N';
NET_NAME
'M_I_CPU1_SA_CA<0>'
 '@T6G_MB_LIB.T6G(SCH_1):M_I_CPU1_SA_CA'<0>:
 C_SIGNAL='@t6g_mb_lib.t6g(sch_1):m_i_cpu1_sa_ca(0)';
NODE_NAME     U26 AW19
 '@T6G_MB_LIB.T6G(SCH_1):PAGE45_I159@PURE_QUANTA.GENOA_SP5(CHIPS)':
 'MIA_CA0': CDS_PINID='MIA_CA0';
NODE_NAME     J100 66
 '@T6G_MB_LIB.T6G(SCH_1):PAGE105_I22@PURE_QUANTA.SCONN288_DDR506112002KQ(CHIPS)':
 'CA0_A': CDS_PINID='CA0_A';
NET_NAME
'M_I_CPU1_SA_CA<1>'
 '@T6G_MB_LIB.T6G(SCH_1):M_I_CPU1_SA_CA'<1>:
 C_SIGNAL='@t6g_mb_lib.t6g(sch_1):m_i_cpu1_sa_ca(1)';
NODE_NAME     U26 AY20
 '@T6G_MB_LIB.T6G(SCH_1):PAGE45_I159@PURE_QUANTA.GENOA_SP5(CHIPS)':
 'MIA_CA1': CDS_PINID='MIA_CA1';
NODE_NAME     J100 211
 '@T6G_MB_LIB.T6G(SCH_1):PAGE105_I22@PURE_QUANTA.SCONN288_DDR506112002KQ(CHIPS)':
 'CA1_A': CDS_PINID='CA1_A';
NET_NAME
'M_I_CPU1_SA_CA<2>'
 '@T6G_MB_LIB.T6G(SCH_1):M_I_CPU1_SA_CA'<2>:
 C_SIGNAL='@t6g_mb_lib.t6g(sch_1):m_i_cpu1_sa_ca(2)';
NODE_NAME     U26 AY21
 '@T6G_MB_LIB.T6G(SCH_1):PAGE45_I159@PURE_QUANTA.GENOA_SP5(CHIPS)':
 'MIA_CA2': CDS_PINID='MIA_CA2';
NODE_NAME     J100 68
 '@T6G_MB_LIB.T6G(SCH_1):PAGE105_I22@PURE_QUANTA.SCONN288_DDR506112002KQ(CHIPS)':
 'CA2_A': CDS_PINID='CA2_A';
NET_NAME
'M_I_CPU1_SA_CA<3>'
 '@T6G_MB_LIB.T6G(SCH_1):M_I_CPU1_SA_CA'<3>:
 C_SIGNAL='@t6g_mb_lib.t6g(sch_1):m_i_cpu1_sa_ca(3)';
NODE_NAME     U26 BA21
 '@T6G_MB_LIB.T6G(SCH_1):PAGE45_I159@PURE_QUANTA.GENOA_SP5(CHIPS)':
 'MIA_CA3': CDS_PINID='MIA_CA3';
NODE_NAME     J100 213
 '@T6G_MB_LIB.T6G(SCH_1):PAGE105_I22@PURE_QUANTA.SCONN288_DDR506112002KQ(CHIPS)':
 'CA3_A': CDS_PINID='CA3_A';
NET_NAME
'M_I_CPU1_SA_CA<4>'
 '@T6G_MB_LIB.T6G(SCH_1):M_I_CPU1_SA_CA'<4>:
 C_SIGNAL='@t6g_mb_lib.t6g(sch_1):m_i_cpu1_sa_ca(4)';
NODE_NAME     U26 BA19
 '@T6G_MB_LIB.T6G(SCH_1):PAGE45_I159@PURE_QUANTA.GENOA_SP5(CHIPS)':
 'MIA_CA4': CDS_PINID='MIA_CA4';
NODE_NAME     J100 70
 '@T6G_MB_LIB.T6G(SCH_1):PAGE105_I22@PURE_QUANTA.SCONN288_DDR506112002KQ(CHIPS)':
 'CA4_A': CDS_PINID='CA4_A';
NET_NAME
'M_I_CPU1_SA_CA<5>'
 '@T6G_MB_LIB.T6G(SCH_1):M_I_CPU1_SA_CA'<5>:
 C_SIGNAL='@t6g_mb_lib.t6g(sch_1):m_i_cpu1_sa_ca(5)';
NODE_NAME     U26 BB20
 '@T6G_MB_LIB.T6G(SCH_1):PAGE45_I159@PURE_QUANTA.GENOA_SP5(CHIPS)':
 'MIA_CA5': CDS_PINID='MIA_CA5';
NODE_NAME     J100 215
 '@T6G_MB_LIB.T6G(SCH_1):PAGE105_I22@PURE_QUANTA.SCONN288_DDR506112002KQ(CHIPS)':
 'CA5_A': CDS_PINID='CA5_A';
NET_NAME
'M_I_CPU1_SA_CA<6>'
 '@T6G_MB_LIB.T6G(SCH_1):M_I_CPU1_SA_CA'<6>:
 C_SIGNAL='@t6g_mb_lib.t6g(sch_1):m_i_cpu1_sa_ca(6)';
NODE_NAME     U26 BB21
 '@T6G_MB_LIB.T6G(SCH_1):PAGE45_I159@PURE_QUANTA.GENOA_SP5(CHIPS)':
 'MIA_CA6': CDS_PINID='MIA_CA6';
NODE_NAME     J100 72
 '@T6G_MB_LIB.T6G(SCH_1):PAGE105_I22@PURE_QUANTA.SCONN288_DDR506112002KQ(CHIPS)':
 'CA6_A': CDS_PINID='CA6_A';
NET_NAME
'M_I_CPU1_SA_CB<0>'
 '@T6G_MB_LIB.T6G(SCH_1):M_I_CPU1_SA_CB'<0>:
 C_SIGNAL='@t6g_mb_lib.t6g(sch_1):m_i_cpu1_sa_cb(0)';
NODE_NAME     U26 AJ19
 '@T6G_MB_LIB.T6G(SCH_1):PAGE45_I159@PURE_QUANTA.GENOA_SP5(CHIPS)':
 'MIA_CHECK0': CDS_PINID='MIA_CHECK0';
NODE_NAME     J100 51
 '@T6G_MB_LIB.T6G(SCH_1):PAGE105_I22@PURE_QUANTA.SCONN288_DDR506112002KQ(CHIPS)':
 'CB0_A': CDS_PINID='CB0_A';
NET_NAME
'M_I_CPU1_SA_CB<1>'
 '@T6G_MB_LIB.T6G(SCH_1):M_I_CPU1_SA_CB'<1>:
 C_SIGNAL='@t6g_mb_lib.t6g(sch_1):m_i_cpu1_sa_cb(1)';
NODE_NAME     U26 AK21
 '@T6G_MB_LIB.T6G(SCH_1):PAGE45_I159@PURE_QUANTA.GENOA_SP5(CHIPS)':
 'MIA_CHECK1': CDS_PINID='MIA_CHECK1';
NODE_NAME     J100 53
 '@T6G_MB_LIB.T6G(SCH_1):PAGE105_I22@PURE_QUANTA.SCONN288_DDR506112002KQ(CHIPS)':
 'CB1_A': CDS_PINID='CB1_A';
NET_NAME
'M_I_CPU1_SA_CB<2>'
 '@T6G_MB_LIB.T6G(SCH_1):M_I_CPU1_SA_CB'<2>:
 C_SIGNAL='@t6g_mb_lib.t6g(sch_1):m_i_cpu1_sa_cb(2)';
NODE_NAME     U26 AK20
 '@T6G_MB_LIB.T6G(SCH_1):PAGE45_I159@PURE_QUANTA.GENOA_SP5(CHIPS)':
 'MIA_CHECK2': CDS_PINID='MIA_CHECK2';
NODE_NAME     J100 196
 '@T6G_MB_LIB.T6G(SCH_1):PAGE105_I22@PURE_QUANTA.SCONN288_DDR506112002KQ(CHIPS)':
 'CB2_A': CDS_PINID='CB2_A';
NET_NAME
'M_I_CPU1_SA_CB<3>'
 '@T6G_MB_LIB.T6G(SCH_1):M_I_CPU1_SA_CB'<3>:
 C_SIGNAL='@t6g_mb_lib.t6g(sch_1):m_i_cpu1_sa_cb(3)';
NODE_NAME     U26 AL21
 '@T6G_MB_LIB.T6G(SCH_1):PAGE45_I159@PURE_QUANTA.GENOA_SP5(CHIPS)':
 'MIA_CHECK3': CDS_PINID='MIA_CHECK3';
NODE_NAME     J100 198
 '@T6G_MB_LIB.T6G(SCH_1):PAGE105_I22@PURE_QUANTA.SCONN288_DDR506112002KQ(CHIPS)':
 'CB3_A': CDS_PINID='CB3_A';
NET_NAME
'M_I_CPU1_SA_CB<4>'
 '@T6G_MB_LIB.T6G(SCH_1):M_I_CPU1_SA_CB'<4>:
 C_SIGNAL='@t6g_mb_lib.t6g(sch_1):m_i_cpu1_sa_cb(4)';
NODE_NAME     U26 AN19
 '@T6G_MB_LIB.T6G(SCH_1):PAGE45_I159@PURE_QUANTA.GENOA_SP5(CHIPS)':
 'MIA_CHECK4': CDS_PINID='MIA_CHECK4';
NODE_NAME     J100 58
 '@T6G_MB_LIB.T6G(SCH_1):PAGE105_I22@PURE_QUANTA.SCONN288_DDR506112002KQ(CHIPS)':
 'CB4_A': CDS_PINID='CB4_A';
NET_NAME
'M_I_CPU1_SA_CB<5>'
 '@T6G_MB_LIB.T6G(SCH_1):M_I_CPU1_SA_CB'<5>:
 C_SIGNAL='@t6g_mb_lib.t6g(sch_1):m_i_cpu1_sa_cb(5)';
NODE_NAME     U26 AP21
 '@T6G_MB_LIB.T6G(SCH_1):PAGE45_I159@PURE_QUANTA.GENOA_SP5(CHIPS)':
 'MIA_CHECK5': CDS_PINID='MIA_CHECK5';
NODE_NAME     J100 60
 '@T6G_MB_LIB.T6G(SCH_1):PAGE105_I22@PURE_QUANTA.SCONN288_DDR506112002KQ(CHIPS)':
 'CB5_A': CDS_PINID='CB5_A';
NET_NAME
'M_I_CPU1_SA_CB<6>'
 '@T6G_MB_LIB.T6G(SCH_1):M_I_CPU1_SA_CB'<6>:
 C_SIGNAL='@t6g_mb_lib.t6g(sch_1):m_i_cpu1_sa_cb(6)';
NODE_NAME     U26 AP20
 '@T6G_MB_LIB.T6G(SCH_1):PAGE45_I159@PURE_QUANTA.GENOA_SP5(CHIPS)':
 'MIA_CHECK6': CDS_PINID='MIA_CHECK6';
NODE_NAME     J100 203
 '@T6G_MB_LIB.T6G(SCH_1):PAGE105_I22@PURE_QUANTA.SCONN288_DDR506112002KQ(CHIPS)':
 'CB6_A': CDS_PINID='CB6_A';
NET_NAME
'M_I_CPU1_SA_CB<7>'
 '@T6G_MB_LIB.T6G(SCH_1):M_I_CPU1_SA_CB'<7>:
 C_SIGNAL='@t6g_mb_lib.t6g(sch_1):m_i_cpu1_sa_cb(7)';
NODE_NAME     U26 AR21
 '@T6G_MB_LIB.T6G(SCH_1):PAGE45_I159@PURE_QUANTA.GENOA_SP5(CHIPS)':
 'MIA_CHECK7': CDS_PINID='MIA_CHECK7';
NODE_NAME     J100 205
 '@T6G_MB_LIB.T6G(SCH_1):PAGE105_I22@PURE_QUANTA.SCONN288_DDR506112002KQ(CHIPS)':
 'CB7_A': CDS_PINID='CB7_A';
NET_NAME
'M_I_CPU1_SA_CS_N<0>'
 '@T6G_MB_LIB.T6G(SCH_1):M_I_CPU1_SA_CS_N'<0>:
 C_SIGNAL='@t6g_mb_lib.t6g(sch_1):m_i_cpu1_sa_cs_n(0)';
NODE_NAME     U26 AU19
 '@T6G_MB_LIB.T6G(SCH_1):PAGE45_I159@PURE_QUANTA.GENOA_SP5(CHIPS)':
 'MIA0_CS_L0': CDS_PINID='MIA0_CS_L0';
NODE_NAME     J100 64
 '@T6G_MB_LIB.T6G(SCH_1):PAGE105_I22@PURE_QUANTA.SCONN288_DDR506112002KQ(CHIPS)':
 'CS0_A_N': CDS_PINID='CS0_A_N';
NET_NAME
'M_I_CPU1_SA_CS_N<1>'
 '@T6G_MB_LIB.T6G(SCH_1):M_I_CPU1_SA_CS_N'<1>:
 C_SIGNAL='@t6g_mb_lib.t6g(sch_1):m_i_cpu1_sa_cs_n(1)';
NODE_NAME     U26 AV21
 '@T6G_MB_LIB.T6G(SCH_1):PAGE45_I159@PURE_QUANTA.GENOA_SP5(CHIPS)':
 'MIA0_CS_L1': CDS_PINID='MIA0_CS_L1';
NODE_NAME     J100 209
 '@T6G_MB_LIB.T6G(SCH_1):PAGE105_I22@PURE_QUANTA.SCONN288_DDR506112002KQ(CHIPS)':
 'CS1_A_N': CDS_PINID='CS1_A_N';
NET_NAME
'M_I_CPU1_SA_DQ<0>'
 '@T6G_MB_LIB.T6G(SCH_1):M_I_CPU1_SA_DQ'<0>:
 C_SIGNAL='@t6g_mb_lib.t6g(sch_1):m_i_cpu1_sa_dq(0)';
NODE_NAME     U26 E19
 '@T6G_MB_LIB.T6G(SCH_1):PAGE45_I159@PURE_QUANTA.GENOA_SP5(CHIPS)':
 'MIA_DATA0': CDS_PINID='MIA_DATA0';
NODE_NAME     J100 7
 '@T6G_MB_LIB.T6G(SCH_1):PAGE105_I22@PURE_QUANTA.SCONN288_DDR506112002KQ(CHIPS)':
 'DQ0_A': CDS_PINID='DQ0_A';
NET_NAME
'M_I_CPU1_SA_DQ<10>'
 '@T6G_MB_LIB.T6G(SCH_1):M_I_CPU1_SA_DQ'<10>:
 C_SIGNAL='@t6g_mb_lib.t6g(sch_1):m_i_cpu1_sa_dq(10)';
NODE_NAME     U26 M20
 '@T6G_MB_LIB.T6G(SCH_1):PAGE45_I159@PURE_QUANTA.GENOA_SP5(CHIPS)':
 'MIA_DATA10': CDS_PINID='MIA_DATA10';
NODE_NAME     J100 163
 '@T6G_MB_LIB.T6G(SCH_1):PAGE105_I22@PURE_QUANTA.SCONN288_DDR506112002KQ(CHIPS)':
 'DQ10_A': CDS_PINID='DQ10_A';
NET_NAME
'M_I_CPU1_SA_DQ<11>'
 '@T6G_MB_LIB.T6G(SCH_1):M_I_CPU1_SA_DQ'<11>:
 C_SIGNAL='@t6g_mb_lib.t6g(sch_1):m_i_cpu1_sa_dq(11)';
NODE_NAME     U26 N21
 '@T6G_MB_LIB.T6G(SCH_1):PAGE45_I159@PURE_QUANTA.GENOA_SP5(CHIPS)':
 'MIA_DATA11': CDS_PINID='MIA_DATA11';
NODE_NAME     J100 165
 '@T6G_MB_LIB.T6G(SCH_1):PAGE105_I22@PURE_QUANTA.SCONN288_DDR506112002KQ(CHIPS)':
 'DQ11_A': CDS_PINID='DQ11_A';
NET_NAME
'M_I_CPU1_SA_DQ<12>'
 '@T6G_MB_LIB.T6G(SCH_1):M_I_CPU1_SA_DQ'<12>:
 C_SIGNAL='@t6g_mb_lib.t6g(sch_1):m_i_cpu1_sa_dq(12)';
NODE_NAME     U26 R19
 '@T6G_MB_LIB.T6G(SCH_1):PAGE45_I159@PURE_QUANTA.GENOA_SP5(CHIPS)':
 'MIA_DATA12': CDS_PINID='MIA_DATA12';
NODE_NAME     J100 25
 '@T6G_MB_LIB.T6G(SCH_1):PAGE105_I22@PURE_QUANTA.SCONN288_DDR506112002KQ(CHIPS)':
 'DQ12_A': CDS_PINID='DQ12_A';
NET_NAME
'M_I_CPU1_SA_DQ<13>'
 '@T6G_MB_LIB.T6G(SCH_1):M_I_CPU1_SA_DQ'<13>:
 C_SIGNAL='@t6g_mb_lib.t6g(sch_1):m_i_cpu1_sa_dq(13)';
NODE_NAME     U26 T21
 '@T6G_MB_LIB.T6G(SCH_1):PAGE45_I159@PURE_QUANTA.GENOA_SP5(CHIPS)':
 'MIA_DATA13': CDS_PINID='MIA_DATA13';
NODE_NAME     J100 27
 '@T6G_MB_LIB.T6G(SCH_1):PAGE105_I22@PURE_QUANTA.SCONN288_DDR506112002KQ(CHIPS)':
 'DQ13_A': CDS_PINID='DQ13_A';
NET_NAME
'M_I_CPU1_SA_DQ<14>'
 '@T6G_MB_LIB.T6G(SCH_1):M_I_CPU1_SA_DQ'<14>:
 C_SIGNAL='@t6g_mb_lib.t6g(sch_1):m_i_cpu1_sa_dq(14)';
NODE_NAME     U26 T20
 '@T6G_MB_LIB.T6G(SCH_1):PAGE45_I159@PURE_QUANTA.GENOA_SP5(CHIPS)':
 'MIA_DATA14': CDS_PINID='MIA_DATA14';
NODE_NAME     J100 170
 '@T6G_MB_LIB.T6G(SCH_1):PAGE105_I22@PURE_QUANTA.SCONN288_DDR506112002KQ(CHIPS)':
 'DQ14_A': CDS_PINID='DQ14_A';
NET_NAME
'M_I_CPU1_SA_DQ<15>'
 '@T6G_MB_LIB.T6G(SCH_1):M_I_CPU1_SA_DQ'<15>:
 C_SIGNAL='@t6g_mb_lib.t6g(sch_1):m_i_cpu1_sa_dq(15)';
NODE_NAME     U26 U21
 '@T6G_MB_LIB.T6G(SCH_1):PAGE45_I159@PURE_QUANTA.GENOA_SP5(CHIPS)':
 'MIA_DATA15': CDS_PINID='MIA_DATA15';
NODE_NAME     J100 172
 '@T6G_MB_LIB.T6G(SCH_1):PAGE105_I22@PURE_QUANTA.SCONN288_DDR506112002KQ(CHIPS)':
 'DQ15_A': CDS_PINID='DQ15_A';
NET_NAME
'M_I_CPU1_SA_DQ<16>'
 '@T6G_MB_LIB.T6G(SCH_1):M_I_CPU1_SA_DQ'<16>:
 C_SIGNAL='@t6g_mb_lib.t6g(sch_1):m_i_cpu1_sa_dq(16)';
NODE_NAME     U26 U19
 '@T6G_MB_LIB.T6G(SCH_1):PAGE45_I159@PURE_QUANTA.GENOA_SP5(CHIPS)':
 'MIA_DATA16': CDS_PINID='MIA_DATA16';
NODE_NAME     J100 29
 '@T6G_MB_LIB.T6G(SCH_1):PAGE105_I22@PURE_QUANTA.SCONN288_DDR506112002KQ(CHIPS)':
 'DQ16_A': CDS_PINID='DQ16_A';
NET_NAME
'M_I_CPU1_SA_DQ<17>'
 '@T6G_MB_LIB.T6G(SCH_1):M_I_CPU1_SA_DQ'<17>:
 C_SIGNAL='@t6g_mb_lib.t6g(sch_1):m_i_cpu1_sa_dq(17)';
NODE_NAME     U26 V21
 '@T6G_MB_LIB.T6G(SCH_1):PAGE45_I159@PURE_QUANTA.GENOA_SP5(CHIPS)':
 'MIA_DATA17': CDS_PINID='MIA_DATA17';
NODE_NAME     J100 31
 '@T6G_MB_LIB.T6G(SCH_1):PAGE105_I22@PURE_QUANTA.SCONN288_DDR506112002KQ(CHIPS)':
 'DQ17_A': CDS_PINID='DQ17_A';
NET_NAME
'M_I_CPU1_SA_DQ<18>'
 '@T6G_MB_LIB.T6G(SCH_1):M_I_CPU1_SA_DQ'<18>:
 C_SIGNAL='@t6g_mb_lib.t6g(sch_1):m_i_cpu1_sa_dq(18)';
NODE_NAME     U26 V20
 '@T6G_MB_LIB.T6G(SCH_1):PAGE45_I159@PURE_QUANTA.GENOA_SP5(CHIPS)':
 'MIA_DATA18': CDS_PINID='MIA_DATA18';
NODE_NAME     J100 174
 '@T6G_MB_LIB.T6G(SCH_1):PAGE105_I22@PURE_QUANTA.SCONN288_DDR506112002KQ(CHIPS)':
 'DQ18_A': CDS_PINID='DQ18_A';
NET_NAME
'M_I_CPU1_SA_DQ<19>'
 '@T6G_MB_LIB.T6G(SCH_1):M_I_CPU1_SA_DQ'<19>:
 C_SIGNAL='@t6g_mb_lib.t6g(sch_1):m_i_cpu1_sa_dq(19)';
NODE_NAME     U26 W21
 '@T6G_MB_LIB.T6G(SCH_1):PAGE45_I159@PURE_QUANTA.GENOA_SP5(CHIPS)':
 'MIA_DATA19': CDS_PINID='MIA_DATA19';
NODE_NAME     J100 176
 '@T6G_MB_LIB.T6G(SCH_1):PAGE105_I22@PURE_QUANTA.SCONN288_DDR506112002KQ(CHIPS)':
 'DQ19_A': CDS_PINID='DQ19_A';
NET_NAME
'M_I_CPU1_SA_DQ<1>'
 '@T6G_MB_LIB.T6G(SCH_1):M_I_CPU1_SA_DQ'<1>:
 C_SIGNAL='@t6g_mb_lib.t6g(sch_1):m_i_cpu1_sa_dq(1)';
NODE_NAME     U26 F21
 '@T6G_MB_LIB.T6G(SCH_1):PAGE45_I159@PURE_QUANTA.GENOA_SP5(CHIPS)':
 'MIA_DATA1': CDS_PINID='MIA_DATA1';
NODE_NAME     J100 9
 '@T6G_MB_LIB.T6G(SCH_1):PAGE105_I22@PURE_QUANTA.SCONN288_DDR506112002KQ(CHIPS)':
 'DQ1_A': CDS_PINID='DQ1_A';
NET_NAME
'M_I_CPU1_SA_DQ<20>'
 '@T6G_MB_LIB.T6G(SCH_1):M_I_CPU1_SA_DQ'<20>:
 C_SIGNAL='@t6g_mb_lib.t6g(sch_1):m_i_cpu1_sa_dq(20)';
NODE_NAME     U26 AA19
 '@T6G_MB_LIB.T6G(SCH_1):PAGE45_I159@PURE_QUANTA.GENOA_SP5(CHIPS)':
 'MIA_DATA20': CDS_PINID='MIA_DATA20';
NODE_NAME     J100 36
 '@T6G_MB_LIB.T6G(SCH_1):PAGE105_I22@PURE_QUANTA.SCONN288_DDR506112002KQ(CHIPS)':
 'DQ20_A': CDS_PINID='DQ20_A';
NET_NAME
'M_I_CPU1_SA_DQ<21>'
 '@T6G_MB_LIB.T6G(SCH_1):M_I_CPU1_SA_DQ'<21>:
 C_SIGNAL='@t6g_mb_lib.t6g(sch_1):m_i_cpu1_sa_dq(21)';
NODE_NAME     U26 AB21
 '@T6G_MB_LIB.T6G(SCH_1):PAGE45_I159@PURE_QUANTA.GENOA_SP5(CHIPS)':
 'MIA_DATA21': CDS_PINID='MIA_DATA21';
NODE_NAME     J100 38
 '@T6G_MB_LIB.T6G(SCH_1):PAGE105_I22@PURE_QUANTA.SCONN288_DDR506112002KQ(CHIPS)':
 'DQ21_A': CDS_PINID='DQ21_A';
NET_NAME
'M_I_CPU1_SA_DQ<22>'
 '@T6G_MB_LIB.T6G(SCH_1):M_I_CPU1_SA_DQ'<22>:
 C_SIGNAL='@t6g_mb_lib.t6g(sch_1):m_i_cpu1_sa_dq(22)';
NODE_NAME     U26 AB20
 '@T6G_MB_LIB.T6G(SCH_1):PAGE45_I159@PURE_QUANTA.GENOA_SP5(CHIPS)':
 'MIA_DATA22': CDS_PINID='MIA_DATA22';
NODE_NAME     J100 181
 '@T6G_MB_LIB.T6G(SCH_1):PAGE105_I22@PURE_QUANTA.SCONN288_DDR506112002KQ(CHIPS)':
 'DQ22_A': CDS_PINID='DQ22_A';
NET_NAME
'M_I_CPU1_SA_DQ<23>'
 '@T6G_MB_LIB.T6G(SCH_1):M_I_CPU1_SA_DQ'<23>:
 C_SIGNAL='@t6g_mb_lib.t6g(sch_1):m_i_cpu1_sa_dq(23)';
NODE_NAME     U26 AC21
 '@T6G_MB_LIB.T6G(SCH_1):PAGE45_I159@PURE_QUANTA.GENOA_SP5(CHIPS)':
 'MIA_DATA23': CDS_PINID='MIA_DATA23';
NODE_NAME     J100 183
 '@T6G_MB_LIB.T6G(SCH_1):PAGE105_I22@PURE_QUANTA.SCONN288_DDR506112002KQ(CHIPS)':
 'DQ23_A': CDS_PINID='DQ23_A';
NET_NAME
'M_I_CPU1_SA_DQ<24>'
 '@T6G_MB_LIB.T6G(SCH_1):M_I_CPU1_SA_DQ'<24>:
 C_SIGNAL='@t6g_mb_lib.t6g(sch_1):m_i_cpu1_sa_dq(24)';
NODE_NAME     U26 AC19
 '@T6G_MB_LIB.T6G(SCH_1):PAGE45_I159@PURE_QUANTA.GENOA_SP5(CHIPS)':
 'MIA_DATA24': CDS_PINID='MIA_DATA24';
NODE_NAME     J100 40
 '@T6G_MB_LIB.T6G(SCH_1):PAGE105_I22@PURE_QUANTA.SCONN288_DDR506112002KQ(CHIPS)':
 'DQ24_A': CDS_PINID='DQ24_A';
NET_NAME
'M_I_CPU1_SA_DQ<25>'
 '@T6G_MB_LIB.T6G(SCH_1):M_I_CPU1_SA_DQ'<25>:
 C_SIGNAL='@t6g_mb_lib.t6g(sch_1):m_i_cpu1_sa_dq(25)';
NODE_NAME     U26 AD21
 '@T6G_MB_LIB.T6G(SCH_1):PAGE45_I159@PURE_QUANTA.GENOA_SP5(CHIPS)':
 'MIA_DATA25': CDS_PINID='MIA_DATA25';
NODE_NAME     J100 42
 '@T6G_MB_LIB.T6G(SCH_1):PAGE105_I22@PURE_QUANTA.SCONN288_DDR506112002KQ(CHIPS)':
 'DQ25_A': CDS_PINID='DQ25_A';
NET_NAME
'M_I_CPU1_SA_DQ<26>'
 '@T6G_MB_LIB.T6G(SCH_1):M_I_CPU1_SA_DQ'<26>:
 C_SIGNAL='@t6g_mb_lib.t6g(sch_1):m_i_cpu1_sa_dq(26)';
NODE_NAME     U26 AD20
 '@T6G_MB_LIB.T6G(SCH_1):PAGE45_I159@PURE_QUANTA.GENOA_SP5(CHIPS)':
 'MIA_DATA26': CDS_PINID='MIA_DATA26';
NODE_NAME     J100 185
 '@T6G_MB_LIB.T6G(SCH_1):PAGE105_I22@PURE_QUANTA.SCONN288_DDR506112002KQ(CHIPS)':
 'DQ26_A': CDS_PINID='DQ26_A';
NET_NAME
'M_I_CPU1_SA_DQ<27>'
 '@T6G_MB_LIB.T6G(SCH_1):M_I_CPU1_SA_DQ'<27>:
 C_SIGNAL='@t6g_mb_lib.t6g(sch_1):m_i_cpu1_sa_dq(27)';
NODE_NAME     U26 AE21
 '@T6G_MB_LIB.T6G(SCH_1):PAGE45_I159@PURE_QUANTA.GENOA_SP5(CHIPS)':
 'MIA_DATA27': CDS_PINID='MIA_DATA27';
NODE_NAME     J100 187
 '@T6G_MB_LIB.T6G(SCH_1):PAGE105_I22@PURE_QUANTA.SCONN288_DDR506112002KQ(CHIPS)':
 'DQ27_A': CDS_PINID='DQ27_A';
NET_NAME
'M_I_CPU1_SA_DQ<28>'
 '@T6G_MB_LIB.T6G(SCH_1):M_I_CPU1_SA_DQ'<28>:
 C_SIGNAL='@t6g_mb_lib.t6g(sch_1):m_i_cpu1_sa_dq(28)';
NODE_NAME     U26 AG19
 '@T6G_MB_LIB.T6G(SCH_1):PAGE45_I159@PURE_QUANTA.GENOA_SP5(CHIPS)':
 'MIA_DATA28': CDS_PINID='MIA_DATA28';
NODE_NAME     J100 47
 '@T6G_MB_LIB.T6G(SCH_1):PAGE105_I22@PURE_QUANTA.SCONN288_DDR506112002KQ(CHIPS)':
 'DQ28_A': CDS_PINID='DQ28_A';
NET_NAME
'M_I_CPU1_SA_DQ<29>'
 '@T6G_MB_LIB.T6G(SCH_1):M_I_CPU1_SA_DQ'<29>:
 C_SIGNAL='@t6g_mb_lib.t6g(sch_1):m_i_cpu1_sa_dq(29)';
NODE_NAME     U26 AH21
 '@T6G_MB_LIB.T6G(SCH_1):PAGE45_I159@PURE_QUANTA.GENOA_SP5(CHIPS)':
 'MIA_DATA29': CDS_PINID='MIA_DATA29';
NODE_NAME     J100 49
 '@T6G_MB_LIB.T6G(SCH_1):PAGE105_I22@PURE_QUANTA.SCONN288_DDR506112002KQ(CHIPS)':
 'DQ29_A': CDS_PINID='DQ29_A';
NET_NAME
'M_I_CPU1_SA_DQ<2>'
 '@T6G_MB_LIB.T6G(SCH_1):M_I_CPU1_SA_DQ'<2>:
 C_SIGNAL='@t6g_mb_lib.t6g(sch_1):m_i_cpu1_sa_dq(2)';
NODE_NAME     U26 F20
 '@T6G_MB_LIB.T6G(SCH_1):PAGE45_I159@PURE_QUANTA.GENOA_SP5(CHIPS)':
 'MIA_DATA2': CDS_PINID='MIA_DATA2';
NODE_NAME     J100 152
 '@T6G_MB_LIB.T6G(SCH_1):PAGE105_I22@PURE_QUANTA.SCONN288_DDR506112002KQ(CHIPS)':
 'DQ2_A': CDS_PINID='DQ2_A';
NET_NAME
'M_I_CPU1_SA_DQ<30>'
 '@T6G_MB_LIB.T6G(SCH_1):M_I_CPU1_SA_DQ'<30>:
 C_SIGNAL='@t6g_mb_lib.t6g(sch_1):m_i_cpu1_sa_dq(30)';
NODE_NAME     U26 AH20
 '@T6G_MB_LIB.T6G(SCH_1):PAGE45_I159@PURE_QUANTA.GENOA_SP5(CHIPS)':
 'MIA_DATA30': CDS_PINID='MIA_DATA30';
NODE_NAME     J100 192
 '@T6G_MB_LIB.T6G(SCH_1):PAGE105_I22@PURE_QUANTA.SCONN288_DDR506112002KQ(CHIPS)':
 'DQ30_A': CDS_PINID='DQ30_A';
NET_NAME
'M_I_CPU1_SA_DQ<31>'
 '@T6G_MB_LIB.T6G(SCH_1):M_I_CPU1_SA_DQ'<31>:
 C_SIGNAL='@t6g_mb_lib.t6g(sch_1):m_i_cpu1_sa_dq(31)';
NODE_NAME     U26 AJ21
 '@T6G_MB_LIB.T6G(SCH_1):PAGE45_I159@PURE_QUANTA.GENOA_SP5(CHIPS)':
 'MIA_DATA31': CDS_PINID='MIA_DATA31';
NODE_NAME     J100 194
 '@T6G_MB_LIB.T6G(SCH_1):PAGE105_I22@PURE_QUANTA.SCONN288_DDR506112002KQ(CHIPS)':
 'DQ31_A': CDS_PINID='DQ31_A';
NET_NAME
'M_I_CPU1_SA_DQ<3>'
 '@T6G_MB_LIB.T6G(SCH_1):M_I_CPU1_SA_DQ'<3>:
 C_SIGNAL='@t6g_mb_lib.t6g(sch_1):m_i_cpu1_sa_dq(3)';
NODE_NAME     U26 G21
 '@T6G_MB_LIB.T6G(SCH_1):PAGE45_I159@PURE_QUANTA.GENOA_SP5(CHIPS)':
 'MIA_DATA3': CDS_PINID='MIA_DATA3';
NODE_NAME     J100 154
 '@T6G_MB_LIB.T6G(SCH_1):PAGE105_I22@PURE_QUANTA.SCONN288_DDR506112002KQ(CHIPS)':
 'DQ3_A': CDS_PINID='DQ3_A';
NET_NAME
'M_I_CPU1_SA_DQ<4>'
 '@T6G_MB_LIB.T6G(SCH_1):M_I_CPU1_SA_DQ'<4>:
 C_SIGNAL='@t6g_mb_lib.t6g(sch_1):m_i_cpu1_sa_dq(4)';
NODE_NAME     U26 J19
 '@T6G_MB_LIB.T6G(SCH_1):PAGE45_I159@PURE_QUANTA.GENOA_SP5(CHIPS)':
 'MIA_DATA4': CDS_PINID='MIA_DATA4';
NODE_NAME     J100 14
 '@T6G_MB_LIB.T6G(SCH_1):PAGE105_I22@PURE_QUANTA.SCONN288_DDR506112002KQ(CHIPS)':
 'DQ4_A': CDS_PINID='DQ4_A';
NET_NAME
'M_I_CPU1_SA_DQ<5>'
 '@T6G_MB_LIB.T6G(SCH_1):M_I_CPU1_SA_DQ'<5>:
 C_SIGNAL='@t6g_mb_lib.t6g(sch_1):m_i_cpu1_sa_dq(5)';
NODE_NAME     U26 K21
 '@T6G_MB_LIB.T6G(SCH_1):PAGE45_I159@PURE_QUANTA.GENOA_SP5(CHIPS)':
 'MIA_DATA5': CDS_PINID='MIA_DATA5';
NODE_NAME     J100 16
 '@T6G_MB_LIB.T6G(SCH_1):PAGE105_I22@PURE_QUANTA.SCONN288_DDR506112002KQ(CHIPS)':
 'DQ5_A': CDS_PINID='DQ5_A';
NET_NAME
'M_I_CPU1_SA_DQ<6>'
 '@T6G_MB_LIB.T6G(SCH_1):M_I_CPU1_SA_DQ'<6>:
 C_SIGNAL='@t6g_mb_lib.t6g(sch_1):m_i_cpu1_sa_dq(6)';
NODE_NAME     U26 K20
 '@T6G_MB_LIB.T6G(SCH_1):PAGE45_I159@PURE_QUANTA.GENOA_SP5(CHIPS)':
 'MIA_DATA6': CDS_PINID='MIA_DATA6';
NODE_NAME     J100 159
 '@T6G_MB_LIB.T6G(SCH_1):PAGE105_I22@PURE_QUANTA.SCONN288_DDR506112002KQ(CHIPS)':
 'DQ6_A': CDS_PINID='DQ6_A';
NET_NAME
'M_I_CPU1_SA_DQ<7>'
 '@T6G_MB_LIB.T6G(SCH_1):M_I_CPU1_SA_DQ'<7>:
 C_SIGNAL='@t6g_mb_lib.t6g(sch_1):m_i_cpu1_sa_dq(7)';
NODE_NAME     U26 L21
 '@T6G_MB_LIB.T6G(SCH_1):PAGE45_I159@PURE_QUANTA.GENOA_SP5(CHIPS)':
 'MIA_DATA7': CDS_PINID='MIA_DATA7';
NODE_NAME     J100 161
 '@T6G_MB_LIB.T6G(SCH_1):PAGE105_I22@PURE_QUANTA.SCONN288_DDR506112002KQ(CHIPS)':
 'DQ7_A': CDS_PINID='DQ7_A';
NET_NAME
'M_I_CPU1_SA_DQ<8>'
 '@T6G_MB_LIB.T6G(SCH_1):M_I_CPU1_SA_DQ'<8>:
 C_SIGNAL='@t6g_mb_lib.t6g(sch_1):m_i_cpu1_sa_dq(8)';
NODE_NAME     U26 L19
 '@T6G_MB_LIB.T6G(SCH_1):PAGE45_I159@PURE_QUANTA.GENOA_SP5(CHIPS)':
 'MIA_DATA8': CDS_PINID='MIA_DATA8';
NODE_NAME     J100 18
 '@T6G_MB_LIB.T6G(SCH_1):PAGE105_I22@PURE_QUANTA.SCONN288_DDR506112002KQ(CHIPS)':
 'DQ8_A': CDS_PINID='DQ8_A';
NET_NAME
'M_I_CPU1_SA_DQ<9>'
 '@T6G_MB_LIB.T6G(SCH_1):M_I_CPU1_SA_DQ'<9>:
 C_SIGNAL='@t6g_mb_lib.t6g(sch_1):m_i_cpu1_sa_dq(9)';
NODE_NAME     U26 M21
 '@T6G_MB_LIB.T6G(SCH_1):PAGE45_I159@PURE_QUANTA.GENOA_SP5(CHIPS)':
 'MIA_DATA9': CDS_PINID='MIA_DATA9';
NODE_NAME     J100 20
 '@T6G_MB_LIB.T6G(SCH_1):PAGE105_I22@PURE_QUANTA.SCONN288_DDR506112002KQ(CHIPS)':
 'DQ9_A': CDS_PINID='DQ9_A';
NET_NAME
'M_I_CPU1_SA_DQS_DN<0>'
 '@T6G_MB_LIB.T6G(SCH_1):M_I_CPU1_SA_DQS_DN'<0>:
 C_SIGNAL='@t6g_mb_lib.t6g(sch_1):m_i_cpu1_sa_dqs_dn(0)';
NODE_NAME     U26 H20
 '@T6G_MB_LIB.T6G(SCH_1):PAGE45_I159@PURE_QUANTA.GENOA_SP5(CHIPS)':
 'MIA_DQS_L0': CDS_PINID='MIA_DQS_L0';
NODE_NAME     J100 12
 '@T6G_MB_LIB.T6G(SCH_1):PAGE105_I236@PURE_QUANTA.SCONN288_DDR506112002KQ(CHIPS)':
 'DQS0_A_C': CDS_PINID='DQS0_A_C';
NET_NAME
'M_I_CPU1_SA_DQS_DN<1>'
 '@T6G_MB_LIB.T6G(SCH_1):M_I_CPU1_SA_DQS_DN'<1>:
 C_SIGNAL='@t6g_mb_lib.t6g(sch_1):m_i_cpu1_sa_dqs_dn(1)';
NODE_NAME     U26 P20
 '@T6G_MB_LIB.T6G(SCH_1):PAGE45_I159@PURE_QUANTA.GENOA_SP5(CHIPS)':
 'MIA_DQS_L1': CDS_PINID='MIA_DQS_L1';
NODE_NAME     J100 23
 '@T6G_MB_LIB.T6G(SCH_1):PAGE105_I236@PURE_QUANTA.SCONN288_DDR506112002KQ(CHIPS)':
 'DQS1_A_C': CDS_PINID='DQS1_A_C';
NET_NAME
'M_I_CPU1_SA_DQS_DN<2>'
 '@T6G_MB_LIB.T6G(SCH_1):M_I_CPU1_SA_DQS_DN'<2>:
 C_SIGNAL='@t6g_mb_lib.t6g(sch_1):m_i_cpu1_sa_dqs_dn(2)';
NODE_NAME     U26 Y20
 '@T6G_MB_LIB.T6G(SCH_1):PAGE45_I159@PURE_QUANTA.GENOA_SP5(CHIPS)':
 'MIA_DQS_L2': CDS_PINID='MIA_DQS_L2';
NODE_NAME     J100 34
 '@T6G_MB_LIB.T6G(SCH_1):PAGE105_I236@PURE_QUANTA.SCONN288_DDR506112002KQ(CHIPS)':
 'DQS2_A_C': CDS_PINID='DQS2_A_C';
NET_NAME
'M_I_CPU1_SA_DQS_DN<3>'
 '@T6G_MB_LIB.T6G(SCH_1):M_I_CPU1_SA_DQS_DN'<3>:
 C_SIGNAL='@t6g_mb_lib.t6g(sch_1):m_i_cpu1_sa_dqs_dn(3)';
NODE_NAME     U26 AF20
 '@T6G_MB_LIB.T6G(SCH_1):PAGE45_I159@PURE_QUANTA.GENOA_SP5(CHIPS)':
 'MIA_DQS_L3': CDS_PINID='MIA_DQS_L3';
NODE_NAME     J100 45
 '@T6G_MB_LIB.T6G(SCH_1):PAGE105_I236@PURE_QUANTA.SCONN288_DDR506112002KQ(CHIPS)':
 'DQS3_A_C': CDS_PINID='DQS3_A_C';
NET_NAME
'M_I_CPU1_SA_DQS_DN<4>'
 '@T6G_MB_LIB.T6G(SCH_1):M_I_CPU1_SA_DQS_DN'<4>:
 C_SIGNAL='@t6g_mb_lib.t6g(sch_1):m_i_cpu1_sa_dqs_dn(4)';
NODE_NAME     U26 AM20
 '@T6G_MB_LIB.T6G(SCH_1):PAGE45_I159@PURE_QUANTA.GENOA_SP5(CHIPS)':
 'MIA_DQS_L4': CDS_PINID='MIA_DQS_L4';
NODE_NAME     J100 56
 '@T6G_MB_LIB.T6G(SCH_1):PAGE105_I236@PURE_QUANTA.SCONN288_DDR506112002KQ(CHIPS)':
 'DQS4_A_C': CDS_PINID='DQS4_A_C';
NET_NAME
'M_I_CPU1_SA_DQS_DN<5>'
 '@T6G_MB_LIB.T6G(SCH_1):M_I_CPU1_SA_DQS_DN'<5>:
 C_SIGNAL='@t6g_mb_lib.t6g(sch_1):m_i_cpu1_sa_dqs_dn(5)';
NODE_NAME     U26 H21
 '@T6G_MB_LIB.T6G(SCH_1):PAGE45_I159@PURE_QUANTA.GENOA_SP5(CHIPS)':
 'MIA_DQS_L5': CDS_PINID='MIA_DQS_L5';
NODE_NAME     J100 156
 '@T6G_MB_LIB.T6G(SCH_1):PAGE105_I236@PURE_QUANTA.SCONN288_DDR506112002KQ(CHIPS)':
 'DQS5_A_C||TDQS5_A_C||DQS5_A_T||TDQS5_A_T': CDS_PINID='\dqs5_a_c||tdqs5_a_c||dqs5_a_t||tdqs5_a_t\';
NET_NAME
'M_I_CPU1_SA_DQS_DN<6>'
 '@T6G_MB_LIB.T6G(SCH_1):M_I_CPU1_SA_DQS_DN'<6>:
 C_SIGNAL='@t6g_mb_lib.t6g(sch_1):m_i_cpu1_sa_dqs_dn(6)';
NODE_NAME     U26 P21
 '@T6G_MB_LIB.T6G(SCH_1):PAGE45_I159@PURE_QUANTA.GENOA_SP5(CHIPS)':
 'MIA_DQS_L6': CDS_PINID='MIA_DQS_L6';
NODE_NAME     J100 167
 '@T6G_MB_LIB.T6G(SCH_1):PAGE105_I236@PURE_QUANTA.SCONN288_DDR506112002KQ(CHIPS)':
 'DQS6_A_C||TDQS6_A_C||DQS6_A_T||TDQS6_A_T': CDS_PINID='\dqs6_a_c||tdqs6_a_c||dqs6_a_t||tdqs6_a_t\';
NET_NAME
'M_I_CPU1_SA_DQS_DN<7>'
 '@T6G_MB_LIB.T6G(SCH_1):M_I_CPU1_SA_DQS_DN'<7>:
 C_SIGNAL='@t6g_mb_lib.t6g(sch_1):m_i_cpu1_sa_dqs_dn(7)';
NODE_NAME     U26 Y21
 '@T6G_MB_LIB.T6G(SCH_1):PAGE45_I159@PURE_QUANTA.GENOA_SP5(CHIPS)':
 'MIA_DQS_L7': CDS_PINID='MIA_DQS_L7';
NODE_NAME     J100 178
 '@T6G_MB_LIB.T6G(SCH_1):PAGE105_I236@PURE_QUANTA.SCONN288_DDR506112002KQ(CHIPS)':
 'DQS7_A_C||TDQS7_A_C': CDS_PINID='\dqs7_a_c||tdqs7_a_c\';
NET_NAME
'M_I_CPU1_SA_DQS_DN<8>'
 '@T6G_MB_LIB.T6G(SCH_1):M_I_CPU1_SA_DQS_DN'<8>:
 C_SIGNAL='@t6g_mb_lib.t6g(sch_1):m_i_cpu1_sa_dqs_dn(8)';
NODE_NAME     U26 AF21
 '@T6G_MB_LIB.T6G(SCH_1):PAGE45_I159@PURE_QUANTA.GENOA_SP5(CHIPS)':
 'MIA_DQS_L8': CDS_PINID='MIA_DQS_L8';
NODE_NAME     J100 189
 '@T6G_MB_LIB.T6G(SCH_1):PAGE105_I236@PURE_QUANTA.SCONN288_DDR506112002KQ(CHIPS)':
 'DQS8_A_C||TDQS8_A_C': CDS_PINID='\dqs8_a_c||tdqs8_a_c\';
NET_NAME
'M_I_CPU1_SA_DQS_DN<9>'
 '@T6G_MB_LIB.T6G(SCH_1):M_I_CPU1_SA_DQS_DN'<9>:
 C_SIGNAL='@t6g_mb_lib.t6g(sch_1):m_i_cpu1_sa_dqs_dn(9)';
NODE_NAME     U26 AM21
 '@T6G_MB_LIB.T6G(SCH_1):PAGE45_I159@PURE_QUANTA.GENOA_SP5(CHIPS)':
 'MIA_DQS_L9': CDS_PINID='MIA_DQS_L9';
NODE_NAME     J100 200
 '@T6G_MB_LIB.T6G(SCH_1):PAGE105_I236@PURE_QUANTA.SCONN288_DDR506112002KQ(CHIPS)':
 'DQS9_A_C||TDQS9_A_C': CDS_PINID='\dqs9_a_c||tdqs9_a_c\';
NET_NAME
'M_I_CPU1_SA_DQS_DP<0>'
 '@T6G_MB_LIB.T6G(SCH_1):M_I_CPU1_SA_DQS_DP'<0>:
 C_SIGNAL='@t6g_mb_lib.t6g(sch_1):m_i_cpu1_sa_dqs_dp(0)';
NODE_NAME     U26 G19
 '@T6G_MB_LIB.T6G(SCH_1):PAGE45_I159@PURE_QUANTA.GENOA_SP5(CHIPS)':
 'MIA_DQS_H0': CDS_PINID='MIA_DQS_H0';
NODE_NAME     J100 11
 '@T6G_MB_LIB.T6G(SCH_1):PAGE105_I236@PURE_QUANTA.SCONN288_DDR506112002KQ(CHIPS)':
 'DQS0_A_T': CDS_PINID='DQS0_A_T';
NET_NAME
'M_I_CPU1_SA_DQS_DP<1>'
 '@T6G_MB_LIB.T6G(SCH_1):M_I_CPU1_SA_DQS_DP'<1>:
 C_SIGNAL='@t6g_mb_lib.t6g(sch_1):m_i_cpu1_sa_dqs_dp(1)';
NODE_NAME     U26 N19
 '@T6G_MB_LIB.T6G(SCH_1):PAGE45_I159@PURE_QUANTA.GENOA_SP5(CHIPS)':
 'MIA_DQS_H1': CDS_PINID='MIA_DQS_H1';
NODE_NAME     J100 22
 '@T6G_MB_LIB.T6G(SCH_1):PAGE105_I236@PURE_QUANTA.SCONN288_DDR506112002KQ(CHIPS)':
 'DQS1_A_T': CDS_PINID='DQS1_A_T';
NET_NAME
'M_I_CPU1_SA_DQS_DP<2>'
 '@T6G_MB_LIB.T6G(SCH_1):M_I_CPU1_SA_DQS_DP'<2>:
 C_SIGNAL='@t6g_mb_lib.t6g(sch_1):m_i_cpu1_sa_dqs_dp(2)';
NODE_NAME     U26 W19
 '@T6G_MB_LIB.T6G(SCH_1):PAGE45_I159@PURE_QUANTA.GENOA_SP5(CHIPS)':
 'MIA_DQS_H2': CDS_PINID='MIA_DQS_H2';
NODE_NAME     J100 33
 '@T6G_MB_LIB.T6G(SCH_1):PAGE105_I236@PURE_QUANTA.SCONN288_DDR506112002KQ(CHIPS)':
 'DQS2_A_T': CDS_PINID='DQS2_A_T';
NET_NAME
'M_I_CPU1_SA_DQS_DP<3>'
 '@T6G_MB_LIB.T6G(SCH_1):M_I_CPU1_SA_DQS_DP'<3>:
 C_SIGNAL='@t6g_mb_lib.t6g(sch_1):m_i_cpu1_sa_dqs_dp(3)';
NODE_NAME     U26 AE19
 '@T6G_MB_LIB.T6G(SCH_1):PAGE45_I159@PURE_QUANTA.GENOA_SP5(CHIPS)':
 'MIA_DQS_H3': CDS_PINID='MIA_DQS_H3';
NODE_NAME     J100 44
 '@T6G_MB_LIB.T6G(SCH_1):PAGE105_I236@PURE_QUANTA.SCONN288_DDR506112002KQ(CHIPS)':
 'DQS3_A_T': CDS_PINID='DQS3_A_T';
NET_NAME
'M_I_CPU1_SA_DQS_DP<4>'
 '@T6G_MB_LIB.T6G(SCH_1):M_I_CPU1_SA_DQS_DP'<4>:
 C_SIGNAL='@t6g_mb_lib.t6g(sch_1):m_i_cpu1_sa_dqs_dp(4)';
NODE_NAME     U26 AL19
 '@T6G_MB_LIB.T6G(SCH_1):PAGE45_I159@PURE_QUANTA.GENOA_SP5(CHIPS)':
 'MIA_DQS_H4': CDS_PINID='MIA_DQS_H4';
NODE_NAME     J100 55
 '@T6G_MB_LIB.T6G(SCH_1):PAGE105_I236@PURE_QUANTA.SCONN288_DDR506112002KQ(CHIPS)':
 'DQS4_A_T': CDS_PINID='DQS4_A_T';
NET_NAME
'M_I_CPU1_SA_DQS_DP<5>'
 '@T6G_MB_LIB.T6G(SCH_1):M_I_CPU1_SA_DQS_DP'<5>:
 C_SIGNAL='@t6g_mb_lib.t6g(sch_1):m_i_cpu1_sa_dqs_dp(5)';
NODE_NAME     U26 J21
 '@T6G_MB_LIB.T6G(SCH_1):PAGE45_I159@PURE_QUANTA.GENOA_SP5(CHIPS)':
 'MIA_DQS_H5': CDS_PINID='MIA_DQS_H5';
NODE_NAME     J100 157
 '@T6G_MB_LIB.T6G(SCH_1):PAGE105_I236@PURE_QUANTA.SCONN288_DDR506112002KQ(CHIPS)':
 'DQS5_A_T||TDQS5_A_T': CDS_PINID='\dqs5_a_t||tdqs5_a_t\';
NET_NAME
'M_I_CPU1_SA_DQS_DP<6>'
 '@T6G_MB_LIB.T6G(SCH_1):M_I_CPU1_SA_DQS_DP'<6>:
 C_SIGNAL='@t6g_mb_lib.t6g(sch_1):m_i_cpu1_sa_dqs_dp(6)';
NODE_NAME     U26 R21
 '@T6G_MB_LIB.T6G(SCH_1):PAGE45_I159@PURE_QUANTA.GENOA_SP5(CHIPS)':
 'MIA_DQS_H6': CDS_PINID='MIA_DQS_H6';
NODE_NAME     J100 168
 '@T6G_MB_LIB.T6G(SCH_1):PAGE105_I236@PURE_QUANTA.SCONN288_DDR506112002KQ(CHIPS)':
 'DQS6_A_T||TDQS6_A_T': CDS_PINID='\dqs6_a_t||tdqs6_a_t\';
NET_NAME
'M_I_CPU1_SA_DQS_DP<7>'
 '@T6G_MB_LIB.T6G(SCH_1):M_I_CPU1_SA_DQS_DP'<7>:
 C_SIGNAL='@t6g_mb_lib.t6g(sch_1):m_i_cpu1_sa_dqs_dp(7)';
NODE_NAME     U26 AA21
 '@T6G_MB_LIB.T6G(SCH_1):PAGE45_I159@PURE_QUANTA.GENOA_SP5(CHIPS)':
 'MIA_DQS_H7': CDS_PINID='MIA_DQS_H7';
NODE_NAME     J100 179
 '@T6G_MB_LIB.T6G(SCH_1):PAGE105_I236@PURE_QUANTA.SCONN288_DDR506112002KQ(CHIPS)':
 'DQS7_A_T||TDQS7_A_T': CDS_PINID='\dqs7_a_t||tdqs7_a_t\';
NET_NAME
'M_I_CPU1_SA_DQS_DP<8>'
 '@T6G_MB_LIB.T6G(SCH_1):M_I_CPU1_SA_DQS_DP'<8>:
 C_SIGNAL='@t6g_mb_lib.t6g(sch_1):m_i_cpu1_sa_dqs_dp(8)';
NODE_NAME     U26 AG21
 '@T6G_MB_LIB.T6G(SCH_1):PAGE45_I159@PURE_QUANTA.GENOA_SP5(CHIPS)':
 'MIA_DQS_H8': CDS_PINID='MIA_DQS_H8';
NODE_NAME     J100 190
 '@T6G_MB_LIB.T6G(SCH_1):PAGE105_I236@PURE_QUANTA.SCONN288_DDR506112002KQ(CHIPS)':
 'DQS8_A_T||TDQS8_A_T': CDS_PINID='\dqs8_a_t||tdqs8_a_t\';
NET_NAME
'M_I_CPU1_SA_DQS_DP<9>'
 '@T6G_MB_LIB.T6G(SCH_1):M_I_CPU1_SA_DQS_DP'<9>:
 C_SIGNAL='@t6g_mb_lib.t6g(sch_1):m_i_cpu1_sa_dqs_dp(9)';
NODE_NAME     U26 AN21
 '@T6G_MB_LIB.T6G(SCH_1):PAGE45_I159@PURE_QUANTA.GENOA_SP5(CHIPS)':
 'MIA_DQS_H9': CDS_PINID='MIA_DQS_H9';
NODE_NAME     J100 201
 '@T6G_MB_LIB.T6G(SCH_1):PAGE105_I236@PURE_QUANTA.SCONN288_DDR506112002KQ(CHIPS)':
 'DQS9_A_T||TDQS9_A_T': CDS_PINID='\dqs9_a_t||tdqs9_a_t\';
NET_NAME
'M_I_CPU1_SA_PAR'
 '@T6G_MB_LIB.T6G(SCH_1):M_I_CPU1_SA_PAR':
 C_SIGNAL='@t6g_mb_lib.t6g(sch_1):m_i_cpu1_sa_par';
NODE_NAME     U26 BC21
 '@T6G_MB_LIB.T6G(SCH_1):PAGE45_I159@PURE_QUANTA.GENOA_SP5(CHIPS)':
 'MIA_PAR': CDS_PINID='MIA_PAR';
NODE_NAME     J100 74
 '@T6G_MB_LIB.T6G(SCH_1):PAGE105_I22@PURE_QUANTA.SCONN288_DDR506112002KQ(CHIPS)':
 'PAR_A': CDS_PINID='PAR_A';
NET_NAME
'M_I_CPU1_SA_RSP<0>'
 '@T6G_MB_LIB.T6G(SCH_1):M_I_CPU1_SA_RSP'<0>:
 C_SIGNAL='@t6g_mb_lib.t6g(sch_1):m_i_cpu1_sa_rsp(0)';
NODE_NAME     U26 BN21
 '@T6G_MB_LIB.T6G(SCH_1):PAGE45_I159@PURE_QUANTA.GENOA_SP5(CHIPS)':
 'MIA0_RSP_L': CDS_PINID='MIA0_RSP_L';
NODE_NAME     J100 86
 '@T6G_MB_LIB.T6G(SCH_1):PAGE105_I22@PURE_QUANTA.SCONN288_DDR506112002KQ(CHIPS)':
 'LBD||RSP_A_N': CDS_PINID='\lbd||rsp_a_n\';
NET_NAME
'M_I_CPU1_SB_CA<0>'
 '@T6G_MB_LIB.T6G(SCH_1):M_I_CPU1_SB_CA'<0>:
 C_SIGNAL='@t6g_mb_lib.t6g(sch_1):m_i_cpu1_sb_ca(0)';
NODE_NAME     U26 BG21
 '@T6G_MB_LIB.T6G(SCH_1):PAGE45_I159@PURE_QUANTA.GENOA_SP5(CHIPS)':
 'MIB_CA0': CDS_PINID='MIB_CA0';
NODE_NAME     J100 76
 '@T6G_MB_LIB.T6G(SCH_1):PAGE105_I22@PURE_QUANTA.SCONN288_DDR506112002KQ(CHIPS)':
 'CA0_B': CDS_PINID='CA0_B';
NET_NAME
'M_I_CPU1_SB_CA<1>'
 '@T6G_MB_LIB.T6G(SCH_1):M_I_CPU1_SB_CA'<1>:
 C_SIGNAL='@t6g_mb_lib.t6g(sch_1):m_i_cpu1_sb_ca(1)';
NODE_NAME     U26 BH21
 '@T6G_MB_LIB.T6G(SCH_1):PAGE45_I159@PURE_QUANTA.GENOA_SP5(CHIPS)':
 'MIB_CA1': CDS_PINID='MIB_CA1';
NODE_NAME     J100 221
 '@T6G_MB_LIB.T6G(SCH_1):PAGE105_I22@PURE_QUANTA.SCONN288_DDR506112002KQ(CHIPS)':
 'CA1_B': CDS_PINID='CA1_B';
NET_NAME
'M_I_CPU1_SB_CA<2>'
 '@T6G_MB_LIB.T6G(SCH_1):M_I_CPU1_SB_CA'<2>:
 C_SIGNAL='@t6g_mb_lib.t6g(sch_1):m_i_cpu1_sb_ca(2)';
NODE_NAME     U26 BH20
 '@T6G_MB_LIB.T6G(SCH_1):PAGE45_I159@PURE_QUANTA.GENOA_SP5(CHIPS)':
 'MIB_CA2': CDS_PINID='MIB_CA2';
NODE_NAME     J100 78
 '@T6G_MB_LIB.T6G(SCH_1):PAGE105_I22@PURE_QUANTA.SCONN288_DDR506112002KQ(CHIPS)':
 'CA2_B': CDS_PINID='CA2_B';
NET_NAME
'M_I_CPU1_SB_CA<3>'
 '@T6G_MB_LIB.T6G(SCH_1):M_I_CPU1_SB_CA'<3>:
 C_SIGNAL='@t6g_mb_lib.t6g(sch_1):m_i_cpu1_sb_ca(3)';
NODE_NAME     U26 BJ19
 '@T6G_MB_LIB.T6G(SCH_1):PAGE45_I159@PURE_QUANTA.GENOA_SP5(CHIPS)':
 'MIB_CA3': CDS_PINID='MIB_CA3';
NODE_NAME     J100 223
 '@T6G_MB_LIB.T6G(SCH_1):PAGE105_I22@PURE_QUANTA.SCONN288_DDR506112002KQ(CHIPS)':
 'CA3_B': CDS_PINID='CA3_B';
NET_NAME
'M_I_CPU1_SB_CA<4>'
 '@T6G_MB_LIB.T6G(SCH_1):M_I_CPU1_SB_CA'<4>:
 C_SIGNAL='@t6g_mb_lib.t6g(sch_1):m_i_cpu1_sb_ca(4)';
NODE_NAME     U26 BJ21
 '@T6G_MB_LIB.T6G(SCH_1):PAGE45_I159@PURE_QUANTA.GENOA_SP5(CHIPS)':
 'MIB_CA4': CDS_PINID='MIB_CA4';
NODE_NAME     J100 80
 '@T6G_MB_LIB.T6G(SCH_1):PAGE105_I22@PURE_QUANTA.SCONN288_DDR506112002KQ(CHIPS)':
 'CA4_B': CDS_PINID='CA4_B';
NET_NAME
'M_I_CPU1_SB_CA<5>'
 '@T6G_MB_LIB.T6G(SCH_1):M_I_CPU1_SB_CA'<5>:
 C_SIGNAL='@t6g_mb_lib.t6g(sch_1):m_i_cpu1_sb_ca(5)';
NODE_NAME     U26 BK21
 '@T6G_MB_LIB.T6G(SCH_1):PAGE45_I159@PURE_QUANTA.GENOA_SP5(CHIPS)':
 'MIB_CA5': CDS_PINID='MIB_CA5';
NODE_NAME     J100 225
 '@T6G_MB_LIB.T6G(SCH_1):PAGE105_I22@PURE_QUANTA.SCONN288_DDR506112002KQ(CHIPS)':
 'CA5_B': CDS_PINID='CA5_B';
NET_NAME
'M_I_CPU1_SB_CA<6>'
 '@T6G_MB_LIB.T6G(SCH_1):M_I_CPU1_SB_CA'<6>:
 C_SIGNAL='@t6g_mb_lib.t6g(sch_1):m_i_cpu1_sb_ca(6)';
NODE_NAME     U26 BK20
 '@T6G_MB_LIB.T6G(SCH_1):PAGE45_I159@PURE_QUANTA.GENOA_SP5(CHIPS)':
 'MIB_CA6': CDS_PINID='MIB_CA6';
NODE_NAME     J100 82
 '@T6G_MB_LIB.T6G(SCH_1):PAGE105_I22@PURE_QUANTA.SCONN288_DDR506112002KQ(CHIPS)':
 'CA6_B': CDS_PINID='CA6_B';
NET_NAME
'M_I_CPU1_SB_CB<0>'
 '@T6G_MB_LIB.T6G(SCH_1):M_I_CPU1_SB_CB'<0>:
 C_SIGNAL='@t6g_mb_lib.t6g(sch_1):m_i_cpu1_sb_cb(0)';
NODE_NAME     U26 BY20
 '@T6G_MB_LIB.T6G(SCH_1):PAGE45_I159@PURE_QUANTA.GENOA_SP5(CHIPS)':
 'MIB_CHECK0': CDS_PINID='MIB_CHECK0';
NODE_NAME     J100 96
 '@T6G_MB_LIB.T6G(SCH_1):PAGE105_I22@PURE_QUANTA.SCONN288_DDR506112002KQ(CHIPS)':
 'CB0_B': CDS_PINID='CB0_B';
NET_NAME
'M_I_CPU1_SB_CB<1>'
 '@T6G_MB_LIB.T6G(SCH_1):M_I_CPU1_SB_CB'<1>:
 C_SIGNAL='@t6g_mb_lib.t6g(sch_1):m_i_cpu1_sb_cb(1)';
NODE_NAME     U26 CA21
 '@T6G_MB_LIB.T6G(SCH_1):PAGE45_I159@PURE_QUANTA.GENOA_SP5(CHIPS)':
 'MIB_CHECK1': CDS_PINID='MIB_CHECK1';
NODE_NAME     J100 98
 '@T6G_MB_LIB.T6G(SCH_1):PAGE105_I22@PURE_QUANTA.SCONN288_DDR506112002KQ(CHIPS)':
 'CB1_B': CDS_PINID='CB1_B';
NET_NAME
'M_I_CPU1_SB_CB<2>'
 '@T6G_MB_LIB.T6G(SCH_1):M_I_CPU1_SB_CB'<2>:
 C_SIGNAL='@t6g_mb_lib.t6g(sch_1):m_i_cpu1_sb_cb(2)';
NODE_NAME     U26 CA19
 '@T6G_MB_LIB.T6G(SCH_1):PAGE45_I159@PURE_QUANTA.GENOA_SP5(CHIPS)':
 'MIB_CHECK2': CDS_PINID='MIB_CHECK2';
NODE_NAME     J100 241
 '@T6G_MB_LIB.T6G(SCH_1):PAGE105_I22@PURE_QUANTA.SCONN288_DDR506112002KQ(CHIPS)':
 'CB2_B': CDS_PINID='CB2_B';
NET_NAME
'M_I_CPU1_SB_CB<3>'
 '@T6G_MB_LIB.T6G(SCH_1):M_I_CPU1_SB_CB'<3>:
 C_SIGNAL='@t6g_mb_lib.t6g(sch_1):m_i_cpu1_sb_cb(3)';
NODE_NAME     U26 CB21
 '@T6G_MB_LIB.T6G(SCH_1):PAGE45_I159@PURE_QUANTA.GENOA_SP5(CHIPS)':
 'MIB_CHECK3': CDS_PINID='MIB_CHECK3';
NODE_NAME     J100 243
 '@T6G_MB_LIB.T6G(SCH_1):PAGE105_I22@PURE_QUANTA.SCONN288_DDR506112002KQ(CHIPS)':
 'CB3_B': CDS_PINID='CB3_B';
NET_NAME
'M_I_CPU1_SB_CB<4>'
 '@T6G_MB_LIB.T6G(SCH_1):M_I_CPU1_SB_CB'<4>:
 C_SIGNAL='@t6g_mb_lib.t6g(sch_1):m_i_cpu1_sb_cb(4)';
NODE_NAME     U26 BT20
 '@T6G_MB_LIB.T6G(SCH_1):PAGE45_I159@PURE_QUANTA.GENOA_SP5(CHIPS)':
 'MIB_CHECK4': CDS_PINID='MIB_CHECK4';
NODE_NAME     J100 89
 '@T6G_MB_LIB.T6G(SCH_1):PAGE105_I22@PURE_QUANTA.SCONN288_DDR506112002KQ(CHIPS)':
 'CB4_B': CDS_PINID='CB4_B';
NET_NAME
'M_I_CPU1_SB_CB<5>'
 '@T6G_MB_LIB.T6G(SCH_1):M_I_CPU1_SB_CB'<5>:
 C_SIGNAL='@t6g_mb_lib.t6g(sch_1):m_i_cpu1_sb_cb(5)';
NODE_NAME     U26 BU21
 '@T6G_MB_LIB.T6G(SCH_1):PAGE45_I159@PURE_QUANTA.GENOA_SP5(CHIPS)':
 'MIB_CHECK5': CDS_PINID='MIB_CHECK5';
NODE_NAME     J100 91
 '@T6G_MB_LIB.T6G(SCH_1):PAGE105_I22@PURE_QUANTA.SCONN288_DDR506112002KQ(CHIPS)':
 'CB5_B': CDS_PINID='CB5_B';
NET_NAME
'M_I_CPU1_SB_CB<6>'
 '@T6G_MB_LIB.T6G(SCH_1):M_I_CPU1_SB_CB'<6>:
 C_SIGNAL='@t6g_mb_lib.t6g(sch_1):m_i_cpu1_sb_cb(6)';
NODE_NAME     U26 BU19
 '@T6G_MB_LIB.T6G(SCH_1):PAGE45_I159@PURE_QUANTA.GENOA_SP5(CHIPS)':
 'MIB_CHECK6': CDS_PINID='MIB_CHECK6';
NODE_NAME     J100 234
 '@T6G_MB_LIB.T6G(SCH_1):PAGE105_I22@PURE_QUANTA.SCONN288_DDR506112002KQ(CHIPS)':
 'CB6_B': CDS_PINID='CB6_B';
NET_NAME
'M_I_CPU1_SB_CB<7>'
 '@T6G_MB_LIB.T6G(SCH_1):M_I_CPU1_SB_CB'<7>:
 C_SIGNAL='@t6g_mb_lib.t6g(sch_1):m_i_cpu1_sb_cb(7)';
NODE_NAME     U26 BV21
 '@T6G_MB_LIB.T6G(SCH_1):PAGE45_I159@PURE_QUANTA.GENOA_SP5(CHIPS)':
 'MIB_CHECK7': CDS_PINID='MIB_CHECK7';
NODE_NAME     J100 236
 '@T6G_MB_LIB.T6G(SCH_1):PAGE105_I22@PURE_QUANTA.SCONN288_DDR506112002KQ(CHIPS)':
 'CB7_B': CDS_PINID='CB7_B';
NET_NAME
'M_I_CPU1_SB_CS_N<0>'
 '@T6G_MB_LIB.T6G(SCH_1):M_I_CPU1_SB_CS_N'<0>:
 C_SIGNAL='@t6g_mb_lib.t6g(sch_1):m_i_cpu1_sb_cs_n(0)';
NODE_NAME     U26 BM21
 '@T6G_MB_LIB.T6G(SCH_1):PAGE45_I159@PURE_QUANTA.GENOA_SP5(CHIPS)':
 'MIB0_CS_L0': CDS_PINID='MIB0_CS_L0';
NODE_NAME     J100 84
 '@T6G_MB_LIB.T6G(SCH_1):PAGE105_I22@PURE_QUANTA.SCONN288_DDR506112002KQ(CHIPS)':
 'CS0_B_N': CDS_PINID='CS0_B_N';
NET_NAME
'M_I_CPU1_SB_CS_N<1>'
 '@T6G_MB_LIB.T6G(SCH_1):M_I_CPU1_SB_CS_N'<1>:
 C_SIGNAL='@t6g_mb_lib.t6g(sch_1):m_i_cpu1_sb_cs_n(1)';
NODE_NAME     U26 BN19
 '@T6G_MB_LIB.T6G(SCH_1):PAGE45_I159@PURE_QUANTA.GENOA_SP5(CHIPS)':
 'MIB0_CS_L1': CDS_PINID='MIB0_CS_L1';
NODE_NAME     J100 229
 '@T6G_MB_LIB.T6G(SCH_1):PAGE105_I22@PURE_QUANTA.SCONN288_DDR506112002KQ(CHIPS)':
 'CS1_B_N': CDS_PINID='CS1_B_N';
NET_NAME
'M_I_CPU1_SB_DQ<0>'
 '@T6G_MB_LIB.T6G(SCH_1):M_I_CPU1_SB_DQ'<0>:
 C_SIGNAL='@t6g_mb_lib.t6g(sch_1):m_i_cpu1_sb_dq(0)';
NODE_NAME     U26 CB20
 '@T6G_MB_LIB.T6G(SCH_1):PAGE45_I159@PURE_QUANTA.GENOA_SP5(CHIPS)':
 'MIB_DATA0': CDS_PINID='MIB_DATA0';
NODE_NAME     J100 100
 '@T6G_MB_LIB.T6G(SCH_1):PAGE105_I22@PURE_QUANTA.SCONN288_DDR506112002KQ(CHIPS)':
 'DQ0_B': CDS_PINID='DQ0_B';
NET_NAME
'M_I_CPU1_SB_DQ<10>'
 '@T6G_MB_LIB.T6G(SCH_1):M_I_CPU1_SB_DQ'<10>:
 C_SIGNAL='@t6g_mb_lib.t6g(sch_1):m_i_cpu1_sb_dq(10)';
NODE_NAME     U26 CJ19
 '@T6G_MB_LIB.T6G(SCH_1):PAGE45_I159@PURE_QUANTA.GENOA_SP5(CHIPS)':
 'MIB_DATA10': CDS_PINID='MIB_DATA10';
NODE_NAME     J100 256
 '@T6G_MB_LIB.T6G(SCH_1):PAGE105_I22@PURE_QUANTA.SCONN288_DDR506112002KQ(CHIPS)':
 'DQ10_B': CDS_PINID='DQ10_B';
NET_NAME
'M_I_CPU1_SB_DQ<11>'
 '@T6G_MB_LIB.T6G(SCH_1):M_I_CPU1_SB_DQ'<11>:
 C_SIGNAL='@t6g_mb_lib.t6g(sch_1):m_i_cpu1_sb_dq(11)';
NODE_NAME     U26 CK21
 '@T6G_MB_LIB.T6G(SCH_1):PAGE45_I159@PURE_QUANTA.GENOA_SP5(CHIPS)':
 'MIB_DATA11': CDS_PINID='MIB_DATA11';
NODE_NAME     J100 258
 '@T6G_MB_LIB.T6G(SCH_1):PAGE105_I22@PURE_QUANTA.SCONN288_DDR506112002KQ(CHIPS)':
 'DQ11_B': CDS_PINID='DQ11_B';
NET_NAME
'M_I_CPU1_SB_DQ<12>'
 '@T6G_MB_LIB.T6G(SCH_1):M_I_CPU1_SB_DQ'<12>:
 C_SIGNAL='@t6g_mb_lib.t6g(sch_1):m_i_cpu1_sb_dq(12)';
NODE_NAME     U26 CM20
 '@T6G_MB_LIB.T6G(SCH_1):PAGE45_I159@PURE_QUANTA.GENOA_SP5(CHIPS)':
 'MIB_DATA12': CDS_PINID='MIB_DATA12';
NODE_NAME     J100 118
 '@T6G_MB_LIB.T6G(SCH_1):PAGE105_I22@PURE_QUANTA.SCONN288_DDR506112002KQ(CHIPS)':
 'DQ12_B': CDS_PINID='DQ12_B';
NET_NAME
'M_I_CPU1_SB_DQ<13>'
 '@T6G_MB_LIB.T6G(SCH_1):M_I_CPU1_SB_DQ'<13>:
 C_SIGNAL='@t6g_mb_lib.t6g(sch_1):m_i_cpu1_sb_dq(13)';
NODE_NAME     U26 CN21
 '@T6G_MB_LIB.T6G(SCH_1):PAGE45_I159@PURE_QUANTA.GENOA_SP5(CHIPS)':
 'MIB_DATA13': CDS_PINID='MIB_DATA13';
NODE_NAME     J100 120
 '@T6G_MB_LIB.T6G(SCH_1):PAGE105_I22@PURE_QUANTA.SCONN288_DDR506112002KQ(CHIPS)':
 'DQ13_B': CDS_PINID='DQ13_B';
NET_NAME
'M_I_CPU1_SB_DQ<14>'
 '@T6G_MB_LIB.T6G(SCH_1):M_I_CPU1_SB_DQ'<14>:
 C_SIGNAL='@t6g_mb_lib.t6g(sch_1):m_i_cpu1_sb_dq(14)';
NODE_NAME     U26 CN19
 '@T6G_MB_LIB.T6G(SCH_1):PAGE45_I159@PURE_QUANTA.GENOA_SP5(CHIPS)':
 'MIB_DATA14': CDS_PINID='MIB_DATA14';
NODE_NAME     J100 263
 '@T6G_MB_LIB.T6G(SCH_1):PAGE105_I22@PURE_QUANTA.SCONN288_DDR506112002KQ(CHIPS)':
 'DQ14_B': CDS_PINID='DQ14_B';
NET_NAME
'M_I_CPU1_SB_DQ<15>'
 '@T6G_MB_LIB.T6G(SCH_1):M_I_CPU1_SB_DQ'<15>:
 C_SIGNAL='@t6g_mb_lib.t6g(sch_1):m_i_cpu1_sb_dq(15)';
NODE_NAME     U26 CP21
 '@T6G_MB_LIB.T6G(SCH_1):PAGE45_I159@PURE_QUANTA.GENOA_SP5(CHIPS)':
 'MIB_DATA15': CDS_PINID='MIB_DATA15';
NODE_NAME     J100 265
 '@T6G_MB_LIB.T6G(SCH_1):PAGE105_I22@PURE_QUANTA.SCONN288_DDR506112002KQ(CHIPS)':
 'DQ15_B': CDS_PINID='DQ15_B';
NET_NAME
'M_I_CPU1_SB_DQ<16>'
 '@T6G_MB_LIB.T6G(SCH_1):M_I_CPU1_SB_DQ'<16>:
 C_SIGNAL='@t6g_mb_lib.t6g(sch_1):m_i_cpu1_sb_dq(16)';
NODE_NAME     U26 CP20
 '@T6G_MB_LIB.T6G(SCH_1):PAGE45_I159@PURE_QUANTA.GENOA_SP5(CHIPS)':
 'MIB_DATA16': CDS_PINID='MIB_DATA16';
NODE_NAME     J100 122
 '@T6G_MB_LIB.T6G(SCH_1):PAGE105_I22@PURE_QUANTA.SCONN288_DDR506112002KQ(CHIPS)':
 'DQ16_B': CDS_PINID='DQ16_B';
NET_NAME
'M_I_CPU1_SB_DQ<17>'
 '@T6G_MB_LIB.T6G(SCH_1):M_I_CPU1_SB_DQ'<17>:
 C_SIGNAL='@t6g_mb_lib.t6g(sch_1):m_i_cpu1_sb_dq(17)';
NODE_NAME     U26 CR21
 '@T6G_MB_LIB.T6G(SCH_1):PAGE45_I159@PURE_QUANTA.GENOA_SP5(CHIPS)':
 'MIB_DATA17': CDS_PINID='MIB_DATA17';
NODE_NAME     J100 124
 '@T6G_MB_LIB.T6G(SCH_1):PAGE105_I22@PURE_QUANTA.SCONN288_DDR506112002KQ(CHIPS)':
 'DQ17_B': CDS_PINID='DQ17_B';
NET_NAME
'M_I_CPU1_SB_DQ<18>'
 '@T6G_MB_LIB.T6G(SCH_1):M_I_CPU1_SB_DQ'<18>:
 C_SIGNAL='@t6g_mb_lib.t6g(sch_1):m_i_cpu1_sb_dq(18)';
NODE_NAME     U26 CR19
 '@T6G_MB_LIB.T6G(SCH_1):PAGE45_I159@PURE_QUANTA.GENOA_SP5(CHIPS)':
 'MIB_DATA18': CDS_PINID='MIB_DATA18';
NODE_NAME     J100 267
 '@T6G_MB_LIB.T6G(SCH_1):PAGE105_I22@PURE_QUANTA.SCONN288_DDR506112002KQ(CHIPS)':
 'DQ18_B': CDS_PINID='DQ18_B';
NET_NAME
'M_I_CPU1_SB_DQ<19>'
 '@T6G_MB_LIB.T6G(SCH_1):M_I_CPU1_SB_DQ'<19>:
 C_SIGNAL='@t6g_mb_lib.t6g(sch_1):m_i_cpu1_sb_dq(19)';
NODE_NAME     U26 CT21
 '@T6G_MB_LIB.T6G(SCH_1):PAGE45_I159@PURE_QUANTA.GENOA_SP5(CHIPS)':
 'MIB_DATA19': CDS_PINID='MIB_DATA19';
NODE_NAME     J100 269
 '@T6G_MB_LIB.T6G(SCH_1):PAGE105_I22@PURE_QUANTA.SCONN288_DDR506112002KQ(CHIPS)':
 'DQ19_B': CDS_PINID='DQ19_B';
NET_NAME
'M_I_CPU1_SB_DQ<1>'
 '@T6G_MB_LIB.T6G(SCH_1):M_I_CPU1_SB_DQ'<1>:
 C_SIGNAL='@t6g_mb_lib.t6g(sch_1):m_i_cpu1_sb_dq(1)';
NODE_NAME     U26 CC21
 '@T6G_MB_LIB.T6G(SCH_1):PAGE45_I159@PURE_QUANTA.GENOA_SP5(CHIPS)':
 'MIB_DATA1': CDS_PINID='MIB_DATA1';
NODE_NAME     J100 102
 '@T6G_MB_LIB.T6G(SCH_1):PAGE105_I22@PURE_QUANTA.SCONN288_DDR506112002KQ(CHIPS)':
 'DQ1_B': CDS_PINID='DQ1_B';
NET_NAME
'M_I_CPU1_SB_DQ<20>'
 '@T6G_MB_LIB.T6G(SCH_1):M_I_CPU1_SB_DQ'<20>:
 C_SIGNAL='@t6g_mb_lib.t6g(sch_1):m_i_cpu1_sb_dq(20)';
NODE_NAME     U26 CV20
 '@T6G_MB_LIB.T6G(SCH_1):PAGE45_I159@PURE_QUANTA.GENOA_SP5(CHIPS)':
 'MIB_DATA20': CDS_PINID='MIB_DATA20';
NODE_NAME     J100 129
 '@T6G_MB_LIB.T6G(SCH_1):PAGE105_I22@PURE_QUANTA.SCONN288_DDR506112002KQ(CHIPS)':
 'DQ20_B': CDS_PINID='DQ20_B';
NET_NAME
'M_I_CPU1_SB_DQ<21>'
 '@T6G_MB_LIB.T6G(SCH_1):M_I_CPU1_SB_DQ'<21>:
 C_SIGNAL='@t6g_mb_lib.t6g(sch_1):m_i_cpu1_sb_dq(21)';
NODE_NAME     U26 CW21
 '@T6G_MB_LIB.T6G(SCH_1):PAGE45_I159@PURE_QUANTA.GENOA_SP5(CHIPS)':
 'MIB_DATA21': CDS_PINID='MIB_DATA21';
NODE_NAME     J100 131
 '@T6G_MB_LIB.T6G(SCH_1):PAGE105_I22@PURE_QUANTA.SCONN288_DDR506112002KQ(CHIPS)':
 'DQ21_B': CDS_PINID='DQ21_B';
NET_NAME
'M_I_CPU1_SB_DQ<22>'
 '@T6G_MB_LIB.T6G(SCH_1):M_I_CPU1_SB_DQ'<22>:
 C_SIGNAL='@t6g_mb_lib.t6g(sch_1):m_i_cpu1_sb_dq(22)';
NODE_NAME     U26 CW19
 '@T6G_MB_LIB.T6G(SCH_1):PAGE45_I159@PURE_QUANTA.GENOA_SP5(CHIPS)':
 'MIB_DATA22': CDS_PINID='MIB_DATA22';
NODE_NAME     J100 274
 '@T6G_MB_LIB.T6G(SCH_1):PAGE105_I22@PURE_QUANTA.SCONN288_DDR506112002KQ(CHIPS)':
 'DQ22_B': CDS_PINID='DQ22_B';
NET_NAME
'M_I_CPU1_SB_DQ<23>'
 '@T6G_MB_LIB.T6G(SCH_1):M_I_CPU1_SB_DQ'<23>:
 C_SIGNAL='@t6g_mb_lib.t6g(sch_1):m_i_cpu1_sb_dq(23)';
NODE_NAME     U26 CY21
 '@T6G_MB_LIB.T6G(SCH_1):PAGE45_I159@PURE_QUANTA.GENOA_SP5(CHIPS)':
 'MIB_DATA23': CDS_PINID='MIB_DATA23';
NODE_NAME     J100 276
 '@T6G_MB_LIB.T6G(SCH_1):PAGE105_I22@PURE_QUANTA.SCONN288_DDR506112002KQ(CHIPS)':
 'DQ23_B': CDS_PINID='DQ23_B';
NET_NAME
'M_I_CPU1_SB_DQ<24>'
 '@T6G_MB_LIB.T6G(SCH_1):M_I_CPU1_SB_DQ'<24>:
 C_SIGNAL='@t6g_mb_lib.t6g(sch_1):m_i_cpu1_sb_dq(24)';
NODE_NAME     U26 CY20
 '@T6G_MB_LIB.T6G(SCH_1):PAGE45_I159@PURE_QUANTA.GENOA_SP5(CHIPS)':
 'MIB_DATA24': CDS_PINID='MIB_DATA24';
NODE_NAME     J100 133
 '@T6G_MB_LIB.T6G(SCH_1):PAGE105_I22@PURE_QUANTA.SCONN288_DDR506112002KQ(CHIPS)':
 'DQ24_B': CDS_PINID='DQ24_B';
NET_NAME
'M_I_CPU1_SB_DQ<25>'
 '@T6G_MB_LIB.T6G(SCH_1):M_I_CPU1_SB_DQ'<25>:
 C_SIGNAL='@t6g_mb_lib.t6g(sch_1):m_i_cpu1_sb_dq(25)';
NODE_NAME     U26 DA21
 '@T6G_MB_LIB.T6G(SCH_1):PAGE45_I159@PURE_QUANTA.GENOA_SP5(CHIPS)':
 'MIB_DATA25': CDS_PINID='MIB_DATA25';
NODE_NAME     J100 135
 '@T6G_MB_LIB.T6G(SCH_1):PAGE105_I22@PURE_QUANTA.SCONN288_DDR506112002KQ(CHIPS)':
 'DQ25_B': CDS_PINID='DQ25_B';
NET_NAME
'M_I_CPU1_SB_DQ<26>'
 '@T6G_MB_LIB.T6G(SCH_1):M_I_CPU1_SB_DQ'<26>:
 C_SIGNAL='@t6g_mb_lib.t6g(sch_1):m_i_cpu1_sb_dq(26)';
NODE_NAME     U26 DA19
 '@T6G_MB_LIB.T6G(SCH_1):PAGE45_I159@PURE_QUANTA.GENOA_SP5(CHIPS)':
 'MIB_DATA26': CDS_PINID='MIB_DATA26';
NODE_NAME     J100 278
 '@T6G_MB_LIB.T6G(SCH_1):PAGE105_I22@PURE_QUANTA.SCONN288_DDR506112002KQ(CHIPS)':
 'DQ26_B': CDS_PINID='DQ26_B';
NET_NAME
'M_I_CPU1_SB_DQ<27>'
 '@T6G_MB_LIB.T6G(SCH_1):M_I_CPU1_SB_DQ'<27>:
 C_SIGNAL='@t6g_mb_lib.t6g(sch_1):m_i_cpu1_sb_dq(27)';
NODE_NAME     U26 DB21
 '@T6G_MB_LIB.T6G(SCH_1):PAGE45_I159@PURE_QUANTA.GENOA_SP5(CHIPS)':
 'MIB_DATA27': CDS_PINID='MIB_DATA27';
NODE_NAME     J100 280
 '@T6G_MB_LIB.T6G(SCH_1):PAGE105_I22@PURE_QUANTA.SCONN288_DDR506112002KQ(CHIPS)':
 'DQ27_B': CDS_PINID='DQ27_B';
NET_NAME
'M_I_CPU1_SB_DQ<28>'
 '@T6G_MB_LIB.T6G(SCH_1):M_I_CPU1_SB_DQ'<28>:
 C_SIGNAL='@t6g_mb_lib.t6g(sch_1):m_i_cpu1_sb_dq(28)';
NODE_NAME     U26 DD20
 '@T6G_MB_LIB.T6G(SCH_1):PAGE45_I159@PURE_QUANTA.GENOA_SP5(CHIPS)':
 'MIB_DATA28': CDS_PINID='MIB_DATA28';
NODE_NAME     J100 140
 '@T6G_MB_LIB.T6G(SCH_1):PAGE105_I22@PURE_QUANTA.SCONN288_DDR506112002KQ(CHIPS)':
 'DQ28_B': CDS_PINID='DQ28_B';
NET_NAME
'M_I_CPU1_SB_DQ<29>'
 '@T6G_MB_LIB.T6G(SCH_1):M_I_CPU1_SB_DQ'<29>:
 C_SIGNAL='@t6g_mb_lib.t6g(sch_1):m_i_cpu1_sb_dq(29)';
NODE_NAME     U26 DE21
 '@T6G_MB_LIB.T6G(SCH_1):PAGE45_I159@PURE_QUANTA.GENOA_SP5(CHIPS)':
 'MIB_DATA29': CDS_PINID='MIB_DATA29';
NODE_NAME     J100 142
 '@T6G_MB_LIB.T6G(SCH_1):PAGE105_I22@PURE_QUANTA.SCONN288_DDR506112002KQ(CHIPS)':
 'DQ29_B': CDS_PINID='DQ29_B';
NET_NAME
'M_I_CPU1_SB_DQ<2>'
 '@T6G_MB_LIB.T6G(SCH_1):M_I_CPU1_SB_DQ'<2>:
 C_SIGNAL='@t6g_mb_lib.t6g(sch_1):m_i_cpu1_sb_dq(2)';
NODE_NAME     U26 CC19
 '@T6G_MB_LIB.T6G(SCH_1):PAGE45_I159@PURE_QUANTA.GENOA_SP5(CHIPS)':
 'MIB_DATA2': CDS_PINID='MIB_DATA2';
NODE_NAME     J100 245
 '@T6G_MB_LIB.T6G(SCH_1):PAGE105_I22@PURE_QUANTA.SCONN288_DDR506112002KQ(CHIPS)':
 'DQ2_B': CDS_PINID='DQ2_B';
NET_NAME
'M_I_CPU1_SB_DQ<30>'
 '@T6G_MB_LIB.T6G(SCH_1):M_I_CPU1_SB_DQ'<30>:
 C_SIGNAL='@t6g_mb_lib.t6g(sch_1):m_i_cpu1_sb_dq(30)';
NODE_NAME     U26 DE19
 '@T6G_MB_LIB.T6G(SCH_1):PAGE45_I159@PURE_QUANTA.GENOA_SP5(CHIPS)':
 'MIB_DATA30': CDS_PINID='MIB_DATA30';
NODE_NAME     J100 285
 '@T6G_MB_LIB.T6G(SCH_1):PAGE105_I22@PURE_QUANTA.SCONN288_DDR506112002KQ(CHIPS)':
 'DQ30_B': CDS_PINID='DQ30_B';
NET_NAME
'M_I_CPU1_SB_DQ<31>'
 '@T6G_MB_LIB.T6G(SCH_1):M_I_CPU1_SB_DQ'<31>:
 C_SIGNAL='@t6g_mb_lib.t6g(sch_1):m_i_cpu1_sb_dq(31)';
NODE_NAME     U26 DF21
 '@T6G_MB_LIB.T6G(SCH_1):PAGE45_I159@PURE_QUANTA.GENOA_SP5(CHIPS)':
 'MIB_DATA31': CDS_PINID='MIB_DATA31';
NODE_NAME     J100 287
 '@T6G_MB_LIB.T6G(SCH_1):PAGE105_I22@PURE_QUANTA.SCONN288_DDR506112002KQ(CHIPS)':
 'DQ31_B': CDS_PINID='DQ31_B';
NET_NAME
'M_I_CPU1_SB_DQ<3>'
 '@T6G_MB_LIB.T6G(SCH_1):M_I_CPU1_SB_DQ'<3>:
 C_SIGNAL='@t6g_mb_lib.t6g(sch_1):m_i_cpu1_sb_dq(3)';
NODE_NAME     U26 CD21
 '@T6G_MB_LIB.T6G(SCH_1):PAGE45_I159@PURE_QUANTA.GENOA_SP5(CHIPS)':
 'MIB_DATA3': CDS_PINID='MIB_DATA3';
NODE_NAME     J100 247
 '@T6G_MB_LIB.T6G(SCH_1):PAGE105_I22@PURE_QUANTA.SCONN288_DDR506112002KQ(CHIPS)':
 'DQ3_B': CDS_PINID='DQ3_B';
NET_NAME
'M_I_CPU1_SB_DQ<4>'
 '@T6G_MB_LIB.T6G(SCH_1):M_I_CPU1_SB_DQ'<4>:
 C_SIGNAL='@t6g_mb_lib.t6g(sch_1):m_i_cpu1_sb_dq(4)';
NODE_NAME     U26 CF20
 '@T6G_MB_LIB.T6G(SCH_1):PAGE45_I159@PURE_QUANTA.GENOA_SP5(CHIPS)':
 'MIB_DATA4': CDS_PINID='MIB_DATA4';
NODE_NAME     J100 107
 '@T6G_MB_LIB.T6G(SCH_1):PAGE105_I22@PURE_QUANTA.SCONN288_DDR506112002KQ(CHIPS)':
 'DQ4_B': CDS_PINID='DQ4_B';
NET_NAME
'M_I_CPU1_SB_DQ<5>'
 '@T6G_MB_LIB.T6G(SCH_1):M_I_CPU1_SB_DQ'<5>:
 C_SIGNAL='@t6g_mb_lib.t6g(sch_1):m_i_cpu1_sb_dq(5)';
NODE_NAME     U26 CG21
 '@T6G_MB_LIB.T6G(SCH_1):PAGE45_I159@PURE_QUANTA.GENOA_SP5(CHIPS)':
 'MIB_DATA5': CDS_PINID='MIB_DATA5';
NODE_NAME     J100 109
 '@T6G_MB_LIB.T6G(SCH_1):PAGE105_I22@PURE_QUANTA.SCONN288_DDR506112002KQ(CHIPS)':
 'DQ5_B': CDS_PINID='DQ5_B';
NET_NAME
'M_I_CPU1_SB_DQ<6>'
 '@T6G_MB_LIB.T6G(SCH_1):M_I_CPU1_SB_DQ'<6>:
 C_SIGNAL='@t6g_mb_lib.t6g(sch_1):m_i_cpu1_sb_dq(6)';
NODE_NAME     U26 CG19
 '@T6G_MB_LIB.T6G(SCH_1):PAGE45_I159@PURE_QUANTA.GENOA_SP5(CHIPS)':
 'MIB_DATA6': CDS_PINID='MIB_DATA6';
NODE_NAME     J100 252
 '@T6G_MB_LIB.T6G(SCH_1):PAGE105_I22@PURE_QUANTA.SCONN288_DDR506112002KQ(CHIPS)':
 'DQ6_B': CDS_PINID='DQ6_B';
NET_NAME
'M_I_CPU1_SB_DQ<7>'
 '@T6G_MB_LIB.T6G(SCH_1):M_I_CPU1_SB_DQ'<7>:
 C_SIGNAL='@t6g_mb_lib.t6g(sch_1):m_i_cpu1_sb_dq(7)';
NODE_NAME     U26 CH21
 '@T6G_MB_LIB.T6G(SCH_1):PAGE45_I159@PURE_QUANTA.GENOA_SP5(CHIPS)':
 'MIB_DATA7': CDS_PINID='MIB_DATA7';
NODE_NAME     J100 254
 '@T6G_MB_LIB.T6G(SCH_1):PAGE105_I22@PURE_QUANTA.SCONN288_DDR506112002KQ(CHIPS)':
 'DQ7_B': CDS_PINID='DQ7_B';
NET_NAME
'M_I_CPU1_SB_DQ<8>'
 '@T6G_MB_LIB.T6G(SCH_1):M_I_CPU1_SB_DQ'<8>:
 C_SIGNAL='@t6g_mb_lib.t6g(sch_1):m_i_cpu1_sb_dq(8)';
NODE_NAME     U26 CH20
 '@T6G_MB_LIB.T6G(SCH_1):PAGE45_I159@PURE_QUANTA.GENOA_SP5(CHIPS)':
 'MIB_DATA8': CDS_PINID='MIB_DATA8';
NODE_NAME     J100 111
 '@T6G_MB_LIB.T6G(SCH_1):PAGE105_I22@PURE_QUANTA.SCONN288_DDR506112002KQ(CHIPS)':
 'DQ8_B': CDS_PINID='DQ8_B';
NET_NAME
'M_I_CPU1_SB_DQ<9>'
 '@T6G_MB_LIB.T6G(SCH_1):M_I_CPU1_SB_DQ'<9>:
 C_SIGNAL='@t6g_mb_lib.t6g(sch_1):m_i_cpu1_sb_dq(9)';
NODE_NAME     U26 CJ21
 '@T6G_MB_LIB.T6G(SCH_1):PAGE45_I159@PURE_QUANTA.GENOA_SP5(CHIPS)':
 'MIB_DATA9': CDS_PINID='MIB_DATA9';
NODE_NAME     J100 113
 '@T6G_MB_LIB.T6G(SCH_1):PAGE105_I22@PURE_QUANTA.SCONN288_DDR506112002KQ(CHIPS)':
 'DQ9_B': CDS_PINID='DQ9_B';
NET_NAME
'M_I_CPU1_SB_DQS_DN<0>'
 '@T6G_MB_LIB.T6G(SCH_1):M_I_CPU1_SB_DQS_DN'<0>:
 C_SIGNAL='@t6g_mb_lib.t6g(sch_1):m_i_cpu1_sb_dqs_dn(0)';
NODE_NAME     U26 CE19
 '@T6G_MB_LIB.T6G(SCH_1):PAGE45_I159@PURE_QUANTA.GENOA_SP5(CHIPS)':
 'MIB_DQS_L0': CDS_PINID='MIB_DQS_L0';
NODE_NAME     J100 105
 '@T6G_MB_LIB.T6G(SCH_1):PAGE105_I236@PURE_QUANTA.SCONN288_DDR506112002KQ(CHIPS)':
 'DQS0_B_C': CDS_PINID='DQS0_B_C';
NET_NAME
'M_I_CPU1_SB_DQS_DN<1>'
 '@T6G_MB_LIB.T6G(SCH_1):M_I_CPU1_SB_DQS_DN'<1>:
 C_SIGNAL='@t6g_mb_lib.t6g(sch_1):m_i_cpu1_sb_dqs_dn(1)';
NODE_NAME     U26 CL19
 '@T6G_MB_LIB.T6G(SCH_1):PAGE45_I159@PURE_QUANTA.GENOA_SP5(CHIPS)':
 'MIB_DQS_L1': CDS_PINID='MIB_DQS_L1';
NODE_NAME     J100 116
 '@T6G_MB_LIB.T6G(SCH_1):PAGE105_I236@PURE_QUANTA.SCONN288_DDR506112002KQ(CHIPS)':
 'DQS1_B_C': CDS_PINID='DQS1_B_C';
NET_NAME
'M_I_CPU1_SB_DQS_DN<2>'
 '@T6G_MB_LIB.T6G(SCH_1):M_I_CPU1_SB_DQS_DN'<2>:
 C_SIGNAL='@t6g_mb_lib.t6g(sch_1):m_i_cpu1_sb_dqs_dn(2)';
NODE_NAME     U26 CU19
 '@T6G_MB_LIB.T6G(SCH_1):PAGE45_I159@PURE_QUANTA.GENOA_SP5(CHIPS)':
 'MIB_DQS_L2': CDS_PINID='MIB_DQS_L2';
NODE_NAME     J100 127
 '@T6G_MB_LIB.T6G(SCH_1):PAGE105_I236@PURE_QUANTA.SCONN288_DDR506112002KQ(CHIPS)':
 'DQS2_B_C': CDS_PINID='DQS2_B_C';
NET_NAME
'M_I_CPU1_SB_DQS_DN<3>'
 '@T6G_MB_LIB.T6G(SCH_1):M_I_CPU1_SB_DQS_DN'<3>:
 C_SIGNAL='@t6g_mb_lib.t6g(sch_1):m_i_cpu1_sb_dqs_dn(3)';
NODE_NAME     U26 DC19
 '@T6G_MB_LIB.T6G(SCH_1):PAGE45_I159@PURE_QUANTA.GENOA_SP5(CHIPS)':
 'MIB_DQS_L3': CDS_PINID='MIB_DQS_L3';
NODE_NAME     J100 138
 '@T6G_MB_LIB.T6G(SCH_1):PAGE105_I236@PURE_QUANTA.SCONN288_DDR506112002KQ(CHIPS)':
 'DQS3_B_C': CDS_PINID='DQS3_B_C';
NET_NAME
'M_I_CPU1_SB_DQS_DN<4>'
 '@T6G_MB_LIB.T6G(SCH_1):M_I_CPU1_SB_DQS_DN'<4>:
 C_SIGNAL='@t6g_mb_lib.t6g(sch_1):m_i_cpu1_sb_dqs_dn(4)';
NODE_NAME     U26 BW21
 '@T6G_MB_LIB.T6G(SCH_1):PAGE45_I159@PURE_QUANTA.GENOA_SP5(CHIPS)':
 'MIB_DQS_L4': CDS_PINID='MIB_DQS_L4';
NODE_NAME     J100 238
 '@T6G_MB_LIB.T6G(SCH_1):PAGE105_I236@PURE_QUANTA.SCONN288_DDR506112002KQ(CHIPS)':
 'DQS4_B_C': CDS_PINID='DQS4_B_C';
NET_NAME
'M_I_CPU1_SB_DQS_DN<5>'
 '@T6G_MB_LIB.T6G(SCH_1):M_I_CPU1_SB_DQS_DN'<5>:
 C_SIGNAL='@t6g_mb_lib.t6g(sch_1):m_i_cpu1_sb_dqs_dn(5)';
NODE_NAME     U26 CE21
 '@T6G_MB_LIB.T6G(SCH_1):PAGE45_I159@PURE_QUANTA.GENOA_SP5(CHIPS)':
 'MIB_DQS_L5': CDS_PINID='MIB_DQS_L5';
NODE_NAME     J100 249
 '@T6G_MB_LIB.T6G(SCH_1):PAGE105_I236@PURE_QUANTA.SCONN288_DDR506112002KQ(CHIPS)':
 'DQS5_B_C||TDQS5_B_C': CDS_PINID='\dqs5_b_c||tdqs5_b_c\';
NET_NAME
'M_I_CPU1_SB_DQS_DN<6>'
 '@T6G_MB_LIB.T6G(SCH_1):M_I_CPU1_SB_DQS_DN'<6>:
 C_SIGNAL='@t6g_mb_lib.t6g(sch_1):m_i_cpu1_sb_dqs_dn(6)';
NODE_NAME     U26 CL21
 '@T6G_MB_LIB.T6G(SCH_1):PAGE45_I159@PURE_QUANTA.GENOA_SP5(CHIPS)':
 'MIB_DQS_L6': CDS_PINID='MIB_DQS_L6';
NODE_NAME     J100 260
 '@T6G_MB_LIB.T6G(SCH_1):PAGE105_I236@PURE_QUANTA.SCONN288_DDR506112002KQ(CHIPS)':
 'DQS6_B_C||TDQS6_B_C': CDS_PINID='\dqs6_b_c||tdqs6_b_c\';
NET_NAME
'M_I_CPU1_SB_DQS_DN<7>'
 '@T6G_MB_LIB.T6G(SCH_1):M_I_CPU1_SB_DQS_DN'<7>:
 C_SIGNAL='@t6g_mb_lib.t6g(sch_1):m_i_cpu1_sb_dqs_dn(7)';
NODE_NAME     U26 CU21
 '@T6G_MB_LIB.T6G(SCH_1):PAGE45_I159@PURE_QUANTA.GENOA_SP5(CHIPS)':
 'MIB_DQS_L7': CDS_PINID='MIB_DQS_L7';
NODE_NAME     J100 271
 '@T6G_MB_LIB.T6G(SCH_1):PAGE105_I236@PURE_QUANTA.SCONN288_DDR506112002KQ(CHIPS)':
 'DQS7_B_C||TDQS7_B_C': CDS_PINID='\dqs7_b_c||tdqs7_b_c\';
NET_NAME
'M_I_CPU1_SB_DQS_DN<8>'
 '@T6G_MB_LIB.T6G(SCH_1):M_I_CPU1_SB_DQS_DN'<8>:
 C_SIGNAL='@t6g_mb_lib.t6g(sch_1):m_i_cpu1_sb_dqs_dn(8)';
NODE_NAME     U26 DC21
 '@T6G_MB_LIB.T6G(SCH_1):PAGE45_I159@PURE_QUANTA.GENOA_SP5(CHIPS)':
 'MIB_DQS_L8': CDS_PINID='MIB_DQS_L8';
NODE_NAME     J100 282
 '@T6G_MB_LIB.T6G(SCH_1):PAGE105_I236@PURE_QUANTA.SCONN288_DDR506112002KQ(CHIPS)':
 'DQS8_B_C||TDQS8_B_C': CDS_PINID='\dqs8_b_c||tdqs8_b_c\';
NET_NAME
'M_I_CPU1_SB_DQS_DN<9>'
 '@T6G_MB_LIB.T6G(SCH_1):M_I_CPU1_SB_DQS_DN'<9>:
 C_SIGNAL='@t6g_mb_lib.t6g(sch_1):m_i_cpu1_sb_dqs_dn(9)';
NODE_NAME     U26 BW19
 '@T6G_MB_LIB.T6G(SCH_1):PAGE45_I159@PURE_QUANTA.GENOA_SP5(CHIPS)':
 'MIB_DQS_L9': CDS_PINID='MIB_DQS_L9';
NODE_NAME     J100 94
 '@T6G_MB_LIB.T6G(SCH_1):PAGE105_I236@PURE_QUANTA.SCONN288_DDR506112002KQ(CHIPS)':
 'DQS9_B_C||TDQS9_B_C': CDS_PINID='\dqs9_b_c||tdqs9_b_c\';
NET_NAME
'M_I_CPU1_SB_DQS_DP<0>'
 '@T6G_MB_LIB.T6G(SCH_1):M_I_CPU1_SB_DQS_DP'<0>:
 C_SIGNAL='@t6g_mb_lib.t6g(sch_1):m_i_cpu1_sb_dqs_dp(0)';
NODE_NAME     U26 CD20
 '@T6G_MB_LIB.T6G(SCH_1):PAGE45_I159@PURE_QUANTA.GENOA_SP5(CHIPS)':
 'MIB_DQS_H0': CDS_PINID='MIB_DQS_H0';
NODE_NAME     J100 104
 '@T6G_MB_LIB.T6G(SCH_1):PAGE105_I236@PURE_QUANTA.SCONN288_DDR506112002KQ(CHIPS)':
 'DQS0_B_T': CDS_PINID='DQS0_B_T';
NET_NAME
'M_I_CPU1_SB_DQS_DP<1>'
 '@T6G_MB_LIB.T6G(SCH_1):M_I_CPU1_SB_DQS_DP'<1>:
 C_SIGNAL='@t6g_mb_lib.t6g(sch_1):m_i_cpu1_sb_dqs_dp(1)';
NODE_NAME     U26 CK20
 '@T6G_MB_LIB.T6G(SCH_1):PAGE45_I159@PURE_QUANTA.GENOA_SP5(CHIPS)':
 'MIB_DQS_H1': CDS_PINID='MIB_DQS_H1';
NODE_NAME     J100 115
 '@T6G_MB_LIB.T6G(SCH_1):PAGE105_I236@PURE_QUANTA.SCONN288_DDR506112002KQ(CHIPS)':
 'DQS1_B_T': CDS_PINID='DQS1_B_T';
NET_NAME
'M_I_CPU1_SB_DQS_DP<2>'
 '@T6G_MB_LIB.T6G(SCH_1):M_I_CPU1_SB_DQS_DP'<2>:
 C_SIGNAL='@t6g_mb_lib.t6g(sch_1):m_i_cpu1_sb_dqs_dp(2)';
NODE_NAME     U26 CT20
 '@T6G_MB_LIB.T6G(SCH_1):PAGE45_I159@PURE_QUANTA.GENOA_SP5(CHIPS)':
 'MIB_DQS_H2': CDS_PINID='MIB_DQS_H2';
NODE_NAME     J100 126
 '@T6G_MB_LIB.T6G(SCH_1):PAGE105_I236@PURE_QUANTA.SCONN288_DDR506112002KQ(CHIPS)':
 'DQS2_B_T': CDS_PINID='DQS2_B_T';
NET_NAME
'M_I_CPU1_SB_DQS_DP<3>'
 '@T6G_MB_LIB.T6G(SCH_1):M_I_CPU1_SB_DQS_DP'<3>:
 C_SIGNAL='@t6g_mb_lib.t6g(sch_1):m_i_cpu1_sb_dqs_dp(3)';
NODE_NAME     U26 DB20
 '@T6G_MB_LIB.T6G(SCH_1):PAGE45_I159@PURE_QUANTA.GENOA_SP5(CHIPS)':
 'MIB_DQS_H3': CDS_PINID='MIB_DQS_H3';
NODE_NAME     J100 137
 '@T6G_MB_LIB.T6G(SCH_1):PAGE105_I236@PURE_QUANTA.SCONN288_DDR506112002KQ(CHIPS)':
 'DQS3_B_T': CDS_PINID='DQS3_B_T';
NET_NAME
'M_I_CPU1_SB_DQS_DP<4>'
 '@T6G_MB_LIB.T6G(SCH_1):M_I_CPU1_SB_DQS_DP'<4>:
 C_SIGNAL='@t6g_mb_lib.t6g(sch_1):m_i_cpu1_sb_dqs_dp(4)';
NODE_NAME     U26 BY21
 '@T6G_MB_LIB.T6G(SCH_1):PAGE45_I159@PURE_QUANTA.GENOA_SP5(CHIPS)':
 'MIB_DQS_H4': CDS_PINID='MIB_DQS_H4';
NODE_NAME     J100 239
 '@T6G_MB_LIB.T6G(SCH_1):PAGE105_I236@PURE_QUANTA.SCONN288_DDR506112002KQ(CHIPS)':
 'DQS4_B_T': CDS_PINID='DQS4_B_T';
NET_NAME
'M_I_CPU1_SB_DQS_DP<5>'
 '@T6G_MB_LIB.T6G(SCH_1):M_I_CPU1_SB_DQS_DP'<5>:
 C_SIGNAL='@t6g_mb_lib.t6g(sch_1):m_i_cpu1_sb_dqs_dp(5)';
NODE_NAME     U26 CF21
 '@T6G_MB_LIB.T6G(SCH_1):PAGE45_I159@PURE_QUANTA.GENOA_SP5(CHIPS)':
 'MIB_DQS_H5': CDS_PINID='MIB_DQS_H5';
NODE_NAME     J100 250
 '@T6G_MB_LIB.T6G(SCH_1):PAGE105_I236@PURE_QUANTA.SCONN288_DDR506112002KQ(CHIPS)':
 'DQS5_B_T||TDQS5_B_T': CDS_PINID='\dqs5_b_t||tdqs5_b_t\';
NET_NAME
'M_I_CPU1_SB_DQS_DP<6>'
 '@T6G_MB_LIB.T6G(SCH_1):M_I_CPU1_SB_DQS_DP'<6>:
 C_SIGNAL='@t6g_mb_lib.t6g(sch_1):m_i_cpu1_sb_dqs_dp(6)';
NODE_NAME     U26 CM21
 '@T6G_MB_LIB.T6G(SCH_1):PAGE45_I159@PURE_QUANTA.GENOA_SP5(CHIPS)':
 'MIB_DQS_H6': CDS_PINID='MIB_DQS_H6';
NODE_NAME     J100 261
 '@T6G_MB_LIB.T6G(SCH_1):PAGE105_I236@PURE_QUANTA.SCONN288_DDR506112002KQ(CHIPS)':
 'DQS6_B_T||TDQS6_B_T': CDS_PINID='\dqs6_b_t||tdqs6_b_t\';
NET_NAME
'M_I_CPU1_SB_DQS_DP<7>'
 '@T6G_MB_LIB.T6G(SCH_1):M_I_CPU1_SB_DQS_DP'<7>:
 C_SIGNAL='@t6g_mb_lib.t6g(sch_1):m_i_cpu1_sb_dqs_dp(7)';
NODE_NAME     U26 CV21
 '@T6G_MB_LIB.T6G(SCH_1):PAGE45_I159@PURE_QUANTA.GENOA_SP5(CHIPS)':
 'MIB_DQS_H7': CDS_PINID='MIB_DQS_H7';
NODE_NAME     J100 272
 '@T6G_MB_LIB.T6G(SCH_1):PAGE105_I236@PURE_QUANTA.SCONN288_DDR506112002KQ(CHIPS)':
 'DQS7_B_T||TDQS7_B_T': CDS_PINID='\dqs7_b_t||tdqs7_b_t\';
NET_NAME
'M_I_CPU1_SB_DQS_DP<8>'
 '@T6G_MB_LIB.T6G(SCH_1):M_I_CPU1_SB_DQS_DP'<8>:
 C_SIGNAL='@t6g_mb_lib.t6g(sch_1):m_i_cpu1_sb_dqs_dp(8)';
NODE_NAME     U26 DD21
 '@T6G_MB_LIB.T6G(SCH_1):PAGE45_I159@PURE_QUANTA.GENOA_SP5(CHIPS)':
 'MIB_DQS_H8': CDS_PINID='MIB_DQS_H8';
NODE_NAME     J100 283
 '@T6G_MB_LIB.T6G(SCH_1):PAGE105_I236@PURE_QUANTA.SCONN288_DDR506112002KQ(CHIPS)':
 'DQS8_B_T||TDQS8_B_T': CDS_PINID='\dqs8_b_t||tdqs8_b_t\';
NET_NAME
'M_I_CPU1_SB_DQS_DP<9>'
 '@T6G_MB_LIB.T6G(SCH_1):M_I_CPU1_SB_DQS_DP'<9>:
 C_SIGNAL='@t6g_mb_lib.t6g(sch_1):m_i_cpu1_sb_dqs_dp(9)';
NODE_NAME     U26 BV20
 '@T6G_MB_LIB.T6G(SCH_1):PAGE45_I159@PURE_QUANTA.GENOA_SP5(CHIPS)':
 'MIB_DQS_H9': CDS_PINID='MIB_DQS_H9';
NODE_NAME     J100 93
 '@T6G_MB_LIB.T6G(SCH_1):PAGE105_I236@PURE_QUANTA.SCONN288_DDR506112002KQ(CHIPS)':
 'DQS9_B_T||TDQS9_B_T||DBI4_B_N': CDS_PINID='\dqs9_b_t||tdqs9_b_t||dbi4_b_n\';
NET_NAME
'M_I_CPU1_SB_PAR'
 '@T6G_MB_LIB.T6G(SCH_1):M_I_CPU1_SB_PAR':
 C_SIGNAL='@t6g_mb_lib.t6g(sch_1):m_i_cpu1_sb_par';
NODE_NAME     U26 BL21
 '@T6G_MB_LIB.T6G(SCH_1):PAGE45_I159@PURE_QUANTA.GENOA_SP5(CHIPS)':
 'MIB_PAR': CDS_PINID='MIB_PAR';
NODE_NAME     J100 227
 '@T6G_MB_LIB.T6G(SCH_1):PAGE105_I22@PURE_QUANTA.SCONN288_DDR506112002KQ(CHIPS)':
 'PAR_B': CDS_PINID='PAR_B';
NET_NAME
'M_I_CPU1_SB_RSP<0>'
 '@T6G_MB_LIB.T6G(SCH_1):M_I_CPU1_SB_RSP'<0>:
 C_SIGNAL='@t6g_mb_lib.t6g(sch_1):m_i_cpu1_sb_rsp(0)';
NODE_NAME     U26 BP20
 '@T6G_MB_LIB.T6G(SCH_1):PAGE45_I159@PURE_QUANTA.GENOA_SP5(CHIPS)':
 'MIB0_RSP_L': CDS_PINID='MIB0_RSP_L';
NODE_NAME     J100 87
 '@T6G_MB_LIB.T6G(SCH_1):PAGE105_I22@PURE_QUANTA.SCONN288_DDR506112002KQ(CHIPS)':
 'LBS||RSP_B_N': CDS_PINID='\lbs||rsp_b_n\';
NET_NAME
'M_J_CPU0_ALERT_N'
 '@T6G_MB_LIB.T6G(SCH_1):M_J_CPU0_ALERT_N':
 C_SIGNAL='@t6g_mb_lib.t6g(sch_1):m_j_cpu0_alert_n';
NODE_NAME     R384 1
 '@T6G_MB_LIB.T6G(SCH_1):PAGE19_I314@PURE_QUANTA.Q_RES(CHIPS)':
 'A': CDS_PINID='A';
NODE_NAME     J68 62
 '@T6G_MB_LIB.T6G(SCH_1):PAGE94_I22@PURE_QUANTA.SCONN288_DDR506112002KQ(CHIPS)':
 'ALERT_N': CDS_PINID='ALERT_N';
NET_NAME
'M_J_CPU0_ALERT_R_N'
 '@T6G_MB_LIB.T6G(SCH_1):M_J_CPU0_ALERT_R_N':
 C_SIGNAL='@t6g_mb_lib.t6g(sch_1):m_j_cpu0_alert_r_n';
NODE_NAME     U25 AT18
 '@T6G_MB_LIB.T6G(SCH_1):PAGE19_I159@PURE_QUANTA.GENOA_SP5(CHIPS)':
 'MJ_ALERT_L': CDS_PINID='MJ_ALERT_L';
NODE_NAME     R384 2
 '@T6G_MB_LIB.T6G(SCH_1):PAGE19_I314@PURE_QUANTA.Q_RES(CHIPS)':
 'B': CDS_PINID='B';
NET_NAME
'M_J_CPU0_CLK_DN<0>'
 '@T6G_MB_LIB.T6G(SCH_1):M_J_CPU0_CLK_DN'<0>:
 C_SIGNAL='@t6g_mb_lib.t6g(sch_1):m_j_cpu0_clk_dn(0)';
NODE_NAME     U25 BD16
 '@T6G_MB_LIB.T6G(SCH_1):PAGE19_I159@PURE_QUANTA.GENOA_SP5(CHIPS)':
 'MJ0_CLK_L': CDS_PINID='MJ0_CLK_L';
NODE_NAME     J68 218
 '@T6G_MB_LIB.T6G(SCH_1):PAGE94_I22@PURE_QUANTA.SCONN288_DDR506112002KQ(CHIPS)':
 'CK_C': CDS_PINID='CK_C';
NET_NAME
'M_J_CPU0_CLK_DP<0>'
 '@T6G_MB_LIB.T6G(SCH_1):M_J_CPU0_CLK_DP'<0>:
 C_SIGNAL='@t6g_mb_lib.t6g(sch_1):m_j_cpu0_clk_dp(0)';
NODE_NAME     U25 BC16
 '@T6G_MB_LIB.T6G(SCH_1):PAGE19_I159@PURE_QUANTA.GENOA_SP5(CHIPS)':
 'MJ0_CLK_H': CDS_PINID='MJ0_CLK_H';
NODE_NAME     J68 217
 '@T6G_MB_LIB.T6G(SCH_1):PAGE94_I22@PURE_QUANTA.SCONN288_DDR506112002KQ(CHIPS)':
 'CK_T': CDS_PINID='CK_T';
NET_NAME
'M_J_CPU0_RESET_N'
 '@T6G_MB_LIB.T6G(SCH_1):M_J_CPU0_RESET_N':
 C_SIGNAL='@t6g_mb_lib.t6g(sch_1):m_j_cpu0_reset_n';
NODE_NAME     U25 AU17
 '@T6G_MB_LIB.T6G(SCH_1):PAGE19_I159@PURE_QUANTA.GENOA_SP5(CHIPS)':
 'MJ_RESET_L': CDS_PINID='MJ_RESET_L';
NODE_NAME     J68 207
 '@T6G_MB_LIB.T6G(SCH_1):PAGE94_I22@PURE_QUANTA.SCONN288_DDR506112002KQ(CHIPS)':
 'RESET_N': CDS_PINID='RESET_N';
NET_NAME
'M_J_CPU0_SA_CA<0>'
 '@T6G_MB_LIB.T6G(SCH_1):M_J_CPU0_SA_CA'<0>:
 C_SIGNAL='@t6g_mb_lib.t6g(sch_1):m_j_cpu0_sa_ca(0)';
NODE_NAME     U25 AW16
 '@T6G_MB_LIB.T6G(SCH_1):PAGE19_I159@PURE_QUANTA.GENOA_SP5(CHIPS)':
 'MJA_CA0': CDS_PINID='MJA_CA0';
NODE_NAME     J68 66
 '@T6G_MB_LIB.T6G(SCH_1):PAGE94_I22@PURE_QUANTA.SCONN288_DDR506112002KQ(CHIPS)':
 'CA0_A': CDS_PINID='CA0_A';
NET_NAME
'M_J_CPU0_SA_CA<1>'
 '@T6G_MB_LIB.T6G(SCH_1):M_J_CPU0_SA_CA'<1>:
 C_SIGNAL='@t6g_mb_lib.t6g(sch_1):m_j_cpu0_sa_ca(1)';
NODE_NAME     U25 AY16
 '@T6G_MB_LIB.T6G(SCH_1):PAGE19_I159@PURE_QUANTA.GENOA_SP5(CHIPS)':
 'MJA_CA1': CDS_PINID='MJA_CA1';
NODE_NAME     J68 211
 '@T6G_MB_LIB.T6G(SCH_1):PAGE94_I22@PURE_QUANTA.SCONN288_DDR506112002KQ(CHIPS)':
 'CA1_A': CDS_PINID='CA1_A';
NET_NAME
'M_J_CPU0_SA_CA<2>'
 '@T6G_MB_LIB.T6G(SCH_1):M_J_CPU0_SA_CA'<2>:
 C_SIGNAL='@t6g_mb_lib.t6g(sch_1):m_j_cpu0_sa_ca(2)';
NODE_NAME     U25 AY18
 '@T6G_MB_LIB.T6G(SCH_1):PAGE19_I159@PURE_QUANTA.GENOA_SP5(CHIPS)':
 'MJA_CA2': CDS_PINID='MJA_CA2';
NODE_NAME     J68 68
 '@T6G_MB_LIB.T6G(SCH_1):PAGE94_I22@PURE_QUANTA.SCONN288_DDR506112002KQ(CHIPS)':
 'CA2_A': CDS_PINID='CA2_A';
NET_NAME
'M_J_CPU0_SA_CA<3>'
 '@T6G_MB_LIB.T6G(SCH_1):M_J_CPU0_SA_CA'<3>:
 C_SIGNAL='@t6g_mb_lib.t6g(sch_1):m_j_cpu0_sa_ca(3)';
NODE_NAME     U25 BA17
 '@T6G_MB_LIB.T6G(SCH_1):PAGE19_I159@PURE_QUANTA.GENOA_SP5(CHIPS)':
 'MJA_CA3': CDS_PINID='MJA_CA3';
NODE_NAME     J68 213
 '@T6G_MB_LIB.T6G(SCH_1):PAGE94_I22@PURE_QUANTA.SCONN288_DDR506112002KQ(CHIPS)':
 'CA3_A': CDS_PINID='CA3_A';
NET_NAME
'M_J_CPU0_SA_CA<4>'
 '@T6G_MB_LIB.T6G(SCH_1):M_J_CPU0_SA_CA'<4>:
 C_SIGNAL='@t6g_mb_lib.t6g(sch_1):m_j_cpu0_sa_ca(4)';
NODE_NAME     U25 BA16
 '@T6G_MB_LIB.T6G(SCH_1):PAGE19_I159@PURE_QUANTA.GENOA_SP5(CHIPS)':
 'MJA_CA4': CDS_PINID='MJA_CA4';
NODE_NAME     J68 70
 '@T6G_MB_LIB.T6G(SCH_1):PAGE94_I22@PURE_QUANTA.SCONN288_DDR506112002KQ(CHIPS)':
 'CA4_A': CDS_PINID='CA4_A';
NET_NAME
'M_J_CPU0_SA_CA<5>'
 '@T6G_MB_LIB.T6G(SCH_1):M_J_CPU0_SA_CA'<5>:
 C_SIGNAL='@t6g_mb_lib.t6g(sch_1):m_j_cpu0_sa_ca(5)';
NODE_NAME     U25 BB16
 '@T6G_MB_LIB.T6G(SCH_1):PAGE19_I159@PURE_QUANTA.GENOA_SP5(CHIPS)':
 'MJA_CA5': CDS_PINID='MJA_CA5';
NODE_NAME     J68 215
 '@T6G_MB_LIB.T6G(SCH_1):PAGE94_I22@PURE_QUANTA.SCONN288_DDR506112002KQ(CHIPS)':
 'CA5_A': CDS_PINID='CA5_A';
NET_NAME
'M_J_CPU0_SA_CA<6>'
 '@T6G_MB_LIB.T6G(SCH_1):M_J_CPU0_SA_CA'<6>:
 C_SIGNAL='@t6g_mb_lib.t6g(sch_1):m_j_cpu0_sa_ca(6)';
NODE_NAME     U25 BB18
 '@T6G_MB_LIB.T6G(SCH_1):PAGE19_I159@PURE_QUANTA.GENOA_SP5(CHIPS)':
 'MJA_CA6': CDS_PINID='MJA_CA6';
NODE_NAME     J68 72
 '@T6G_MB_LIB.T6G(SCH_1):PAGE94_I22@PURE_QUANTA.SCONN288_DDR506112002KQ(CHIPS)':
 'CA6_A': CDS_PINID='CA6_A';
NET_NAME
'M_J_CPU0_SA_CB<0>'
 '@T6G_MB_LIB.T6G(SCH_1):M_J_CPU0_SA_CB'<0>:
 C_SIGNAL='@t6g_mb_lib.t6g(sch_1):m_j_cpu0_sa_cb(0)';
NODE_NAME     U25 AJ16
 '@T6G_MB_LIB.T6G(SCH_1):PAGE19_I159@PURE_QUANTA.GENOA_SP5(CHIPS)':
 'MJA_CHECK0': CDS_PINID='MJA_CHECK0';
NODE_NAME     J68 51
 '@T6G_MB_LIB.T6G(SCH_1):PAGE94_I22@PURE_QUANTA.SCONN288_DDR506112002KQ(CHIPS)':
 'CB0_A': CDS_PINID='CB0_A';
NET_NAME
'M_J_CPU0_SA_CB<1>'
 '@T6G_MB_LIB.T6G(SCH_1):M_J_CPU0_SA_CB'<1>:
 C_SIGNAL='@t6g_mb_lib.t6g(sch_1):m_j_cpu0_sa_cb(1)';
NODE_NAME     U25 AK18
 '@T6G_MB_LIB.T6G(SCH_1):PAGE19_I159@PURE_QUANTA.GENOA_SP5(CHIPS)':
 'MJA_CHECK1': CDS_PINID='MJA_CHECK1';
NODE_NAME     J68 53
 '@T6G_MB_LIB.T6G(SCH_1):PAGE94_I22@PURE_QUANTA.SCONN288_DDR506112002KQ(CHIPS)':
 'CB1_A': CDS_PINID='CB1_A';
NET_NAME
'M_J_CPU0_SA_CB<2>'
 '@T6G_MB_LIB.T6G(SCH_1):M_J_CPU0_SA_CB'<2>:
 C_SIGNAL='@t6g_mb_lib.t6g(sch_1):m_j_cpu0_sa_cb(2)';
NODE_NAME     U25 AK16
 '@T6G_MB_LIB.T6G(SCH_1):PAGE19_I159@PURE_QUANTA.GENOA_SP5(CHIPS)':
 'MJA_CHECK2': CDS_PINID='MJA_CHECK2';
NODE_NAME     J68 196
 '@T6G_MB_LIB.T6G(SCH_1):PAGE94_I22@PURE_QUANTA.SCONN288_DDR506112002KQ(CHIPS)':
 'CB2_A': CDS_PINID='CB2_A';
NET_NAME
'M_J_CPU0_SA_CB<3>'
 '@T6G_MB_LIB.T6G(SCH_1):M_J_CPU0_SA_CB'<3>:
 C_SIGNAL='@t6g_mb_lib.t6g(sch_1):m_j_cpu0_sa_cb(3)';
NODE_NAME     U25 AL17
 '@T6G_MB_LIB.T6G(SCH_1):PAGE19_I159@PURE_QUANTA.GENOA_SP5(CHIPS)':
 'MJA_CHECK3': CDS_PINID='MJA_CHECK3';
NODE_NAME     J68 198
 '@T6G_MB_LIB.T6G(SCH_1):PAGE94_I22@PURE_QUANTA.SCONN288_DDR506112002KQ(CHIPS)':
 'CB3_A': CDS_PINID='CB3_A';
NET_NAME
'M_J_CPU0_SA_CB<4>'
 '@T6G_MB_LIB.T6G(SCH_1):M_J_CPU0_SA_CB'<4>:
 C_SIGNAL='@t6g_mb_lib.t6g(sch_1):m_j_cpu0_sa_cb(4)';
NODE_NAME     U25 AN16
 '@T6G_MB_LIB.T6G(SCH_1):PAGE19_I159@PURE_QUANTA.GENOA_SP5(CHIPS)':
 'MJA_CHECK4': CDS_PINID='MJA_CHECK4';
NODE_NAME     J68 58
 '@T6G_MB_LIB.T6G(SCH_1):PAGE94_I22@PURE_QUANTA.SCONN288_DDR506112002KQ(CHIPS)':
 'CB4_A': CDS_PINID='CB4_A';
NET_NAME
'M_J_CPU0_SA_CB<5>'
 '@T6G_MB_LIB.T6G(SCH_1):M_J_CPU0_SA_CB'<5>:
 C_SIGNAL='@t6g_mb_lib.t6g(sch_1):m_j_cpu0_sa_cb(5)';
NODE_NAME     U25 AP18
 '@T6G_MB_LIB.T6G(SCH_1):PAGE19_I159@PURE_QUANTA.GENOA_SP5(CHIPS)':
 'MJA_CHECK5': CDS_PINID='MJA_CHECK5';
NODE_NAME     J68 60
 '@T6G_MB_LIB.T6G(SCH_1):PAGE94_I22@PURE_QUANTA.SCONN288_DDR506112002KQ(CHIPS)':
 'CB5_A': CDS_PINID='CB5_A';
NET_NAME
'M_J_CPU0_SA_CB<6>'
 '@T6G_MB_LIB.T6G(SCH_1):M_J_CPU0_SA_CB'<6>:
 C_SIGNAL='@t6g_mb_lib.t6g(sch_1):m_j_cpu0_sa_cb(6)';
NODE_NAME     U25 AP16
 '@T6G_MB_LIB.T6G(SCH_1):PAGE19_I159@PURE_QUANTA.GENOA_SP5(CHIPS)':
 'MJA_CHECK6': CDS_PINID='MJA_CHECK6';
NODE_NAME     J68 203
 '@T6G_MB_LIB.T6G(SCH_1):PAGE94_I22@PURE_QUANTA.SCONN288_DDR506112002KQ(CHIPS)':
 'CB6_A': CDS_PINID='CB6_A';
NET_NAME
'M_J_CPU0_SA_CB<7>'
 '@T6G_MB_LIB.T6G(SCH_1):M_J_CPU0_SA_CB'<7>:
 C_SIGNAL='@t6g_mb_lib.t6g(sch_1):m_j_cpu0_sa_cb(7)';
NODE_NAME     U25 AR17
 '@T6G_MB_LIB.T6G(SCH_1):PAGE19_I159@PURE_QUANTA.GENOA_SP5(CHIPS)':
 'MJA_CHECK7': CDS_PINID='MJA_CHECK7';
NODE_NAME     J68 205
 '@T6G_MB_LIB.T6G(SCH_1):PAGE94_I22@PURE_QUANTA.SCONN288_DDR506112002KQ(CHIPS)':
 'CB7_A': CDS_PINID='CB7_A';
NET_NAME
'M_J_CPU0_SA_CS_N<0>'
 '@T6G_MB_LIB.T6G(SCH_1):M_J_CPU0_SA_CS_N'<0>:
 C_SIGNAL='@t6g_mb_lib.t6g(sch_1):m_j_cpu0_sa_cs_n(0)';
NODE_NAME     U25 AU16
 '@T6G_MB_LIB.T6G(SCH_1):PAGE19_I159@PURE_QUANTA.GENOA_SP5(CHIPS)':
 'MJA0_CS_L0': CDS_PINID='MJA0_CS_L0';
NODE_NAME     J68 64
 '@T6G_MB_LIB.T6G(SCH_1):PAGE94_I22@PURE_QUANTA.SCONN288_DDR506112002KQ(CHIPS)':
 'CS0_A_N': CDS_PINID='CS0_A_N';
NET_NAME
'M_J_CPU0_SA_CS_N<1>'
 '@T6G_MB_LIB.T6G(SCH_1):M_J_CPU0_SA_CS_N'<1>:
 C_SIGNAL='@t6g_mb_lib.t6g(sch_1):m_j_cpu0_sa_cs_n(1)';
NODE_NAME     U25 AV18
 '@T6G_MB_LIB.T6G(SCH_1):PAGE19_I159@PURE_QUANTA.GENOA_SP5(CHIPS)':
 'MJA0_CS_L1': CDS_PINID='MJA0_CS_L1';
NODE_NAME     J68 209
 '@T6G_MB_LIB.T6G(SCH_1):PAGE94_I22@PURE_QUANTA.SCONN288_DDR506112002KQ(CHIPS)':
 'CS1_A_N': CDS_PINID='CS1_A_N';
NET_NAME
'M_J_CPU0_SA_DQ<0>'
 '@T6G_MB_LIB.T6G(SCH_1):M_J_CPU0_SA_DQ'<0>:
 C_SIGNAL='@t6g_mb_lib.t6g(sch_1):m_j_cpu0_sa_dq(0)';
NODE_NAME     U25 E16
 '@T6G_MB_LIB.T6G(SCH_1):PAGE19_I159@PURE_QUANTA.GENOA_SP5(CHIPS)':
 'MJA_DATA0': CDS_PINID='MJA_DATA0';
NODE_NAME     J68 7
 '@T6G_MB_LIB.T6G(SCH_1):PAGE94_I22@PURE_QUANTA.SCONN288_DDR506112002KQ(CHIPS)':
 'DQ0_A': CDS_PINID='DQ0_A';
NET_NAME
'M_J_CPU0_SA_DQ<10>'
 '@T6G_MB_LIB.T6G(SCH_1):M_J_CPU0_SA_DQ'<10>:
 C_SIGNAL='@t6g_mb_lib.t6g(sch_1):m_j_cpu0_sa_dq(10)';
NODE_NAME     U25 M16
 '@T6G_MB_LIB.T6G(SCH_1):PAGE19_I159@PURE_QUANTA.GENOA_SP5(CHIPS)':
 'MJA_DATA10': CDS_PINID='MJA_DATA10';
NODE_NAME     J68 163
 '@T6G_MB_LIB.T6G(SCH_1):PAGE94_I22@PURE_QUANTA.SCONN288_DDR506112002KQ(CHIPS)':
 'DQ10_A': CDS_PINID='DQ10_A';
NET_NAME
'M_J_CPU0_SA_DQ<11>'
 '@T6G_MB_LIB.T6G(SCH_1):M_J_CPU0_SA_DQ'<11>:
 C_SIGNAL='@t6g_mb_lib.t6g(sch_1):m_j_cpu0_sa_dq(11)';
NODE_NAME     U25 N17
 '@T6G_MB_LIB.T6G(SCH_1):PAGE19_I159@PURE_QUANTA.GENOA_SP5(CHIPS)':
 'MJA_DATA11': CDS_PINID='MJA_DATA11';
NODE_NAME     J68 165
 '@T6G_MB_LIB.T6G(SCH_1):PAGE94_I22@PURE_QUANTA.SCONN288_DDR506112002KQ(CHIPS)':
 'DQ11_A': CDS_PINID='DQ11_A';
NET_NAME
'M_J_CPU0_SA_DQ<12>'
 '@T6G_MB_LIB.T6G(SCH_1):M_J_CPU0_SA_DQ'<12>:
 C_SIGNAL='@t6g_mb_lib.t6g(sch_1):m_j_cpu0_sa_dq(12)';
NODE_NAME     U25 R16
 '@T6G_MB_LIB.T6G(SCH_1):PAGE19_I159@PURE_QUANTA.GENOA_SP5(CHIPS)':
 'MJA_DATA12': CDS_PINID='MJA_DATA12';
NODE_NAME     J68 25
 '@T6G_MB_LIB.T6G(SCH_1):PAGE94_I22@PURE_QUANTA.SCONN288_DDR506112002KQ(CHIPS)':
 'DQ12_A': CDS_PINID='DQ12_A';
NET_NAME
'M_J_CPU0_SA_DQ<13>'
 '@T6G_MB_LIB.T6G(SCH_1):M_J_CPU0_SA_DQ'<13>:
 C_SIGNAL='@t6g_mb_lib.t6g(sch_1):m_j_cpu0_sa_dq(13)';
NODE_NAME     U25 T18
 '@T6G_MB_LIB.T6G(SCH_1):PAGE19_I159@PURE_QUANTA.GENOA_SP5(CHIPS)':
 'MJA_DATA13': CDS_PINID='MJA_DATA13';
NODE_NAME     J68 27
 '@T6G_MB_LIB.T6G(SCH_1):PAGE94_I22@PURE_QUANTA.SCONN288_DDR506112002KQ(CHIPS)':
 'DQ13_A': CDS_PINID='DQ13_A';
NET_NAME
'M_J_CPU0_SA_DQ<14>'
 '@T6G_MB_LIB.T6G(SCH_1):M_J_CPU0_SA_DQ'<14>:
 C_SIGNAL='@t6g_mb_lib.t6g(sch_1):m_j_cpu0_sa_dq(14)';
NODE_NAME     U25 T16
 '@T6G_MB_LIB.T6G(SCH_1):PAGE19_I159@PURE_QUANTA.GENOA_SP5(CHIPS)':
 'MJA_DATA14': CDS_PINID='MJA_DATA14';
NODE_NAME     J68 170
 '@T6G_MB_LIB.T6G(SCH_1):PAGE94_I22@PURE_QUANTA.SCONN288_DDR506112002KQ(CHIPS)':
 'DQ14_A': CDS_PINID='DQ14_A';
NET_NAME
'M_J_CPU0_SA_DQ<15>'
 '@T6G_MB_LIB.T6G(SCH_1):M_J_CPU0_SA_DQ'<15>:
 C_SIGNAL='@t6g_mb_lib.t6g(sch_1):m_j_cpu0_sa_dq(15)';
NODE_NAME     U25 U17
 '@T6G_MB_LIB.T6G(SCH_1):PAGE19_I159@PURE_QUANTA.GENOA_SP5(CHIPS)':
 'MJA_DATA15': CDS_PINID='MJA_DATA15';
NODE_NAME     J68 172
 '@T6G_MB_LIB.T6G(SCH_1):PAGE94_I22@PURE_QUANTA.SCONN288_DDR506112002KQ(CHIPS)':
 'DQ15_A': CDS_PINID='DQ15_A';
NET_NAME
'M_J_CPU0_SA_DQ<16>'
 '@T6G_MB_LIB.T6G(SCH_1):M_J_CPU0_SA_DQ'<16>:
 C_SIGNAL='@t6g_mb_lib.t6g(sch_1):m_j_cpu0_sa_dq(16)';
NODE_NAME     U25 U16
 '@T6G_MB_LIB.T6G(SCH_1):PAGE19_I159@PURE_QUANTA.GENOA_SP5(CHIPS)':
 'MJA_DATA16': CDS_PINID='MJA_DATA16';
NODE_NAME     J68 29
 '@T6G_MB_LIB.T6G(SCH_1):PAGE94_I22@PURE_QUANTA.SCONN288_DDR506112002KQ(CHIPS)':
 'DQ16_A': CDS_PINID='DQ16_A';
NET_NAME
'M_J_CPU0_SA_DQ<17>'
 '@T6G_MB_LIB.T6G(SCH_1):M_J_CPU0_SA_DQ'<17>:
 C_SIGNAL='@t6g_mb_lib.t6g(sch_1):m_j_cpu0_sa_dq(17)';
NODE_NAME     U25 V18
 '@T6G_MB_LIB.T6G(SCH_1):PAGE19_I159@PURE_QUANTA.GENOA_SP5(CHIPS)':
 'MJA_DATA17': CDS_PINID='MJA_DATA17';
NODE_NAME     J68 31
 '@T6G_MB_LIB.T6G(SCH_1):PAGE94_I22@PURE_QUANTA.SCONN288_DDR506112002KQ(CHIPS)':
 'DQ17_A': CDS_PINID='DQ17_A';
NET_NAME
'M_J_CPU0_SA_DQ<18>'
 '@T6G_MB_LIB.T6G(SCH_1):M_J_CPU0_SA_DQ'<18>:
 C_SIGNAL='@t6g_mb_lib.t6g(sch_1):m_j_cpu0_sa_dq(18)';
NODE_NAME     U25 V16
 '@T6G_MB_LIB.T6G(SCH_1):PAGE19_I159@PURE_QUANTA.GENOA_SP5(CHIPS)':
 'MJA_DATA18': CDS_PINID='MJA_DATA18';
NODE_NAME     J68 174
 '@T6G_MB_LIB.T6G(SCH_1):PAGE94_I22@PURE_QUANTA.SCONN288_DDR506112002KQ(CHIPS)':
 'DQ18_A': CDS_PINID='DQ18_A';
NET_NAME
'M_J_CPU0_SA_DQ<19>'
 '@T6G_MB_LIB.T6G(SCH_1):M_J_CPU0_SA_DQ'<19>:
 C_SIGNAL='@t6g_mb_lib.t6g(sch_1):m_j_cpu0_sa_dq(19)';
NODE_NAME     U25 W17
 '@T6G_MB_LIB.T6G(SCH_1):PAGE19_I159@PURE_QUANTA.GENOA_SP5(CHIPS)':
 'MJA_DATA19': CDS_PINID='MJA_DATA19';
NODE_NAME     J68 176
 '@T6G_MB_LIB.T6G(SCH_1):PAGE94_I22@PURE_QUANTA.SCONN288_DDR506112002KQ(CHIPS)':
 'DQ19_A': CDS_PINID='DQ19_A';
NET_NAME
'M_J_CPU0_SA_DQ<1>'
 '@T6G_MB_LIB.T6G(SCH_1):M_J_CPU0_SA_DQ'<1>:
 C_SIGNAL='@t6g_mb_lib.t6g(sch_1):m_j_cpu0_sa_dq(1)';
NODE_NAME     U25 F18
 '@T6G_MB_LIB.T6G(SCH_1):PAGE19_I159@PURE_QUANTA.GENOA_SP5(CHIPS)':
 'MJA_DATA1': CDS_PINID='MJA_DATA1';
NODE_NAME     J68 9
 '@T6G_MB_LIB.T6G(SCH_1):PAGE94_I22@PURE_QUANTA.SCONN288_DDR506112002KQ(CHIPS)':
 'DQ1_A': CDS_PINID='DQ1_A';
NET_NAME
'M_J_CPU0_SA_DQ<20>'
 '@T6G_MB_LIB.T6G(SCH_1):M_J_CPU0_SA_DQ'<20>:
 C_SIGNAL='@t6g_mb_lib.t6g(sch_1):m_j_cpu0_sa_dq(20)';
NODE_NAME     U25 AA16
 '@T6G_MB_LIB.T6G(SCH_1):PAGE19_I159@PURE_QUANTA.GENOA_SP5(CHIPS)':
 'MJA_DATA20': CDS_PINID='MJA_DATA20';
NODE_NAME     J68 36
 '@T6G_MB_LIB.T6G(SCH_1):PAGE94_I22@PURE_QUANTA.SCONN288_DDR506112002KQ(CHIPS)':
 'DQ20_A': CDS_PINID='DQ20_A';
NET_NAME
'M_J_CPU0_SA_DQ<21>'
 '@T6G_MB_LIB.T6G(SCH_1):M_J_CPU0_SA_DQ'<21>:
 C_SIGNAL='@t6g_mb_lib.t6g(sch_1):m_j_cpu0_sa_dq(21)';
NODE_NAME     U25 AB18
 '@T6G_MB_LIB.T6G(SCH_1):PAGE19_I159@PURE_QUANTA.GENOA_SP5(CHIPS)':
 'MJA_DATA21': CDS_PINID='MJA_DATA21';
NODE_NAME     J68 38
 '@T6G_MB_LIB.T6G(SCH_1):PAGE94_I22@PURE_QUANTA.SCONN288_DDR506112002KQ(CHIPS)':
 'DQ21_A': CDS_PINID='DQ21_A';
NET_NAME
'M_J_CPU0_SA_DQ<22>'
 '@T6G_MB_LIB.T6G(SCH_1):M_J_CPU0_SA_DQ'<22>:
 C_SIGNAL='@t6g_mb_lib.t6g(sch_1):m_j_cpu0_sa_dq(22)';
NODE_NAME     U25 AB16
 '@T6G_MB_LIB.T6G(SCH_1):PAGE19_I159@PURE_QUANTA.GENOA_SP5(CHIPS)':
 'MJA_DATA22': CDS_PINID='MJA_DATA22';
NODE_NAME     J68 181
 '@T6G_MB_LIB.T6G(SCH_1):PAGE94_I22@PURE_QUANTA.SCONN288_DDR506112002KQ(CHIPS)':
 'DQ22_A': CDS_PINID='DQ22_A';
NET_NAME
'M_J_CPU0_SA_DQ<23>'
 '@T6G_MB_LIB.T6G(SCH_1):M_J_CPU0_SA_DQ'<23>:
 C_SIGNAL='@t6g_mb_lib.t6g(sch_1):m_j_cpu0_sa_dq(23)';
NODE_NAME     U25 AC17
 '@T6G_MB_LIB.T6G(SCH_1):PAGE19_I159@PURE_QUANTA.GENOA_SP5(CHIPS)':
 'MJA_DATA23': CDS_PINID='MJA_DATA23';
NODE_NAME     J68 183
 '@T6G_MB_LIB.T6G(SCH_1):PAGE94_I22@PURE_QUANTA.SCONN288_DDR506112002KQ(CHIPS)':
 'DQ23_A': CDS_PINID='DQ23_A';
NET_NAME
'M_J_CPU0_SA_DQ<24>'
 '@T6G_MB_LIB.T6G(SCH_1):M_J_CPU0_SA_DQ'<24>:
 C_SIGNAL='@t6g_mb_lib.t6g(sch_1):m_j_cpu0_sa_dq(24)';
NODE_NAME     U25 AC16
 '@T6G_MB_LIB.T6G(SCH_1):PAGE19_I159@PURE_QUANTA.GENOA_SP5(CHIPS)':
 'MJA_DATA24': CDS_PINID='MJA_DATA24';
NODE_NAME     J68 40
 '@T6G_MB_LIB.T6G(SCH_1):PAGE94_I22@PURE_QUANTA.SCONN288_DDR506112002KQ(CHIPS)':
 'DQ24_A': CDS_PINID='DQ24_A';
NET_NAME
'M_J_CPU0_SA_DQ<25>'
 '@T6G_MB_LIB.T6G(SCH_1):M_J_CPU0_SA_DQ'<25>:
 C_SIGNAL='@t6g_mb_lib.t6g(sch_1):m_j_cpu0_sa_dq(25)';
NODE_NAME     U25 AD18
 '@T6G_MB_LIB.T6G(SCH_1):PAGE19_I159@PURE_QUANTA.GENOA_SP5(CHIPS)':
 'MJA_DATA25': CDS_PINID='MJA_DATA25';
NODE_NAME     J68 42
 '@T6G_MB_LIB.T6G(SCH_1):PAGE94_I22@PURE_QUANTA.SCONN288_DDR506112002KQ(CHIPS)':
 'DQ25_A': CDS_PINID='DQ25_A';
NET_NAME
'M_J_CPU0_SA_DQ<26>'
 '@T6G_MB_LIB.T6G(SCH_1):M_J_CPU0_SA_DQ'<26>:
 C_SIGNAL='@t6g_mb_lib.t6g(sch_1):m_j_cpu0_sa_dq(26)';
NODE_NAME     U25 AD16
 '@T6G_MB_LIB.T6G(SCH_1):PAGE19_I159@PURE_QUANTA.GENOA_SP5(CHIPS)':
 'MJA_DATA26': CDS_PINID='MJA_DATA26';
NODE_NAME     J68 185
 '@T6G_MB_LIB.T6G(SCH_1):PAGE94_I22@PURE_QUANTA.SCONN288_DDR506112002KQ(CHIPS)':
 'DQ26_A': CDS_PINID='DQ26_A';
NET_NAME
'M_J_CPU0_SA_DQ<27>'
 '@T6G_MB_LIB.T6G(SCH_1):M_J_CPU0_SA_DQ'<27>:
 C_SIGNAL='@t6g_mb_lib.t6g(sch_1):m_j_cpu0_sa_dq(27)';
NODE_NAME     U25 AE17
 '@T6G_MB_LIB.T6G(SCH_1):PAGE19_I159@PURE_QUANTA.GENOA_SP5(CHIPS)':
 'MJA_DATA27': CDS_PINID='MJA_DATA27';
NODE_NAME     J68 187
 '@T6G_MB_LIB.T6G(SCH_1):PAGE94_I22@PURE_QUANTA.SCONN288_DDR506112002KQ(CHIPS)':
 'DQ27_A': CDS_PINID='DQ27_A';
NET_NAME
'M_J_CPU0_SA_DQ<28>'
 '@T6G_MB_LIB.T6G(SCH_1):M_J_CPU0_SA_DQ'<28>:
 C_SIGNAL='@t6g_mb_lib.t6g(sch_1):m_j_cpu0_sa_dq(28)';
NODE_NAME     U25 AG16
 '@T6G_MB_LIB.T6G(SCH_1):PAGE19_I159@PURE_QUANTA.GENOA_SP5(CHIPS)':
 'MJA_DATA28': CDS_PINID='MJA_DATA28';
NODE_NAME     J68 47
 '@T6G_MB_LIB.T6G(SCH_1):PAGE94_I22@PURE_QUANTA.SCONN288_DDR506112002KQ(CHIPS)':
 'DQ28_A': CDS_PINID='DQ28_A';
NET_NAME
'M_J_CPU0_SA_DQ<29>'
 '@T6G_MB_LIB.T6G(SCH_1):M_J_CPU0_SA_DQ'<29>:
 C_SIGNAL='@t6g_mb_lib.t6g(sch_1):m_j_cpu0_sa_dq(29)';
NODE_NAME     U25 AH18
 '@T6G_MB_LIB.T6G(SCH_1):PAGE19_I159@PURE_QUANTA.GENOA_SP5(CHIPS)':
 'MJA_DATA29': CDS_PINID='MJA_DATA29';
NODE_NAME     J68 49
 '@T6G_MB_LIB.T6G(SCH_1):PAGE94_I22@PURE_QUANTA.SCONN288_DDR506112002KQ(CHIPS)':
 'DQ29_A': CDS_PINID='DQ29_A';
NET_NAME
'M_J_CPU0_SA_DQ<2>'
 '@T6G_MB_LIB.T6G(SCH_1):M_J_CPU0_SA_DQ'<2>:
 C_SIGNAL='@t6g_mb_lib.t6g(sch_1):m_j_cpu0_sa_dq(2)';
NODE_NAME     U25 F16
 '@T6G_MB_LIB.T6G(SCH_1):PAGE19_I159@PURE_QUANTA.GENOA_SP5(CHIPS)':
 'MJA_DATA2': CDS_PINID='MJA_DATA2';
NODE_NAME     J68 152
 '@T6G_MB_LIB.T6G(SCH_1):PAGE94_I22@PURE_QUANTA.SCONN288_DDR506112002KQ(CHIPS)':
 'DQ2_A': CDS_PINID='DQ2_A';
NET_NAME
'M_J_CPU0_SA_DQ<30>'
 '@T6G_MB_LIB.T6G(SCH_1):M_J_CPU0_SA_DQ'<30>:
 C_SIGNAL='@t6g_mb_lib.t6g(sch_1):m_j_cpu0_sa_dq(30)';
NODE_NAME     U25 AH16
 '@T6G_MB_LIB.T6G(SCH_1):PAGE19_I159@PURE_QUANTA.GENOA_SP5(CHIPS)':
 'MJA_DATA30': CDS_PINID='MJA_DATA30';
NODE_NAME     J68 192
 '@T6G_MB_LIB.T6G(SCH_1):PAGE94_I22@PURE_QUANTA.SCONN288_DDR506112002KQ(CHIPS)':
 'DQ30_A': CDS_PINID='DQ30_A';
NET_NAME
'M_J_CPU0_SA_DQ<31>'
 '@T6G_MB_LIB.T6G(SCH_1):M_J_CPU0_SA_DQ'<31>:
 C_SIGNAL='@t6g_mb_lib.t6g(sch_1):m_j_cpu0_sa_dq(31)';
NODE_NAME     U25 AJ17
 '@T6G_MB_LIB.T6G(SCH_1):PAGE19_I159@PURE_QUANTA.GENOA_SP5(CHIPS)':
 'MJA_DATA31': CDS_PINID='MJA_DATA31';
NODE_NAME     J68 194
 '@T6G_MB_LIB.T6G(SCH_1):PAGE94_I22@PURE_QUANTA.SCONN288_DDR506112002KQ(CHIPS)':
 'DQ31_A': CDS_PINID='DQ31_A';
NET_NAME
'M_J_CPU0_SA_DQ<3>'
 '@T6G_MB_LIB.T6G(SCH_1):M_J_CPU0_SA_DQ'<3>:
 C_SIGNAL='@t6g_mb_lib.t6g(sch_1):m_j_cpu0_sa_dq(3)';
NODE_NAME     U25 G17
 '@T6G_MB_LIB.T6G(SCH_1):PAGE19_I159@PURE_QUANTA.GENOA_SP5(CHIPS)':
 'MJA_DATA3': CDS_PINID='MJA_DATA3';
NODE_NAME     J68 154
 '@T6G_MB_LIB.T6G(SCH_1):PAGE94_I22@PURE_QUANTA.SCONN288_DDR506112002KQ(CHIPS)':
 'DQ3_A': CDS_PINID='DQ3_A';
NET_NAME
'M_J_CPU0_SA_DQ<4>'
 '@T6G_MB_LIB.T6G(SCH_1):M_J_CPU0_SA_DQ'<4>:
 C_SIGNAL='@t6g_mb_lib.t6g(sch_1):m_j_cpu0_sa_dq(4)';
NODE_NAME     U25 J16
 '@T6G_MB_LIB.T6G(SCH_1):PAGE19_I159@PURE_QUANTA.GENOA_SP5(CHIPS)':
 'MJA_DATA4': CDS_PINID='MJA_DATA4';
NODE_NAME     J68 14
 '@T6G_MB_LIB.T6G(SCH_1):PAGE94_I22@PURE_QUANTA.SCONN288_DDR506112002KQ(CHIPS)':
 'DQ4_A': CDS_PINID='DQ4_A';
NET_NAME
'M_J_CPU0_SA_DQ<5>'
 '@T6G_MB_LIB.T6G(SCH_1):M_J_CPU0_SA_DQ'<5>:
 C_SIGNAL='@t6g_mb_lib.t6g(sch_1):m_j_cpu0_sa_dq(5)';
NODE_NAME     U25 K18
 '@T6G_MB_LIB.T6G(SCH_1):PAGE19_I159@PURE_QUANTA.GENOA_SP5(CHIPS)':
 'MJA_DATA5': CDS_PINID='MJA_DATA5';
NODE_NAME     J68 16
 '@T6G_MB_LIB.T6G(SCH_1):PAGE94_I22@PURE_QUANTA.SCONN288_DDR506112002KQ(CHIPS)':
 'DQ5_A': CDS_PINID='DQ5_A';
NET_NAME
'M_J_CPU0_SA_DQ<6>'
 '@T6G_MB_LIB.T6G(SCH_1):M_J_CPU0_SA_DQ'<6>:
 C_SIGNAL='@t6g_mb_lib.t6g(sch_1):m_j_cpu0_sa_dq(6)';
NODE_NAME     U25 K16
 '@T6G_MB_LIB.T6G(SCH_1):PAGE19_I159@PURE_QUANTA.GENOA_SP5(CHIPS)':
 'MJA_DATA6': CDS_PINID='MJA_DATA6';
NODE_NAME     J68 159
 '@T6G_MB_LIB.T6G(SCH_1):PAGE94_I22@PURE_QUANTA.SCONN288_DDR506112002KQ(CHIPS)':
 'DQ6_A': CDS_PINID='DQ6_A';
NET_NAME
'M_J_CPU0_SA_DQ<7>'
 '@T6G_MB_LIB.T6G(SCH_1):M_J_CPU0_SA_DQ'<7>:
 C_SIGNAL='@t6g_mb_lib.t6g(sch_1):m_j_cpu0_sa_dq(7)';
NODE_NAME     U25 L17
 '@T6G_MB_LIB.T6G(SCH_1):PAGE19_I159@PURE_QUANTA.GENOA_SP5(CHIPS)':
 'MJA_DATA7': CDS_PINID='MJA_DATA7';
NODE_NAME     J68 161
 '@T6G_MB_LIB.T6G(SCH_1):PAGE94_I22@PURE_QUANTA.SCONN288_DDR506112002KQ(CHIPS)':
 'DQ7_A': CDS_PINID='DQ7_A';
NET_NAME
'M_J_CPU0_SA_DQ<8>'
 '@T6G_MB_LIB.T6G(SCH_1):M_J_CPU0_SA_DQ'<8>:
 C_SIGNAL='@t6g_mb_lib.t6g(sch_1):m_j_cpu0_sa_dq(8)';
NODE_NAME     U25 L16
 '@T6G_MB_LIB.T6G(SCH_1):PAGE19_I159@PURE_QUANTA.GENOA_SP5(CHIPS)':
 'MJA_DATA8': CDS_PINID='MJA_DATA8';
NODE_NAME     J68 18
 '@T6G_MB_LIB.T6G(SCH_1):PAGE94_I22@PURE_QUANTA.SCONN288_DDR506112002KQ(CHIPS)':
 'DQ8_A': CDS_PINID='DQ8_A';
NET_NAME
'M_J_CPU0_SA_DQ<9>'
 '@T6G_MB_LIB.T6G(SCH_1):M_J_CPU0_SA_DQ'<9>:
 C_SIGNAL='@t6g_mb_lib.t6g(sch_1):m_j_cpu0_sa_dq(9)';
NODE_NAME     U25 M18
 '@T6G_MB_LIB.T6G(SCH_1):PAGE19_I159@PURE_QUANTA.GENOA_SP5(CHIPS)':
 'MJA_DATA9': CDS_PINID='MJA_DATA9';
NODE_NAME     J68 20
 '@T6G_MB_LIB.T6G(SCH_1):PAGE94_I22@PURE_QUANTA.SCONN288_DDR506112002KQ(CHIPS)':
 'DQ9_A': CDS_PINID='DQ9_A';
NET_NAME
'M_J_CPU0_SA_DQS_DN<0>'
 '@T6G_MB_LIB.T6G(SCH_1):M_J_CPU0_SA_DQS_DN'<0>:
 C_SIGNAL='@t6g_mb_lib.t6g(sch_1):m_j_cpu0_sa_dqs_dn(0)';
NODE_NAME     U25 H16
 '@T6G_MB_LIB.T6G(SCH_1):PAGE19_I159@PURE_QUANTA.GENOA_SP5(CHIPS)':
 'MJA_DQS_L0': CDS_PINID='MJA_DQS_L0';
NODE_NAME     J68 12
 '@T6G_MB_LIB.T6G(SCH_1):PAGE94_I236@PURE_QUANTA.SCONN288_DDR506112002KQ(CHIPS)':
 'DQS0_A_C': CDS_PINID='DQS0_A_C';
NET_NAME
'M_J_CPU0_SA_DQS_DN<1>'
 '@T6G_MB_LIB.T6G(SCH_1):M_J_CPU0_SA_DQS_DN'<1>:
 C_SIGNAL='@t6g_mb_lib.t6g(sch_1):m_j_cpu0_sa_dqs_dn(1)';
NODE_NAME     U25 P16
 '@T6G_MB_LIB.T6G(SCH_1):PAGE19_I159@PURE_QUANTA.GENOA_SP5(CHIPS)':
 'MJA_DQS_L1': CDS_PINID='MJA_DQS_L1';
NODE_NAME     J68 23
 '@T6G_MB_LIB.T6G(SCH_1):PAGE94_I236@PURE_QUANTA.SCONN288_DDR506112002KQ(CHIPS)':
 'DQS1_A_C': CDS_PINID='DQS1_A_C';
NET_NAME
'M_J_CPU0_SA_DQS_DN<2>'
 '@T6G_MB_LIB.T6G(SCH_1):M_J_CPU0_SA_DQS_DN'<2>:
 C_SIGNAL='@t6g_mb_lib.t6g(sch_1):m_j_cpu0_sa_dqs_dn(2)';
NODE_NAME     U25 Y16
 '@T6G_MB_LIB.T6G(SCH_1):PAGE19_I159@PURE_QUANTA.GENOA_SP5(CHIPS)':
 'MJA_DQS_L2': CDS_PINID='MJA_DQS_L2';
NODE_NAME     J68 34
 '@T6G_MB_LIB.T6G(SCH_1):PAGE94_I236@PURE_QUANTA.SCONN288_DDR506112002KQ(CHIPS)':
 'DQS2_A_C': CDS_PINID='DQS2_A_C';
NET_NAME
'M_J_CPU0_SA_DQS_DN<3>'
 '@T6G_MB_LIB.T6G(SCH_1):M_J_CPU0_SA_DQS_DN'<3>:
 C_SIGNAL='@t6g_mb_lib.t6g(sch_1):m_j_cpu0_sa_dqs_dn(3)';
NODE_NAME     U25 AF16
 '@T6G_MB_LIB.T6G(SCH_1):PAGE19_I159@PURE_QUANTA.GENOA_SP5(CHIPS)':
 'MJA_DQS_L3': CDS_PINID='MJA_DQS_L3';
NODE_NAME     J68 45
 '@T6G_MB_LIB.T6G(SCH_1):PAGE94_I236@PURE_QUANTA.SCONN288_DDR506112002KQ(CHIPS)':
 'DQS3_A_C': CDS_PINID='DQS3_A_C';
NET_NAME
'M_J_CPU0_SA_DQS_DN<4>'
 '@T6G_MB_LIB.T6G(SCH_1):M_J_CPU0_SA_DQS_DN'<4>:
 C_SIGNAL='@t6g_mb_lib.t6g(sch_1):m_j_cpu0_sa_dqs_dn(4)';
NODE_NAME     U25 AM16
 '@T6G_MB_LIB.T6G(SCH_1):PAGE19_I159@PURE_QUANTA.GENOA_SP5(CHIPS)':
 'MJA_DQS_L4': CDS_PINID='MJA_DQS_L4';
NODE_NAME     J68 56
 '@T6G_MB_LIB.T6G(SCH_1):PAGE94_I236@PURE_QUANTA.SCONN288_DDR506112002KQ(CHIPS)':
 'DQS4_A_C': CDS_PINID='DQS4_A_C';
NET_NAME
'M_J_CPU0_SA_DQS_DN<5>'
 '@T6G_MB_LIB.T6G(SCH_1):M_J_CPU0_SA_DQS_DN'<5>:
 C_SIGNAL='@t6g_mb_lib.t6g(sch_1):m_j_cpu0_sa_dqs_dn(5)';
NODE_NAME     U25 H18
 '@T6G_MB_LIB.T6G(SCH_1):PAGE19_I159@PURE_QUANTA.GENOA_SP5(CHIPS)':
 'MJA_DQS_L5': CDS_PINID='MJA_DQS_L5';
NODE_NAME     J68 156
 '@T6G_MB_LIB.T6G(SCH_1):PAGE94_I236@PURE_QUANTA.SCONN288_DDR506112002KQ(CHIPS)':
 'DQS5_A_C||TDQS5_A_C||DQS5_A_T||TDQS5_A_T': CDS_PINID='\dqs5_a_c||tdqs5_a_c||dqs5_a_t||tdqs5_a_t\';
NET_NAME
'M_J_CPU0_SA_DQS_DN<6>'
 '@T6G_MB_LIB.T6G(SCH_1):M_J_CPU0_SA_DQS_DN'<6>:
 C_SIGNAL='@t6g_mb_lib.t6g(sch_1):m_j_cpu0_sa_dqs_dn(6)';
NODE_NAME     U25 P18
 '@T6G_MB_LIB.T6G(SCH_1):PAGE19_I159@PURE_QUANTA.GENOA_SP5(CHIPS)':
 'MJA_DQS_L6': CDS_PINID='MJA_DQS_L6';
NODE_NAME     J68 167
 '@T6G_MB_LIB.T6G(SCH_1):PAGE94_I236@PURE_QUANTA.SCONN288_DDR506112002KQ(CHIPS)':
 'DQS6_A_C||TDQS6_A_C||DQS6_A_T||TDQS6_A_T': CDS_PINID='\dqs6_a_c||tdqs6_a_c||dqs6_a_t||tdqs6_a_t\';
NET_NAME
'M_J_CPU0_SA_DQS_DN<7>'
 '@T6G_MB_LIB.T6G(SCH_1):M_J_CPU0_SA_DQS_DN'<7>:
 C_SIGNAL='@t6g_mb_lib.t6g(sch_1):m_j_cpu0_sa_dqs_dn(7)';
NODE_NAME     U25 Y18
 '@T6G_MB_LIB.T6G(SCH_1):PAGE19_I159@PURE_QUANTA.GENOA_SP5(CHIPS)':
 'MJA_DQS_L7': CDS_PINID='MJA_DQS_L7';
NODE_NAME     J68 178
 '@T6G_MB_LIB.T6G(SCH_1):PAGE94_I236@PURE_QUANTA.SCONN288_DDR506112002KQ(CHIPS)':
 'DQS7_A_C||TDQS7_A_C': CDS_PINID='\dqs7_a_c||tdqs7_a_c\';
NET_NAME
'M_J_CPU0_SA_DQS_DN<8>'
 '@T6G_MB_LIB.T6G(SCH_1):M_J_CPU0_SA_DQS_DN'<8>:
 C_SIGNAL='@t6g_mb_lib.t6g(sch_1):m_j_cpu0_sa_dqs_dn(8)';
NODE_NAME     U25 AF18
 '@T6G_MB_LIB.T6G(SCH_1):PAGE19_I159@PURE_QUANTA.GENOA_SP5(CHIPS)':
 'MJA_DQS_L8': CDS_PINID='MJA_DQS_L8';
NODE_NAME     J68 189
 '@T6G_MB_LIB.T6G(SCH_1):PAGE94_I236@PURE_QUANTA.SCONN288_DDR506112002KQ(CHIPS)':
 'DQS8_A_C||TDQS8_A_C': CDS_PINID='\dqs8_a_c||tdqs8_a_c\';
NET_NAME
'M_J_CPU0_SA_DQS_DN<9>'
 '@T6G_MB_LIB.T6G(SCH_1):M_J_CPU0_SA_DQS_DN'<9>:
 C_SIGNAL='@t6g_mb_lib.t6g(sch_1):m_j_cpu0_sa_dqs_dn(9)';
NODE_NAME     U25 AM18
 '@T6G_MB_LIB.T6G(SCH_1):PAGE19_I159@PURE_QUANTA.GENOA_SP5(CHIPS)':
 'MJA_DQS_L9': CDS_PINID='MJA_DQS_L9';
NODE_NAME     J68 200
 '@T6G_MB_LIB.T6G(SCH_1):PAGE94_I236@PURE_QUANTA.SCONN288_DDR506112002KQ(CHIPS)':
 'DQS9_A_C||TDQS9_A_C': CDS_PINID='\dqs9_a_c||tdqs9_a_c\';
NET_NAME
'M_J_CPU0_SA_DQS_DP<0>'
 '@T6G_MB_LIB.T6G(SCH_1):M_J_CPU0_SA_DQS_DP'<0>:
 C_SIGNAL='@t6g_mb_lib.t6g(sch_1):m_j_cpu0_sa_dqs_dp(0)';
NODE_NAME     U25 G16
 '@T6G_MB_LIB.T6G(SCH_1):PAGE19_I159@PURE_QUANTA.GENOA_SP5(CHIPS)':
 'MJA_DQS_H0': CDS_PINID='MJA_DQS_H0';
NODE_NAME     J68 11
 '@T6G_MB_LIB.T6G(SCH_1):PAGE94_I236@PURE_QUANTA.SCONN288_DDR506112002KQ(CHIPS)':
 'DQS0_A_T': CDS_PINID='DQS0_A_T';
NET_NAME
'M_J_CPU0_SA_DQS_DP<1>'
 '@T6G_MB_LIB.T6G(SCH_1):M_J_CPU0_SA_DQS_DP'<1>:
 C_SIGNAL='@t6g_mb_lib.t6g(sch_1):m_j_cpu0_sa_dqs_dp(1)';
NODE_NAME     U25 N16
 '@T6G_MB_LIB.T6G(SCH_1):PAGE19_I159@PURE_QUANTA.GENOA_SP5(CHIPS)':
 'MJA_DQS_H1': CDS_PINID='MJA_DQS_H1';
NODE_NAME     J68 22
 '@T6G_MB_LIB.T6G(SCH_1):PAGE94_I236@PURE_QUANTA.SCONN288_DDR506112002KQ(CHIPS)':
 'DQS1_A_T': CDS_PINID='DQS1_A_T';
NET_NAME
'M_J_CPU0_SA_DQS_DP<2>'
 '@T6G_MB_LIB.T6G(SCH_1):M_J_CPU0_SA_DQS_DP'<2>:
 C_SIGNAL='@t6g_mb_lib.t6g(sch_1):m_j_cpu0_sa_dqs_dp(2)';
NODE_NAME     U25 W16
 '@T6G_MB_LIB.T6G(SCH_1):PAGE19_I159@PURE_QUANTA.GENOA_SP5(CHIPS)':
 'MJA_DQS_H2': CDS_PINID='MJA_DQS_H2';
NODE_NAME     J68 33
 '@T6G_MB_LIB.T6G(SCH_1):PAGE94_I236@PURE_QUANTA.SCONN288_DDR506112002KQ(CHIPS)':
 'DQS2_A_T': CDS_PINID='DQS2_A_T';
NET_NAME
'M_J_CPU0_SA_DQS_DP<3>'
 '@T6G_MB_LIB.T6G(SCH_1):M_J_CPU0_SA_DQS_DP'<3>:
 C_SIGNAL='@t6g_mb_lib.t6g(sch_1):m_j_cpu0_sa_dqs_dp(3)';
NODE_NAME     U25 AE16
 '@T6G_MB_LIB.T6G(SCH_1):PAGE19_I159@PURE_QUANTA.GENOA_SP5(CHIPS)':
 'MJA_DQS_H3': CDS_PINID='MJA_DQS_H3';
NODE_NAME     J68 44
 '@T6G_MB_LIB.T6G(SCH_1):PAGE94_I236@PURE_QUANTA.SCONN288_DDR506112002KQ(CHIPS)':
 'DQS3_A_T': CDS_PINID='DQS3_A_T';
NET_NAME
'M_J_CPU0_SA_DQS_DP<4>'
 '@T6G_MB_LIB.T6G(SCH_1):M_J_CPU0_SA_DQS_DP'<4>:
 C_SIGNAL='@t6g_mb_lib.t6g(sch_1):m_j_cpu0_sa_dqs_dp(4)';
NODE_NAME     U25 AL16
 '@T6G_MB_LIB.T6G(SCH_1):PAGE19_I159@PURE_QUANTA.GENOA_SP5(CHIPS)':
 'MJA_DQS_H4': CDS_PINID='MJA_DQS_H4';
NODE_NAME     J68 55
 '@T6G_MB_LIB.T6G(SCH_1):PAGE94_I236@PURE_QUANTA.SCONN288_DDR506112002KQ(CHIPS)':
 'DQS4_A_T': CDS_PINID='DQS4_A_T';
NET_NAME
'M_J_CPU0_SA_DQS_DP<5>'
 '@T6G_MB_LIB.T6G(SCH_1):M_J_CPU0_SA_DQS_DP'<5>:
 C_SIGNAL='@t6g_mb_lib.t6g(sch_1):m_j_cpu0_sa_dqs_dp(5)';
NODE_NAME     U25 J17
 '@T6G_MB_LIB.T6G(SCH_1):PAGE19_I159@PURE_QUANTA.GENOA_SP5(CHIPS)':
 'MJA_DQS_H5': CDS_PINID='MJA_DQS_H5';
NODE_NAME     J68 157
 '@T6G_MB_LIB.T6G(SCH_1):PAGE94_I236@PURE_QUANTA.SCONN288_DDR506112002KQ(CHIPS)':
 'DQS5_A_T||TDQS5_A_T': CDS_PINID='\dqs5_a_t||tdqs5_a_t\';
NET_NAME
'M_J_CPU0_SA_DQS_DP<6>'
 '@T6G_MB_LIB.T6G(SCH_1):M_J_CPU0_SA_DQS_DP'<6>:
 C_SIGNAL='@t6g_mb_lib.t6g(sch_1):m_j_cpu0_sa_dqs_dp(6)';
NODE_NAME     U25 R17
 '@T6G_MB_LIB.T6G(SCH_1):PAGE19_I159@PURE_QUANTA.GENOA_SP5(CHIPS)':
 'MJA_DQS_H6': CDS_PINID='MJA_DQS_H6';
NODE_NAME     J68 168
 '@T6G_MB_LIB.T6G(SCH_1):PAGE94_I236@PURE_QUANTA.SCONN288_DDR506112002KQ(CHIPS)':
 'DQS6_A_T||TDQS6_A_T': CDS_PINID='\dqs6_a_t||tdqs6_a_t\';
NET_NAME
'M_J_CPU0_SA_DQS_DP<7>'
 '@T6G_MB_LIB.T6G(SCH_1):M_J_CPU0_SA_DQS_DP'<7>:
 C_SIGNAL='@t6g_mb_lib.t6g(sch_1):m_j_cpu0_sa_dqs_dp(7)';
NODE_NAME     U25 AA17
 '@T6G_MB_LIB.T6G(SCH_1):PAGE19_I159@PURE_QUANTA.GENOA_SP5(CHIPS)':
 'MJA_DQS_H7': CDS_PINID='MJA_DQS_H7';
NODE_NAME     J68 179
 '@T6G_MB_LIB.T6G(SCH_1):PAGE94_I236@PURE_QUANTA.SCONN288_DDR506112002KQ(CHIPS)':
 'DQS7_A_T||TDQS7_A_T': CDS_PINID='\dqs7_a_t||tdqs7_a_t\';
NET_NAME
'M_J_CPU0_SA_DQS_DP<8>'
 '@T6G_MB_LIB.T6G(SCH_1):M_J_CPU0_SA_DQS_DP'<8>:
 C_SIGNAL='@t6g_mb_lib.t6g(sch_1):m_j_cpu0_sa_dqs_dp(8)';
NODE_NAME     U25 AG17
 '@T6G_MB_LIB.T6G(SCH_1):PAGE19_I159@PURE_QUANTA.GENOA_SP5(CHIPS)':
 'MJA_DQS_H8': CDS_PINID='MJA_DQS_H8';
NODE_NAME     J68 190
 '@T6G_MB_LIB.T6G(SCH_1):PAGE94_I236@PURE_QUANTA.SCONN288_DDR506112002KQ(CHIPS)':
 'DQS8_A_T||TDQS8_A_T': CDS_PINID='\dqs8_a_t||tdqs8_a_t\';
NET_NAME
'M_J_CPU0_SA_DQS_DP<9>'
 '@T6G_MB_LIB.T6G(SCH_1):M_J_CPU0_SA_DQS_DP'<9>:
 C_SIGNAL='@t6g_mb_lib.t6g(sch_1):m_j_cpu0_sa_dqs_dp(9)';
NODE_NAME     U25 AN17
 '@T6G_MB_LIB.T6G(SCH_1):PAGE19_I159@PURE_QUANTA.GENOA_SP5(CHIPS)':
 'MJA_DQS_H9': CDS_PINID='MJA_DQS_H9';
NODE_NAME     J68 201
 '@T6G_MB_LIB.T6G(SCH_1):PAGE94_I236@PURE_QUANTA.SCONN288_DDR506112002KQ(CHIPS)':
 'DQS9_A_T||TDQS9_A_T': CDS_PINID='\dqs9_a_t||tdqs9_a_t\';
NET_NAME
'M_J_CPU0_SA_PAR'
 '@T6G_MB_LIB.T6G(SCH_1):M_J_CPU0_SA_PAR':
 C_SIGNAL='@t6g_mb_lib.t6g(sch_1):m_j_cpu0_sa_par';
NODE_NAME     U25 BC17
 '@T6G_MB_LIB.T6G(SCH_1):PAGE19_I159@PURE_QUANTA.GENOA_SP5(CHIPS)':
 'MJA_PAR': CDS_PINID='MJA_PAR';
NODE_NAME     J68 74
 '@T6G_MB_LIB.T6G(SCH_1):PAGE94_I22@PURE_QUANTA.SCONN288_DDR506112002KQ(CHIPS)':
 'PAR_A': CDS_PINID='PAR_A';
NET_NAME
'M_J_CPU0_SA_RSP<0>'
 '@T6G_MB_LIB.T6G(SCH_1):M_J_CPU0_SA_RSP'<0>:
 C_SIGNAL='@t6g_mb_lib.t6g(sch_1):m_j_cpu0_sa_rsp(0)';
NODE_NAME     U25 BN17
 '@T6G_MB_LIB.T6G(SCH_1):PAGE19_I159@PURE_QUANTA.GENOA_SP5(CHIPS)':
 'MJA0_RSP_L': CDS_PINID='MJA0_RSP_L';
NODE_NAME     J68 86
 '@T6G_MB_LIB.T6G(SCH_1):PAGE94_I22@PURE_QUANTA.SCONN288_DDR506112002KQ(CHIPS)':
 'LBD||RSP_A_N': CDS_PINID='\lbd||rsp_a_n\';
NET_NAME
'M_J_CPU0_SB_CA<0>'
 '@T6G_MB_LIB.T6G(SCH_1):M_J_CPU0_SB_CA'<0>:
 C_SIGNAL='@t6g_mb_lib.t6g(sch_1):m_j_cpu0_sb_ca(0)';
NODE_NAME     U25 BG17
 '@T6G_MB_LIB.T6G(SCH_1):PAGE19_I159@PURE_QUANTA.GENOA_SP5(CHIPS)':
 'MJB_CA0': CDS_PINID='MJB_CA0';
NODE_NAME     J68 76
 '@T6G_MB_LIB.T6G(SCH_1):PAGE94_I22@PURE_QUANTA.SCONN288_DDR506112002KQ(CHIPS)':
 'CA0_B': CDS_PINID='CA0_B';
NET_NAME
'M_J_CPU0_SB_CA<1>'
 '@T6G_MB_LIB.T6G(SCH_1):M_J_CPU0_SB_CA'<1>:
 C_SIGNAL='@t6g_mb_lib.t6g(sch_1):m_j_cpu0_sb_ca(1)';
NODE_NAME     U25 BH18
 '@T6G_MB_LIB.T6G(SCH_1):PAGE19_I159@PURE_QUANTA.GENOA_SP5(CHIPS)':
 'MJB_CA1': CDS_PINID='MJB_CA1';
NODE_NAME     J68 221
 '@T6G_MB_LIB.T6G(SCH_1):PAGE94_I22@PURE_QUANTA.SCONN288_DDR506112002KQ(CHIPS)':
 'CA1_B': CDS_PINID='CA1_B';
NET_NAME
'M_J_CPU0_SB_CA<2>'
 '@T6G_MB_LIB.T6G(SCH_1):M_J_CPU0_SB_CA'<2>:
 C_SIGNAL='@t6g_mb_lib.t6g(sch_1):m_j_cpu0_sb_ca(2)';
NODE_NAME     U25 BH16
 '@T6G_MB_LIB.T6G(SCH_1):PAGE19_I159@PURE_QUANTA.GENOA_SP5(CHIPS)':
 'MJB_CA2': CDS_PINID='MJB_CA2';
NODE_NAME     J68 78
 '@T6G_MB_LIB.T6G(SCH_1):PAGE94_I22@PURE_QUANTA.SCONN288_DDR506112002KQ(CHIPS)':
 'CA2_B': CDS_PINID='CA2_B';
NET_NAME
'M_J_CPU0_SB_CA<3>'
 '@T6G_MB_LIB.T6G(SCH_1):M_J_CPU0_SB_CA'<3>:
 C_SIGNAL='@t6g_mb_lib.t6g(sch_1):m_j_cpu0_sb_ca(3)';
NODE_NAME     U25 BJ16
 '@T6G_MB_LIB.T6G(SCH_1):PAGE19_I159@PURE_QUANTA.GENOA_SP5(CHIPS)':
 'MJB_CA3': CDS_PINID='MJB_CA3';
NODE_NAME     J68 223
 '@T6G_MB_LIB.T6G(SCH_1):PAGE94_I22@PURE_QUANTA.SCONN288_DDR506112002KQ(CHIPS)':
 'CA3_B': CDS_PINID='CA3_B';
NET_NAME
'M_J_CPU0_SB_CA<4>'
 '@T6G_MB_LIB.T6G(SCH_1):M_J_CPU0_SB_CA'<4>:
 C_SIGNAL='@t6g_mb_lib.t6g(sch_1):m_j_cpu0_sb_ca(4)';
NODE_NAME     U25 BJ17
 '@T6G_MB_LIB.T6G(SCH_1):PAGE19_I159@PURE_QUANTA.GENOA_SP5(CHIPS)':
 'MJB_CA4': CDS_PINID='MJB_CA4';
NODE_NAME     J68 80
 '@T6G_MB_LIB.T6G(SCH_1):PAGE94_I22@PURE_QUANTA.SCONN288_DDR506112002KQ(CHIPS)':
 'CA4_B': CDS_PINID='CA4_B';
NET_NAME
'M_J_CPU0_SB_CA<5>'
 '@T6G_MB_LIB.T6G(SCH_1):M_J_CPU0_SB_CA'<5>:
 C_SIGNAL='@t6g_mb_lib.t6g(sch_1):m_j_cpu0_sb_ca(5)';
NODE_NAME     U25 BK18
 '@T6G_MB_LIB.T6G(SCH_1):PAGE19_I159@PURE_QUANTA.GENOA_SP5(CHIPS)':
 'MJB_CA5': CDS_PINID='MJB_CA5';
NODE_NAME     J68 225
 '@T6G_MB_LIB.T6G(SCH_1):PAGE94_I22@PURE_QUANTA.SCONN288_DDR506112002KQ(CHIPS)':
 'CA5_B': CDS_PINID='CA5_B';
NET_NAME
'M_J_CPU0_SB_CA<6>'
 '@T6G_MB_LIB.T6G(SCH_1):M_J_CPU0_SB_CA'<6>:
 C_SIGNAL='@t6g_mb_lib.t6g(sch_1):m_j_cpu0_sb_ca(6)';
NODE_NAME     U25 BK16
 '@T6G_MB_LIB.T6G(SCH_1):PAGE19_I159@PURE_QUANTA.GENOA_SP5(CHIPS)':
 'MJB_CA6': CDS_PINID='MJB_CA6';
NODE_NAME     J68 82
 '@T6G_MB_LIB.T6G(SCH_1):PAGE94_I22@PURE_QUANTA.SCONN288_DDR506112002KQ(CHIPS)':
 'CA6_B': CDS_PINID='CA6_B';
NET_NAME
'M_J_CPU0_SB_CB<0>'
 '@T6G_MB_LIB.T6G(SCH_1):M_J_CPU0_SB_CB'<0>:
 C_SIGNAL='@t6g_mb_lib.t6g(sch_1):m_j_cpu0_sb_cb(0)';
NODE_NAME     U25 BY16
 '@T6G_MB_LIB.T6G(SCH_1):PAGE19_I159@PURE_QUANTA.GENOA_SP5(CHIPS)':
 'MJB_CHECK0': CDS_PINID='MJB_CHECK0';
NODE_NAME     J68 96
 '@T6G_MB_LIB.T6G(SCH_1):PAGE94_I22@PURE_QUANTA.SCONN288_DDR506112002KQ(CHIPS)':
 'CB0_B': CDS_PINID='CB0_B';
NET_NAME
'M_J_CPU0_SB_CB<1>'
 '@T6G_MB_LIB.T6G(SCH_1):M_J_CPU0_SB_CB'<1>:
 C_SIGNAL='@t6g_mb_lib.t6g(sch_1):m_j_cpu0_sb_cb(1)';
NODE_NAME     U25 CA17
 '@T6G_MB_LIB.T6G(SCH_1):PAGE19_I159@PURE_QUANTA.GENOA_SP5(CHIPS)':
 'MJB_CHECK1': CDS_PINID='MJB_CHECK1';
NODE_NAME     J68 98
 '@T6G_MB_LIB.T6G(SCH_1):PAGE94_I22@PURE_QUANTA.SCONN288_DDR506112002KQ(CHIPS)':
 'CB1_B': CDS_PINID='CB1_B';
NET_NAME
'M_J_CPU0_SB_CB<2>'
 '@T6G_MB_LIB.T6G(SCH_1):M_J_CPU0_SB_CB'<2>:
 C_SIGNAL='@t6g_mb_lib.t6g(sch_1):m_j_cpu0_sb_cb(2)';
NODE_NAME     U25 CA16
 '@T6G_MB_LIB.T6G(SCH_1):PAGE19_I159@PURE_QUANTA.GENOA_SP5(CHIPS)':
 'MJB_CHECK2': CDS_PINID='MJB_CHECK2';
NODE_NAME     J68 241
 '@T6G_MB_LIB.T6G(SCH_1):PAGE94_I22@PURE_QUANTA.SCONN288_DDR506112002KQ(CHIPS)':
 'CB2_B': CDS_PINID='CB2_B';
NET_NAME
'M_J_CPU0_SB_CB<3>'
 '@T6G_MB_LIB.T6G(SCH_1):M_J_CPU0_SB_CB'<3>:
 C_SIGNAL='@t6g_mb_lib.t6g(sch_1):m_j_cpu0_sb_cb(3)';
NODE_NAME     U25 CB18
 '@T6G_MB_LIB.T6G(SCH_1):PAGE19_I159@PURE_QUANTA.GENOA_SP5(CHIPS)':
 'MJB_CHECK3': CDS_PINID='MJB_CHECK3';
NODE_NAME     J68 243
 '@T6G_MB_LIB.T6G(SCH_1):PAGE94_I22@PURE_QUANTA.SCONN288_DDR506112002KQ(CHIPS)':
 'CB3_B': CDS_PINID='CB3_B';
NET_NAME
'M_J_CPU0_SB_CB<4>'
 '@T6G_MB_LIB.T6G(SCH_1):M_J_CPU0_SB_CB'<4>:
 C_SIGNAL='@t6g_mb_lib.t6g(sch_1):m_j_cpu0_sb_cb(4)';
NODE_NAME     U25 BT16
 '@T6G_MB_LIB.T6G(SCH_1):PAGE19_I159@PURE_QUANTA.GENOA_SP5(CHIPS)':
 'MJB_CHECK4': CDS_PINID='MJB_CHECK4';
NODE_NAME     J68 89
 '@T6G_MB_LIB.T6G(SCH_1):PAGE94_I22@PURE_QUANTA.SCONN288_DDR506112002KQ(CHIPS)':
 'CB4_B': CDS_PINID='CB4_B';
NET_NAME
'M_J_CPU0_SB_CB<5>'
 '@T6G_MB_LIB.T6G(SCH_1):M_J_CPU0_SB_CB'<5>:
 C_SIGNAL='@t6g_mb_lib.t6g(sch_1):m_j_cpu0_sb_cb(5)';
NODE_NAME     U25 BU17
 '@T6G_MB_LIB.T6G(SCH_1):PAGE19_I159@PURE_QUANTA.GENOA_SP5(CHIPS)':
 'MJB_CHECK5': CDS_PINID='MJB_CHECK5';
NODE_NAME     J68 91
 '@T6G_MB_LIB.T6G(SCH_1):PAGE94_I22@PURE_QUANTA.SCONN288_DDR506112002KQ(CHIPS)':
 'CB5_B': CDS_PINID='CB5_B';
NET_NAME
'M_J_CPU0_SB_CB<6>'
 '@T6G_MB_LIB.T6G(SCH_1):M_J_CPU0_SB_CB'<6>:
 C_SIGNAL='@t6g_mb_lib.t6g(sch_1):m_j_cpu0_sb_cb(6)';
NODE_NAME     U25 BU16
 '@T6G_MB_LIB.T6G(SCH_1):PAGE19_I159@PURE_QUANTA.GENOA_SP5(CHIPS)':
 'MJB_CHECK6': CDS_PINID='MJB_CHECK6';
NODE_NAME     J68 234
 '@T6G_MB_LIB.T6G(SCH_1):PAGE94_I22@PURE_QUANTA.SCONN288_DDR506112002KQ(CHIPS)':
 'CB6_B': CDS_PINID='CB6_B';
NET_NAME
'M_J_CPU0_SB_CB<7>'
 '@T6G_MB_LIB.T6G(SCH_1):M_J_CPU0_SB_CB'<7>:
 C_SIGNAL='@t6g_mb_lib.t6g(sch_1):m_j_cpu0_sb_cb(7)';
NODE_NAME     U25 BV18
 '@T6G_MB_LIB.T6G(SCH_1):PAGE19_I159@PURE_QUANTA.GENOA_SP5(CHIPS)':
 'MJB_CHECK7': CDS_PINID='MJB_CHECK7';
NODE_NAME     J68 236
 '@T6G_MB_LIB.T6G(SCH_1):PAGE94_I22@PURE_QUANTA.SCONN288_DDR506112002KQ(CHIPS)':
 'CB7_B': CDS_PINID='CB7_B';
NET_NAME
'M_J_CPU0_SB_CS_N<0>'
 '@T6G_MB_LIB.T6G(SCH_1):M_J_CPU0_SB_CS_N'<0>:
 C_SIGNAL='@t6g_mb_lib.t6g(sch_1):m_j_cpu0_sb_cs_n(0)';
NODE_NAME     U25 BM18
 '@T6G_MB_LIB.T6G(SCH_1):PAGE19_I159@PURE_QUANTA.GENOA_SP5(CHIPS)':
 'MJB0_CS_L0': CDS_PINID='MJB0_CS_L0';
NODE_NAME     J68 84
 '@T6G_MB_LIB.T6G(SCH_1):PAGE94_I22@PURE_QUANTA.SCONN288_DDR506112002KQ(CHIPS)':
 'CS0_B_N': CDS_PINID='CS0_B_N';
NET_NAME
'M_J_CPU0_SB_CS_N<1>'
 '@T6G_MB_LIB.T6G(SCH_1):M_J_CPU0_SB_CS_N'<1>:
 C_SIGNAL='@t6g_mb_lib.t6g(sch_1):m_j_cpu0_sb_cs_n(1)';
NODE_NAME     U25 BN16
 '@T6G_MB_LIB.T6G(SCH_1):PAGE19_I159@PURE_QUANTA.GENOA_SP5(CHIPS)':
 'MJB0_CS_L1': CDS_PINID='MJB0_CS_L1';
NODE_NAME     J68 229
 '@T6G_MB_LIB.T6G(SCH_1):PAGE94_I22@PURE_QUANTA.SCONN288_DDR506112002KQ(CHIPS)':
 'CS1_B_N': CDS_PINID='CS1_B_N';
NET_NAME
'M_J_CPU0_SB_DQ<0>'
 '@T6G_MB_LIB.T6G(SCH_1):M_J_CPU0_SB_DQ'<0>:
 C_SIGNAL='@t6g_mb_lib.t6g(sch_1):m_j_cpu0_sb_dq(0)';
NODE_NAME     U25 CB16
 '@T6G_MB_LIB.T6G(SCH_1):PAGE19_I159@PURE_QUANTA.GENOA_SP5(CHIPS)':
 'MJB_DATA0': CDS_PINID='MJB_DATA0';
NODE_NAME     J68 100
 '@T6G_MB_LIB.T6G(SCH_1):PAGE94_I22@PURE_QUANTA.SCONN288_DDR506112002KQ(CHIPS)':
 'DQ0_B': CDS_PINID='DQ0_B';
NET_NAME
'M_J_CPU0_SB_DQ<10>'
 '@T6G_MB_LIB.T6G(SCH_1):M_J_CPU0_SB_DQ'<10>:
 C_SIGNAL='@t6g_mb_lib.t6g(sch_1):m_j_cpu0_sb_dq(10)';
NODE_NAME     U25 CJ16
 '@T6G_MB_LIB.T6G(SCH_1):PAGE19_I159@PURE_QUANTA.GENOA_SP5(CHIPS)':
 'MJB_DATA10': CDS_PINID='MJB_DATA10';
NODE_NAME     J68 256
 '@T6G_MB_LIB.T6G(SCH_1):PAGE94_I22@PURE_QUANTA.SCONN288_DDR506112002KQ(CHIPS)':
 'DQ10_B': CDS_PINID='DQ10_B';
NET_NAME
'M_J_CPU0_SB_DQ<11>'
 '@T6G_MB_LIB.T6G(SCH_1):M_J_CPU0_SB_DQ'<11>:
 C_SIGNAL='@t6g_mb_lib.t6g(sch_1):m_j_cpu0_sb_dq(11)';
NODE_NAME     U25 CK18
 '@T6G_MB_LIB.T6G(SCH_1):PAGE19_I159@PURE_QUANTA.GENOA_SP5(CHIPS)':
 'MJB_DATA11': CDS_PINID='MJB_DATA11';
NODE_NAME     J68 258
 '@T6G_MB_LIB.T6G(SCH_1):PAGE94_I22@PURE_QUANTA.SCONN288_DDR506112002KQ(CHIPS)':
 'DQ11_B': CDS_PINID='DQ11_B';
NET_NAME
'M_J_CPU0_SB_DQ<12>'
 '@T6G_MB_LIB.T6G(SCH_1):M_J_CPU0_SB_DQ'<12>:
 C_SIGNAL='@t6g_mb_lib.t6g(sch_1):m_j_cpu0_sb_dq(12)';
NODE_NAME     U25 CM16
 '@T6G_MB_LIB.T6G(SCH_1):PAGE19_I159@PURE_QUANTA.GENOA_SP5(CHIPS)':
 'MJB_DATA12': CDS_PINID='MJB_DATA12';
NODE_NAME     J68 118
 '@T6G_MB_LIB.T6G(SCH_1):PAGE94_I22@PURE_QUANTA.SCONN288_DDR506112002KQ(CHIPS)':
 'DQ12_B': CDS_PINID='DQ12_B';
NET_NAME
'M_J_CPU0_SB_DQ<13>'
 '@T6G_MB_LIB.T6G(SCH_1):M_J_CPU0_SB_DQ'<13>:
 C_SIGNAL='@t6g_mb_lib.t6g(sch_1):m_j_cpu0_sb_dq(13)';
NODE_NAME     U25 CN17
 '@T6G_MB_LIB.T6G(SCH_1):PAGE19_I159@PURE_QUANTA.GENOA_SP5(CHIPS)':
 'MJB_DATA13': CDS_PINID='MJB_DATA13';
NODE_NAME     J68 120
 '@T6G_MB_LIB.T6G(SCH_1):PAGE94_I22@PURE_QUANTA.SCONN288_DDR506112002KQ(CHIPS)':
 'DQ13_B': CDS_PINID='DQ13_B';
NET_NAME
'M_J_CPU0_SB_DQ<14>'
 '@T6G_MB_LIB.T6G(SCH_1):M_J_CPU0_SB_DQ'<14>:
 C_SIGNAL='@t6g_mb_lib.t6g(sch_1):m_j_cpu0_sb_dq(14)';
NODE_NAME     U25 CN16
 '@T6G_MB_LIB.T6G(SCH_1):PAGE19_I159@PURE_QUANTA.GENOA_SP5(CHIPS)':
 'MJB_DATA14': CDS_PINID='MJB_DATA14';
NODE_NAME     J68 263
 '@T6G_MB_LIB.T6G(SCH_1):PAGE94_I22@PURE_QUANTA.SCONN288_DDR506112002KQ(CHIPS)':
 'DQ14_B': CDS_PINID='DQ14_B';
NET_NAME
'M_J_CPU0_SB_DQ<15>'
 '@T6G_MB_LIB.T6G(SCH_1):M_J_CPU0_SB_DQ'<15>:
 C_SIGNAL='@t6g_mb_lib.t6g(sch_1):m_j_cpu0_sb_dq(15)';
NODE_NAME     U25 CP18
 '@T6G_MB_LIB.T6G(SCH_1):PAGE19_I159@PURE_QUANTA.GENOA_SP5(CHIPS)':
 'MJB_DATA15': CDS_PINID='MJB_DATA15';
NODE_NAME     J68 265
 '@T6G_MB_LIB.T6G(SCH_1):PAGE94_I22@PURE_QUANTA.SCONN288_DDR506112002KQ(CHIPS)':
 'DQ15_B': CDS_PINID='DQ15_B';
NET_NAME
'M_J_CPU0_SB_DQ<16>'
 '@T6G_MB_LIB.T6G(SCH_1):M_J_CPU0_SB_DQ'<16>:
 C_SIGNAL='@t6g_mb_lib.t6g(sch_1):m_j_cpu0_sb_dq(16)';
NODE_NAME     U25 CP16
 '@T6G_MB_LIB.T6G(SCH_1):PAGE19_I159@PURE_QUANTA.GENOA_SP5(CHIPS)':
 'MJB_DATA16': CDS_PINID='MJB_DATA16';
NODE_NAME     J68 122
 '@T6G_MB_LIB.T6G(SCH_1):PAGE94_I22@PURE_QUANTA.SCONN288_DDR506112002KQ(CHIPS)':
 'DQ16_B': CDS_PINID='DQ16_B';
NET_NAME
'M_J_CPU0_SB_DQ<17>'
 '@T6G_MB_LIB.T6G(SCH_1):M_J_CPU0_SB_DQ'<17>:
 C_SIGNAL='@t6g_mb_lib.t6g(sch_1):m_j_cpu0_sb_dq(17)';
NODE_NAME     U25 CR17
 '@T6G_MB_LIB.T6G(SCH_1):PAGE19_I159@PURE_QUANTA.GENOA_SP5(CHIPS)':
 'MJB_DATA17': CDS_PINID='MJB_DATA17';
NODE_NAME     J68 124
 '@T6G_MB_LIB.T6G(SCH_1):PAGE94_I22@PURE_QUANTA.SCONN288_DDR506112002KQ(CHIPS)':
 'DQ17_B': CDS_PINID='DQ17_B';
NET_NAME
'M_J_CPU0_SB_DQ<18>'
 '@T6G_MB_LIB.T6G(SCH_1):M_J_CPU0_SB_DQ'<18>:
 C_SIGNAL='@t6g_mb_lib.t6g(sch_1):m_j_cpu0_sb_dq(18)';
NODE_NAME     U25 CR16
 '@T6G_MB_LIB.T6G(SCH_1):PAGE19_I159@PURE_QUANTA.GENOA_SP5(CHIPS)':
 'MJB_DATA18': CDS_PINID='MJB_DATA18';
NODE_NAME     J68 267
 '@T6G_MB_LIB.T6G(SCH_1):PAGE94_I22@PURE_QUANTA.SCONN288_DDR506112002KQ(CHIPS)':
 'DQ18_B': CDS_PINID='DQ18_B';
NET_NAME
'M_J_CPU0_SB_DQ<19>'
 '@T6G_MB_LIB.T6G(SCH_1):M_J_CPU0_SB_DQ'<19>:
 C_SIGNAL='@t6g_mb_lib.t6g(sch_1):m_j_cpu0_sb_dq(19)';
NODE_NAME     U25 CT18
 '@T6G_MB_LIB.T6G(SCH_1):PAGE19_I159@PURE_QUANTA.GENOA_SP5(CHIPS)':
 'MJB_DATA19': CDS_PINID='MJB_DATA19';
NODE_NAME     J68 269
 '@T6G_MB_LIB.T6G(SCH_1):PAGE94_I22@PURE_QUANTA.SCONN288_DDR506112002KQ(CHIPS)':
 'DQ19_B': CDS_PINID='DQ19_B';
NET_NAME
'M_J_CPU0_SB_DQ<1>'
 '@T6G_MB_LIB.T6G(SCH_1):M_J_CPU0_SB_DQ'<1>:
 C_SIGNAL='@t6g_mb_lib.t6g(sch_1):m_j_cpu0_sb_dq(1)';
NODE_NAME     U25 CC17
 '@T6G_MB_LIB.T6G(SCH_1):PAGE19_I159@PURE_QUANTA.GENOA_SP5(CHIPS)':
 'MJB_DATA1': CDS_PINID='MJB_DATA1';
NODE_NAME     J68 102
 '@T6G_MB_LIB.T6G(SCH_1):PAGE94_I22@PURE_QUANTA.SCONN288_DDR506112002KQ(CHIPS)':
 'DQ1_B': CDS_PINID='DQ1_B';
NET_NAME
'M_J_CPU0_SB_DQ<20>'
 '@T6G_MB_LIB.T6G(SCH_1):M_J_CPU0_SB_DQ'<20>:
 C_SIGNAL='@t6g_mb_lib.t6g(sch_1):m_j_cpu0_sb_dq(20)';
NODE_NAME     U25 CV16
 '@T6G_MB_LIB.T6G(SCH_1):PAGE19_I159@PURE_QUANTA.GENOA_SP5(CHIPS)':
 'MJB_DATA20': CDS_PINID='MJB_DATA20';
NODE_NAME     J68 129
 '@T6G_MB_LIB.T6G(SCH_1):PAGE94_I22@PURE_QUANTA.SCONN288_DDR506112002KQ(CHIPS)':
 'DQ20_B': CDS_PINID='DQ20_B';
NET_NAME
'M_J_CPU0_SB_DQ<21>'
 '@T6G_MB_LIB.T6G(SCH_1):M_J_CPU0_SB_DQ'<21>:
 C_SIGNAL='@t6g_mb_lib.t6g(sch_1):m_j_cpu0_sb_dq(21)';
NODE_NAME     U25 CW17
 '@T6G_MB_LIB.T6G(SCH_1):PAGE19_I159@PURE_QUANTA.GENOA_SP5(CHIPS)':
 'MJB_DATA21': CDS_PINID='MJB_DATA21';
NODE_NAME     J68 131
 '@T6G_MB_LIB.T6G(SCH_1):PAGE94_I22@PURE_QUANTA.SCONN288_DDR506112002KQ(CHIPS)':
 'DQ21_B': CDS_PINID='DQ21_B';
NET_NAME
'M_J_CPU0_SB_DQ<22>'
 '@T6G_MB_LIB.T6G(SCH_1):M_J_CPU0_SB_DQ'<22>:
 C_SIGNAL='@t6g_mb_lib.t6g(sch_1):m_j_cpu0_sb_dq(22)';
NODE_NAME     U25 CW16
 '@T6G_MB_LIB.T6G(SCH_1):PAGE19_I159@PURE_QUANTA.GENOA_SP5(CHIPS)':
 'MJB_DATA22': CDS_PINID='MJB_DATA22';
NODE_NAME     J68 274
 '@T6G_MB_LIB.T6G(SCH_1):PAGE94_I22@PURE_QUANTA.SCONN288_DDR506112002KQ(CHIPS)':
 'DQ22_B': CDS_PINID='DQ22_B';
NET_NAME
'M_J_CPU0_SB_DQ<23>'
 '@T6G_MB_LIB.T6G(SCH_1):M_J_CPU0_SB_DQ'<23>:
 C_SIGNAL='@t6g_mb_lib.t6g(sch_1):m_j_cpu0_sb_dq(23)';
NODE_NAME     U25 CY18
 '@T6G_MB_LIB.T6G(SCH_1):PAGE19_I159@PURE_QUANTA.GENOA_SP5(CHIPS)':
 'MJB_DATA23': CDS_PINID='MJB_DATA23';
NODE_NAME     J68 276
 '@T6G_MB_LIB.T6G(SCH_1):PAGE94_I22@PURE_QUANTA.SCONN288_DDR506112002KQ(CHIPS)':
 'DQ23_B': CDS_PINID='DQ23_B';
NET_NAME
'M_J_CPU0_SB_DQ<24>'
 '@T6G_MB_LIB.T6G(SCH_1):M_J_CPU0_SB_DQ'<24>:
 C_SIGNAL='@t6g_mb_lib.t6g(sch_1):m_j_cpu0_sb_dq(24)';
NODE_NAME     U25 CY16
 '@T6G_MB_LIB.T6G(SCH_1):PAGE19_I159@PURE_QUANTA.GENOA_SP5(CHIPS)':
 'MJB_DATA24': CDS_PINID='MJB_DATA24';
NODE_NAME     J68 133
 '@T6G_MB_LIB.T6G(SCH_1):PAGE94_I22@PURE_QUANTA.SCONN288_DDR506112002KQ(CHIPS)':
 'DQ24_B': CDS_PINID='DQ24_B';
NET_NAME
'M_J_CPU0_SB_DQ<25>'
 '@T6G_MB_LIB.T6G(SCH_1):M_J_CPU0_SB_DQ'<25>:
 C_SIGNAL='@t6g_mb_lib.t6g(sch_1):m_j_cpu0_sb_dq(25)';
NODE_NAME     U25 DA17
 '@T6G_MB_LIB.T6G(SCH_1):PAGE19_I159@PURE_QUANTA.GENOA_SP5(CHIPS)':
 'MJB_DATA25': CDS_PINID='MJB_DATA25';
NODE_NAME     J68 135
 '@T6G_MB_LIB.T6G(SCH_1):PAGE94_I22@PURE_QUANTA.SCONN288_DDR506112002KQ(CHIPS)':
 'DQ25_B': CDS_PINID='DQ25_B';
NET_NAME
'M_J_CPU0_SB_DQ<26>'
 '@T6G_MB_LIB.T6G(SCH_1):M_J_CPU0_SB_DQ'<26>:
 C_SIGNAL='@t6g_mb_lib.t6g(sch_1):m_j_cpu0_sb_dq(26)';
NODE_NAME     U25 DA16
 '@T6G_MB_LIB.T6G(SCH_1):PAGE19_I159@PURE_QUANTA.GENOA_SP5(CHIPS)':
 'MJB_DATA26': CDS_PINID='MJB_DATA26';
NODE_NAME     J68 278
 '@T6G_MB_LIB.T6G(SCH_1):PAGE94_I22@PURE_QUANTA.SCONN288_DDR506112002KQ(CHIPS)':
 'DQ26_B': CDS_PINID='DQ26_B';
NET_NAME
'M_J_CPU0_SB_DQ<27>'
 '@T6G_MB_LIB.T6G(SCH_1):M_J_CPU0_SB_DQ'<27>:
 C_SIGNAL='@t6g_mb_lib.t6g(sch_1):m_j_cpu0_sb_dq(27)';
NODE_NAME     U25 DB18
 '@T6G_MB_LIB.T6G(SCH_1):PAGE19_I159@PURE_QUANTA.GENOA_SP5(CHIPS)':
 'MJB_DATA27': CDS_PINID='MJB_DATA27';
NODE_NAME     J68 280
 '@T6G_MB_LIB.T6G(SCH_1):PAGE94_I22@PURE_QUANTA.SCONN288_DDR506112002KQ(CHIPS)':
 'DQ27_B': CDS_PINID='DQ27_B';
NET_NAME
'M_J_CPU0_SB_DQ<28>'
 '@T6G_MB_LIB.T6G(SCH_1):M_J_CPU0_SB_DQ'<28>:
 C_SIGNAL='@t6g_mb_lib.t6g(sch_1):m_j_cpu0_sb_dq(28)';
NODE_NAME     U25 DD16
 '@T6G_MB_LIB.T6G(SCH_1):PAGE19_I159@PURE_QUANTA.GENOA_SP5(CHIPS)':
 'MJB_DATA28': CDS_PINID='MJB_DATA28';
NODE_NAME     J68 140
 '@T6G_MB_LIB.T6G(SCH_1):PAGE94_I22@PURE_QUANTA.SCONN288_DDR506112002KQ(CHIPS)':
 'DQ28_B': CDS_PINID='DQ28_B';
NET_NAME
'M_J_CPU0_SB_DQ<29>'
 '@T6G_MB_LIB.T6G(SCH_1):M_J_CPU0_SB_DQ'<29>:
 C_SIGNAL='@t6g_mb_lib.t6g(sch_1):m_j_cpu0_sb_dq(29)';
NODE_NAME     U25 DE17
 '@T6G_MB_LIB.T6G(SCH_1):PAGE19_I159@PURE_QUANTA.GENOA_SP5(CHIPS)':
 'MJB_DATA29': CDS_PINID='MJB_DATA29';
NODE_NAME     J68 142
 '@T6G_MB_LIB.T6G(SCH_1):PAGE94_I22@PURE_QUANTA.SCONN288_DDR506112002KQ(CHIPS)':
 'DQ29_B': CDS_PINID='DQ29_B';
NET_NAME
'M_J_CPU0_SB_DQ<2>'
 '@T6G_MB_LIB.T6G(SCH_1):M_J_CPU0_SB_DQ'<2>:
 C_SIGNAL='@t6g_mb_lib.t6g(sch_1):m_j_cpu0_sb_dq(2)';
NODE_NAME     U25 CC16
 '@T6G_MB_LIB.T6G(SCH_1):PAGE19_I159@PURE_QUANTA.GENOA_SP5(CHIPS)':
 'MJB_DATA2': CDS_PINID='MJB_DATA2';
NODE_NAME     J68 245
 '@T6G_MB_LIB.T6G(SCH_1):PAGE94_I22@PURE_QUANTA.SCONN288_DDR506112002KQ(CHIPS)':
 'DQ2_B': CDS_PINID='DQ2_B';
NET_NAME
'M_J_CPU0_SB_DQ<30>'
 '@T6G_MB_LIB.T6G(SCH_1):M_J_CPU0_SB_DQ'<30>:
 C_SIGNAL='@t6g_mb_lib.t6g(sch_1):m_j_cpu0_sb_dq(30)';
NODE_NAME     U25 DE16
 '@T6G_MB_LIB.T6G(SCH_1):PAGE19_I159@PURE_QUANTA.GENOA_SP5(CHIPS)':
 'MJB_DATA30': CDS_PINID='MJB_DATA30';
NODE_NAME     J68 285
 '@T6G_MB_LIB.T6G(SCH_1):PAGE94_I22@PURE_QUANTA.SCONN288_DDR506112002KQ(CHIPS)':
 'DQ30_B': CDS_PINID='DQ30_B';
NET_NAME
'M_J_CPU0_SB_DQ<31>'
 '@T6G_MB_LIB.T6G(SCH_1):M_J_CPU0_SB_DQ'<31>:
 C_SIGNAL='@t6g_mb_lib.t6g(sch_1):m_j_cpu0_sb_dq(31)';
NODE_NAME     U25 DF16
 '@T6G_MB_LIB.T6G(SCH_1):PAGE19_I159@PURE_QUANTA.GENOA_SP5(CHIPS)':
 'MJB_DATA31': CDS_PINID='MJB_DATA31';
NODE_NAME     J68 287
 '@T6G_MB_LIB.T6G(SCH_1):PAGE94_I22@PURE_QUANTA.SCONN288_DDR506112002KQ(CHIPS)':
 'DQ31_B': CDS_PINID='DQ31_B';
NET_NAME
'M_J_CPU0_SB_DQ<3>'
 '@T6G_MB_LIB.T6G(SCH_1):M_J_CPU0_SB_DQ'<3>:
 C_SIGNAL='@t6g_mb_lib.t6g(sch_1):m_j_cpu0_sb_dq(3)';
NODE_NAME     U25 CD18
 '@T6G_MB_LIB.T6G(SCH_1):PAGE19_I159@PURE_QUANTA.GENOA_SP5(CHIPS)':
 'MJB_DATA3': CDS_PINID='MJB_DATA3';
NODE_NAME     J68 247
 '@T6G_MB_LIB.T6G(SCH_1):PAGE94_I22@PURE_QUANTA.SCONN288_DDR506112002KQ(CHIPS)':
 'DQ3_B': CDS_PINID='DQ3_B';
NET_NAME
'M_J_CPU0_SB_DQ<4>'
 '@T6G_MB_LIB.T6G(SCH_1):M_J_CPU0_SB_DQ'<4>:
 C_SIGNAL='@t6g_mb_lib.t6g(sch_1):m_j_cpu0_sb_dq(4)';
NODE_NAME     U25 CF16
 '@T6G_MB_LIB.T6G(SCH_1):PAGE19_I159@PURE_QUANTA.GENOA_SP5(CHIPS)':
 'MJB_DATA4': CDS_PINID='MJB_DATA4';
NODE_NAME     J68 107
 '@T6G_MB_LIB.T6G(SCH_1):PAGE94_I22@PURE_QUANTA.SCONN288_DDR506112002KQ(CHIPS)':
 'DQ4_B': CDS_PINID='DQ4_B';
NET_NAME
'M_J_CPU0_SB_DQ<5>'
 '@T6G_MB_LIB.T6G(SCH_1):M_J_CPU0_SB_DQ'<5>:
 C_SIGNAL='@t6g_mb_lib.t6g(sch_1):m_j_cpu0_sb_dq(5)';
NODE_NAME     U25 CG17
 '@T6G_MB_LIB.T6G(SCH_1):PAGE19_I159@PURE_QUANTA.GENOA_SP5(CHIPS)':
 'MJB_DATA5': CDS_PINID='MJB_DATA5';
NODE_NAME     J68 109
 '@T6G_MB_LIB.T6G(SCH_1):PAGE94_I22@PURE_QUANTA.SCONN288_DDR506112002KQ(CHIPS)':
 'DQ5_B': CDS_PINID='DQ5_B';
NET_NAME
'M_J_CPU0_SB_DQ<6>'
 '@T6G_MB_LIB.T6G(SCH_1):M_J_CPU0_SB_DQ'<6>:
 C_SIGNAL='@t6g_mb_lib.t6g(sch_1):m_j_cpu0_sb_dq(6)';
NODE_NAME     U25 CG16
 '@T6G_MB_LIB.T6G(SCH_1):PAGE19_I159@PURE_QUANTA.GENOA_SP5(CHIPS)':
 'MJB_DATA6': CDS_PINID='MJB_DATA6';
NODE_NAME     J68 252
 '@T6G_MB_LIB.T6G(SCH_1):PAGE94_I22@PURE_QUANTA.SCONN288_DDR506112002KQ(CHIPS)':
 'DQ6_B': CDS_PINID='DQ6_B';
NET_NAME
'M_J_CPU0_SB_DQ<7>'
 '@T6G_MB_LIB.T6G(SCH_1):M_J_CPU0_SB_DQ'<7>:
 C_SIGNAL='@t6g_mb_lib.t6g(sch_1):m_j_cpu0_sb_dq(7)';
NODE_NAME     U25 CH18
 '@T6G_MB_LIB.T6G(SCH_1):PAGE19_I159@PURE_QUANTA.GENOA_SP5(CHIPS)':
 'MJB_DATA7': CDS_PINID='MJB_DATA7';
NODE_NAME     J68 254
 '@T6G_MB_LIB.T6G(SCH_1):PAGE94_I22@PURE_QUANTA.SCONN288_DDR506112002KQ(CHIPS)':
 'DQ7_B': CDS_PINID='DQ7_B';
NET_NAME
'M_J_CPU0_SB_DQ<8>'
 '@T6G_MB_LIB.T6G(SCH_1):M_J_CPU0_SB_DQ'<8>:
 C_SIGNAL='@t6g_mb_lib.t6g(sch_1):m_j_cpu0_sb_dq(8)';
NODE_NAME     U25 CH16
 '@T6G_MB_LIB.T6G(SCH_1):PAGE19_I159@PURE_QUANTA.GENOA_SP5(CHIPS)':
 'MJB_DATA8': CDS_PINID='MJB_DATA8';
NODE_NAME     J68 111
 '@T6G_MB_LIB.T6G(SCH_1):PAGE94_I22@PURE_QUANTA.SCONN288_DDR506112002KQ(CHIPS)':
 'DQ8_B': CDS_PINID='DQ8_B';
NET_NAME
'M_J_CPU0_SB_DQ<9>'
 '@T6G_MB_LIB.T6G(SCH_1):M_J_CPU0_SB_DQ'<9>:
 C_SIGNAL='@t6g_mb_lib.t6g(sch_1):m_j_cpu0_sb_dq(9)';
NODE_NAME     U25 CJ17
 '@T6G_MB_LIB.T6G(SCH_1):PAGE19_I159@PURE_QUANTA.GENOA_SP5(CHIPS)':
 'MJB_DATA9': CDS_PINID='MJB_DATA9';
NODE_NAME     J68 113
 '@T6G_MB_LIB.T6G(SCH_1):PAGE94_I22@PURE_QUANTA.SCONN288_DDR506112002KQ(CHIPS)':
 'DQ9_B': CDS_PINID='DQ9_B';
NET_NAME
'M_J_CPU0_SB_DQS_DN<0>'
 '@T6G_MB_LIB.T6G(SCH_1):M_J_CPU0_SB_DQS_DN'<0>:
 C_SIGNAL='@t6g_mb_lib.t6g(sch_1):m_j_cpu0_sb_dqs_dn(0)';
NODE_NAME     U25 CE16
 '@T6G_MB_LIB.T6G(SCH_1):PAGE19_I159@PURE_QUANTA.GENOA_SP5(CHIPS)':
 'MJB_DQS_L0': CDS_PINID='MJB_DQS_L0';
NODE_NAME     J68 105
 '@T6G_MB_LIB.T6G(SCH_1):PAGE94_I236@PURE_QUANTA.SCONN288_DDR506112002KQ(CHIPS)':
 'DQS0_B_C': CDS_PINID='DQS0_B_C';
NET_NAME
'M_J_CPU0_SB_DQS_DN<1>'
 '@T6G_MB_LIB.T6G(SCH_1):M_J_CPU0_SB_DQS_DN'<1>:
 C_SIGNAL='@t6g_mb_lib.t6g(sch_1):m_j_cpu0_sb_dqs_dn(1)';
NODE_NAME     U25 CL16
 '@T6G_MB_LIB.T6G(SCH_1):PAGE19_I159@PURE_QUANTA.GENOA_SP5(CHIPS)':
 'MJB_DQS_L1': CDS_PINID='MJB_DQS_L1';
NODE_NAME     J68 116
 '@T6G_MB_LIB.T6G(SCH_1):PAGE94_I236@PURE_QUANTA.SCONN288_DDR506112002KQ(CHIPS)':
 'DQS1_B_C': CDS_PINID='DQS1_B_C';
NET_NAME
'M_J_CPU0_SB_DQS_DN<2>'
 '@T6G_MB_LIB.T6G(SCH_1):M_J_CPU0_SB_DQS_DN'<2>:
 C_SIGNAL='@t6g_mb_lib.t6g(sch_1):m_j_cpu0_sb_dqs_dn(2)';
NODE_NAME     U25 CU16
 '@T6G_MB_LIB.T6G(SCH_1):PAGE19_I159@PURE_QUANTA.GENOA_SP5(CHIPS)':
 'MJB_DQS_L2': CDS_PINID='MJB_DQS_L2';
NODE_NAME     J68 127
 '@T6G_MB_LIB.T6G(SCH_1):PAGE94_I236@PURE_QUANTA.SCONN288_DDR506112002KQ(CHIPS)':
 'DQS2_B_C': CDS_PINID='DQS2_B_C';
NET_NAME
'M_J_CPU0_SB_DQS_DN<3>'
 '@T6G_MB_LIB.T6G(SCH_1):M_J_CPU0_SB_DQS_DN'<3>:
 C_SIGNAL='@t6g_mb_lib.t6g(sch_1):m_j_cpu0_sb_dqs_dn(3)';
NODE_NAME     U25 DC16
 '@T6G_MB_LIB.T6G(SCH_1):PAGE19_I159@PURE_QUANTA.GENOA_SP5(CHIPS)':
 'MJB_DQS_L3': CDS_PINID='MJB_DQS_L3';
NODE_NAME     J68 138
 '@T6G_MB_LIB.T6G(SCH_1):PAGE94_I236@PURE_QUANTA.SCONN288_DDR506112002KQ(CHIPS)':
 'DQS3_B_C': CDS_PINID='DQS3_B_C';
NET_NAME
'M_J_CPU0_SB_DQS_DN<4>'
 '@T6G_MB_LIB.T6G(SCH_1):M_J_CPU0_SB_DQS_DN'<4>:
 C_SIGNAL='@t6g_mb_lib.t6g(sch_1):m_j_cpu0_sb_dqs_dn(4)';
NODE_NAME     U25 BW17
 '@T6G_MB_LIB.T6G(SCH_1):PAGE19_I159@PURE_QUANTA.GENOA_SP5(CHIPS)':
 'MJB_DQS_L4': CDS_PINID='MJB_DQS_L4';
NODE_NAME     J68 238
 '@T6G_MB_LIB.T6G(SCH_1):PAGE94_I236@PURE_QUANTA.SCONN288_DDR506112002KQ(CHIPS)':
 'DQS4_B_C': CDS_PINID='DQS4_B_C';
NET_NAME
'M_J_CPU0_SB_DQS_DN<5>'
 '@T6G_MB_LIB.T6G(SCH_1):M_J_CPU0_SB_DQS_DN'<5>:
 C_SIGNAL='@t6g_mb_lib.t6g(sch_1):m_j_cpu0_sb_dqs_dn(5)';
NODE_NAME     U25 CE17
 '@T6G_MB_LIB.T6G(SCH_1):PAGE19_I159@PURE_QUANTA.GENOA_SP5(CHIPS)':
 'MJB_DQS_L5': CDS_PINID='MJB_DQS_L5';
NODE_NAME     J68 249
 '@T6G_MB_LIB.T6G(SCH_1):PAGE94_I236@PURE_QUANTA.SCONN288_DDR506112002KQ(CHIPS)':
 'DQS5_B_C||TDQS5_B_C': CDS_PINID='\dqs5_b_c||tdqs5_b_c\';
NET_NAME
'M_J_CPU0_SB_DQS_DN<6>'
 '@T6G_MB_LIB.T6G(SCH_1):M_J_CPU0_SB_DQS_DN'<6>:
 C_SIGNAL='@t6g_mb_lib.t6g(sch_1):m_j_cpu0_sb_dqs_dn(6)';
NODE_NAME     U25 CL17
 '@T6G_MB_LIB.T6G(SCH_1):PAGE19_I159@PURE_QUANTA.GENOA_SP5(CHIPS)':
 'MJB_DQS_L6': CDS_PINID='MJB_DQS_L6';
NODE_NAME     J68 260
 '@T6G_MB_LIB.T6G(SCH_1):PAGE94_I236@PURE_QUANTA.SCONN288_DDR506112002KQ(CHIPS)':
 'DQS6_B_C||TDQS6_B_C': CDS_PINID='\dqs6_b_c||tdqs6_b_c\';
NET_NAME
'M_J_CPU0_SB_DQS_DN<7>'
 '@T6G_MB_LIB.T6G(SCH_1):M_J_CPU0_SB_DQS_DN'<7>:
 C_SIGNAL='@t6g_mb_lib.t6g(sch_1):m_j_cpu0_sb_dqs_dn(7)';
NODE_NAME     U25 CU17
 '@T6G_MB_LIB.T6G(SCH_1):PAGE19_I159@PURE_QUANTA.GENOA_SP5(CHIPS)':
 'MJB_DQS_L7': CDS_PINID='MJB_DQS_L7';
NODE_NAME     J68 271
 '@T6G_MB_LIB.T6G(SCH_1):PAGE94_I236@PURE_QUANTA.SCONN288_DDR506112002KQ(CHIPS)':
 'DQS7_B_C||TDQS7_B_C': CDS_PINID='\dqs7_b_c||tdqs7_b_c\';
NET_NAME
'M_J_CPU0_SB_DQS_DN<8>'
 '@T6G_MB_LIB.T6G(SCH_1):M_J_CPU0_SB_DQS_DN'<8>:
 C_SIGNAL='@t6g_mb_lib.t6g(sch_1):m_j_cpu0_sb_dqs_dn(8)';
NODE_NAME     U25 DC17
 '@T6G_MB_LIB.T6G(SCH_1):PAGE19_I159@PURE_QUANTA.GENOA_SP5(CHIPS)':
 'MJB_DQS_L8': CDS_PINID='MJB_DQS_L8';
NODE_NAME     J68 282
 '@T6G_MB_LIB.T6G(SCH_1):PAGE94_I236@PURE_QUANTA.SCONN288_DDR506112002KQ(CHIPS)':
 'DQS8_B_C||TDQS8_B_C': CDS_PINID='\dqs8_b_c||tdqs8_b_c\';
NET_NAME
'M_J_CPU0_SB_DQS_DN<9>'
 '@T6G_MB_LIB.T6G(SCH_1):M_J_CPU0_SB_DQS_DN'<9>:
 C_SIGNAL='@t6g_mb_lib.t6g(sch_1):m_j_cpu0_sb_dqs_dn(9)';
NODE_NAME     U25 BW16
 '@T6G_MB_LIB.T6G(SCH_1):PAGE19_I159@PURE_QUANTA.GENOA_SP5(CHIPS)':
 'MJB_DQS_L9': CDS_PINID='MJB_DQS_L9';
NODE_NAME     J68 94
 '@T6G_MB_LIB.T6G(SCH_1):PAGE94_I236@PURE_QUANTA.SCONN288_DDR506112002KQ(CHIPS)':
 'DQS9_B_C||TDQS9_B_C': CDS_PINID='\dqs9_b_c||tdqs9_b_c\';
NET_NAME
'M_J_CPU0_SB_DQS_DP<0>'
 '@T6G_MB_LIB.T6G(SCH_1):M_J_CPU0_SB_DQS_DP'<0>:
 C_SIGNAL='@t6g_mb_lib.t6g(sch_1):m_j_cpu0_sb_dqs_dp(0)';
NODE_NAME     U25 CD16
 '@T6G_MB_LIB.T6G(SCH_1):PAGE19_I159@PURE_QUANTA.GENOA_SP5(CHIPS)':
 'MJB_DQS_H0': CDS_PINID='MJB_DQS_H0';
NODE_NAME     J68 104
 '@T6G_MB_LIB.T6G(SCH_1):PAGE94_I236@PURE_QUANTA.SCONN288_DDR506112002KQ(CHIPS)':
 'DQS0_B_T': CDS_PINID='DQS0_B_T';
NET_NAME
'M_J_CPU0_SB_DQS_DP<1>'
 '@T6G_MB_LIB.T6G(SCH_1):M_J_CPU0_SB_DQS_DP'<1>:
 C_SIGNAL='@t6g_mb_lib.t6g(sch_1):m_j_cpu0_sb_dqs_dp(1)';
NODE_NAME     U25 CK16
 '@T6G_MB_LIB.T6G(SCH_1):PAGE19_I159@PURE_QUANTA.GENOA_SP5(CHIPS)':
 'MJB_DQS_H1': CDS_PINID='MJB_DQS_H1';
NODE_NAME     J68 115
 '@T6G_MB_LIB.T6G(SCH_1):PAGE94_I236@PURE_QUANTA.SCONN288_DDR506112002KQ(CHIPS)':
 'DQS1_B_T': CDS_PINID='DQS1_B_T';
NET_NAME
'M_J_CPU0_SB_DQS_DP<2>'
 '@T6G_MB_LIB.T6G(SCH_1):M_J_CPU0_SB_DQS_DP'<2>:
 C_SIGNAL='@t6g_mb_lib.t6g(sch_1):m_j_cpu0_sb_dqs_dp(2)';
NODE_NAME     U25 CT16
 '@T6G_MB_LIB.T6G(SCH_1):PAGE19_I159@PURE_QUANTA.GENOA_SP5(CHIPS)':
 'MJB_DQS_H2': CDS_PINID='MJB_DQS_H2';
NODE_NAME     J68 126
 '@T6G_MB_LIB.T6G(SCH_1):PAGE94_I236@PURE_QUANTA.SCONN288_DDR506112002KQ(CHIPS)':
 'DQS2_B_T': CDS_PINID='DQS2_B_T';
NET_NAME
'M_J_CPU0_SB_DQS_DP<3>'
 '@T6G_MB_LIB.T6G(SCH_1):M_J_CPU0_SB_DQS_DP'<3>:
 C_SIGNAL='@t6g_mb_lib.t6g(sch_1):m_j_cpu0_sb_dqs_dp(3)';
NODE_NAME     U25 DB16
 '@T6G_MB_LIB.T6G(SCH_1):PAGE19_I159@PURE_QUANTA.GENOA_SP5(CHIPS)':
 'MJB_DQS_H3': CDS_PINID='MJB_DQS_H3';
NODE_NAME     J68 137
 '@T6G_MB_LIB.T6G(SCH_1):PAGE94_I236@PURE_QUANTA.SCONN288_DDR506112002KQ(CHIPS)':
 'DQS3_B_T': CDS_PINID='DQS3_B_T';
NET_NAME
'M_J_CPU0_SB_DQS_DP<4>'
 '@T6G_MB_LIB.T6G(SCH_1):M_J_CPU0_SB_DQS_DP'<4>:
 C_SIGNAL='@t6g_mb_lib.t6g(sch_1):m_j_cpu0_sb_dqs_dp(4)';
NODE_NAME     U25 BY18
 '@T6G_MB_LIB.T6G(SCH_1):PAGE19_I159@PURE_QUANTA.GENOA_SP5(CHIPS)':
 'MJB_DQS_H4': CDS_PINID='MJB_DQS_H4';
NODE_NAME     J68 239
 '@T6G_MB_LIB.T6G(SCH_1):PAGE94_I236@PURE_QUANTA.SCONN288_DDR506112002KQ(CHIPS)':
 'DQS4_B_T': CDS_PINID='DQS4_B_T';
NET_NAME
'M_J_CPU0_SB_DQS_DP<5>'
 '@T6G_MB_LIB.T6G(SCH_1):M_J_CPU0_SB_DQS_DP'<5>:
 C_SIGNAL='@t6g_mb_lib.t6g(sch_1):m_j_cpu0_sb_dqs_dp(5)';
NODE_NAME     U25 CF18
 '@T6G_MB_LIB.T6G(SCH_1):PAGE19_I159@PURE_QUANTA.GENOA_SP5(CHIPS)':
 'MJB_DQS_H5': CDS_PINID='MJB_DQS_H5';
NODE_NAME     J68 250
 '@T6G_MB_LIB.T6G(SCH_1):PAGE94_I236@PURE_QUANTA.SCONN288_DDR506112002KQ(CHIPS)':
 'DQS5_B_T||TDQS5_B_T': CDS_PINID='\dqs5_b_t||tdqs5_b_t\';
NET_NAME
'M_J_CPU0_SB_DQS_DP<6>'
 '@T6G_MB_LIB.T6G(SCH_1):M_J_CPU0_SB_DQS_DP'<6>:
 C_SIGNAL='@t6g_mb_lib.t6g(sch_1):m_j_cpu0_sb_dqs_dp(6)';
NODE_NAME     U25 CM18
 '@T6G_MB_LIB.T6G(SCH_1):PAGE19_I159@PURE_QUANTA.GENOA_SP5(CHIPS)':
 'MJB_DQS_H6': CDS_PINID='MJB_DQS_H6';
NODE_NAME     J68 261
 '@T6G_MB_LIB.T6G(SCH_1):PAGE94_I236@PURE_QUANTA.SCONN288_DDR506112002KQ(CHIPS)':
 'DQS6_B_T||TDQS6_B_T': CDS_PINID='\dqs6_b_t||tdqs6_b_t\';
NET_NAME
'M_J_CPU0_SB_DQS_DP<7>'
 '@T6G_MB_LIB.T6G(SCH_1):M_J_CPU0_SB_DQS_DP'<7>:
 C_SIGNAL='@t6g_mb_lib.t6g(sch_1):m_j_cpu0_sb_dqs_dp(7)';
NODE_NAME     U25 CV18
 '@T6G_MB_LIB.T6G(SCH_1):PAGE19_I159@PURE_QUANTA.GENOA_SP5(CHIPS)':
 'MJB_DQS_H7': CDS_PINID='MJB_DQS_H7';
NODE_NAME     J68 272
 '@T6G_MB_LIB.T6G(SCH_1):PAGE94_I236@PURE_QUANTA.SCONN288_DDR506112002KQ(CHIPS)':
 'DQS7_B_T||TDQS7_B_T': CDS_PINID='\dqs7_b_t||tdqs7_b_t\';
NET_NAME
'M_J_CPU0_SB_DQS_DP<8>'
 '@T6G_MB_LIB.T6G(SCH_1):M_J_CPU0_SB_DQS_DP'<8>:
 C_SIGNAL='@t6g_mb_lib.t6g(sch_1):m_j_cpu0_sb_dqs_dp(8)';
NODE_NAME     U25 DD18
 '@T6G_MB_LIB.T6G(SCH_1):PAGE19_I159@PURE_QUANTA.GENOA_SP5(CHIPS)':
 'MJB_DQS_H8': CDS_PINID='MJB_DQS_H8';
NODE_NAME     J68 283
 '@T6G_MB_LIB.T6G(SCH_1):PAGE94_I236@PURE_QUANTA.SCONN288_DDR506112002KQ(CHIPS)':
 'DQS8_B_T||TDQS8_B_T': CDS_PINID='\dqs8_b_t||tdqs8_b_t\';
NET_NAME
'M_J_CPU0_SB_DQS_DP<9>'
 '@T6G_MB_LIB.T6G(SCH_1):M_J_CPU0_SB_DQS_DP'<9>:
 C_SIGNAL='@t6g_mb_lib.t6g(sch_1):m_j_cpu0_sb_dqs_dp(9)';
NODE_NAME     U25 BV16
 '@T6G_MB_LIB.T6G(SCH_1):PAGE19_I159@PURE_QUANTA.GENOA_SP5(CHIPS)':
 'MJB_DQS_H9': CDS_PINID='MJB_DQS_H9';
NODE_NAME     J68 93
 '@T6G_MB_LIB.T6G(SCH_1):PAGE94_I236@PURE_QUANTA.SCONN288_DDR506112002KQ(CHIPS)':
 'DQS9_B_T||TDQS9_B_T||DBI4_B_N': CDS_PINID='\dqs9_b_t||tdqs9_b_t||dbi4_b_n\';
NET_NAME
'M_J_CPU0_SB_PAR'
 '@T6G_MB_LIB.T6G(SCH_1):M_J_CPU0_SB_PAR':
 C_SIGNAL='@t6g_mb_lib.t6g(sch_1):m_j_cpu0_sb_par';
NODE_NAME     U25 BL17
 '@T6G_MB_LIB.T6G(SCH_1):PAGE19_I159@PURE_QUANTA.GENOA_SP5(CHIPS)':
 'MJB_PAR': CDS_PINID='MJB_PAR';
NODE_NAME     J68 227
 '@T6G_MB_LIB.T6G(SCH_1):PAGE94_I22@PURE_QUANTA.SCONN288_DDR506112002KQ(CHIPS)':
 'PAR_B': CDS_PINID='PAR_B';
NET_NAME
'M_J_CPU0_SB_RSP<0>'
 '@T6G_MB_LIB.T6G(SCH_1):M_J_CPU0_SB_RSP'<0>:
 C_SIGNAL='@t6g_mb_lib.t6g(sch_1):m_j_cpu0_sb_rsp(0)';
NODE_NAME     U25 BP16
 '@T6G_MB_LIB.T6G(SCH_1):PAGE19_I159@PURE_QUANTA.GENOA_SP5(CHIPS)':
 'MJB0_RSP_L': CDS_PINID='MJB0_RSP_L';
NODE_NAME     J68 87
 '@T6G_MB_LIB.T6G(SCH_1):PAGE94_I22@PURE_QUANTA.SCONN288_DDR506112002KQ(CHIPS)':
 'LBS||RSP_B_N': CDS_PINID='\lbs||rsp_b_n\';
NET_NAME
'M_J_CPU1_ALERT_N'
 '@T6G_MB_LIB.T6G(SCH_1):M_J_CPU1_ALERT_N':
 C_SIGNAL='@t6g_mb_lib.t6g(sch_1):m_j_cpu1_alert_n';
NODE_NAME     R509 1
 '@T6G_MB_LIB.T6G(SCH_1):PAGE46_I314@PURE_QUANTA.Q_RES(CHIPS)':
 'A': CDS_PINID='A';
NODE_NAME     J29 62
 '@T6G_MB_LIB.T6G(SCH_1):PAGE106_I22@PURE_QUANTA.SCONN288_DDR506112002KQ(CHIPS)':
 'ALERT_N': CDS_PINID='ALERT_N';
NET_NAME
'M_J_CPU1_ALERT_R_N'
 '@T6G_MB_LIB.T6G(SCH_1):M_J_CPU1_ALERT_R_N':
 C_SIGNAL='@t6g_mb_lib.t6g(sch_1):m_j_cpu1_alert_r_n';
NODE_NAME     U26 AT18
 '@T6G_MB_LIB.T6G(SCH_1):PAGE46_I159@PURE_QUANTA.GENOA_SP5(CHIPS)':
 'MJ_ALERT_L': CDS_PINID='MJ_ALERT_L';
NODE_NAME     R509 2
 '@T6G_MB_LIB.T6G(SCH_1):PAGE46_I314@PURE_QUANTA.Q_RES(CHIPS)':
 'B': CDS_PINID='B';
NET_NAME
'M_J_CPU1_CLK_DN<0>'
 '@T6G_MB_LIB.T6G(SCH_1):M_J_CPU1_CLK_DN'<0>:
 C_SIGNAL='@t6g_mb_lib.t6g(sch_1):m_j_cpu1_clk_dn(0)';
NODE_NAME     U26 BD16
 '@T6G_MB_LIB.T6G(SCH_1):PAGE46_I159@PURE_QUANTA.GENOA_SP5(CHIPS)':
 'MJ0_CLK_L': CDS_PINID='MJ0_CLK_L';
NODE_NAME     J29 218
 '@T6G_MB_LIB.T6G(SCH_1):PAGE106_I22@PURE_QUANTA.SCONN288_DDR506112002KQ(CHIPS)':
 'CK_C': CDS_PINID='CK_C';
NET_NAME
'M_J_CPU1_CLK_DP<0>'
 '@T6G_MB_LIB.T6G(SCH_1):M_J_CPU1_CLK_DP'<0>:
 C_SIGNAL='@t6g_mb_lib.t6g(sch_1):m_j_cpu1_clk_dp(0)';
NODE_NAME     U26 BC16
 '@T6G_MB_LIB.T6G(SCH_1):PAGE46_I159@PURE_QUANTA.GENOA_SP5(CHIPS)':
 'MJ0_CLK_H': CDS_PINID='MJ0_CLK_H';
NODE_NAME     J29 217
 '@T6G_MB_LIB.T6G(SCH_1):PAGE106_I22@PURE_QUANTA.SCONN288_DDR506112002KQ(CHIPS)':
 'CK_T': CDS_PINID='CK_T';
NET_NAME
'M_J_CPU1_RESET_N'
 '@T6G_MB_LIB.T6G(SCH_1):M_J_CPU1_RESET_N':
 C_SIGNAL='@t6g_mb_lib.t6g(sch_1):m_j_cpu1_reset_n';
NODE_NAME     U26 AU17
 '@T6G_MB_LIB.T6G(SCH_1):PAGE46_I159@PURE_QUANTA.GENOA_SP5(CHIPS)':
 'MJ_RESET_L': CDS_PINID='MJ_RESET_L';
NODE_NAME     J29 207
 '@T6G_MB_LIB.T6G(SCH_1):PAGE106_I22@PURE_QUANTA.SCONN288_DDR506112002KQ(CHIPS)':
 'RESET_N': CDS_PINID='RESET_N';
NET_NAME
'M_J_CPU1_SA_CA<0>'
 '@T6G_MB_LIB.T6G(SCH_1):M_J_CPU1_SA_CA'<0>:
 C_SIGNAL='@t6g_mb_lib.t6g(sch_1):m_j_cpu1_sa_ca(0)';
NODE_NAME     U26 AW16
 '@T6G_MB_LIB.T6G(SCH_1):PAGE46_I159@PURE_QUANTA.GENOA_SP5(CHIPS)':
 'MJA_CA0': CDS_PINID='MJA_CA0';
NODE_NAME     J29 66
 '@T6G_MB_LIB.T6G(SCH_1):PAGE106_I22@PURE_QUANTA.SCONN288_DDR506112002KQ(CHIPS)':
 'CA0_A': CDS_PINID='CA0_A';
NET_NAME
'M_J_CPU1_SA_CA<1>'
 '@T6G_MB_LIB.T6G(SCH_1):M_J_CPU1_SA_CA'<1>:
 C_SIGNAL='@t6g_mb_lib.t6g(sch_1):m_j_cpu1_sa_ca(1)';
NODE_NAME     U26 AY16
 '@T6G_MB_LIB.T6G(SCH_1):PAGE46_I159@PURE_QUANTA.GENOA_SP5(CHIPS)':
 'MJA_CA1': CDS_PINID='MJA_CA1';
NODE_NAME     J29 211
 '@T6G_MB_LIB.T6G(SCH_1):PAGE106_I22@PURE_QUANTA.SCONN288_DDR506112002KQ(CHIPS)':
 'CA1_A': CDS_PINID='CA1_A';
NET_NAME
'M_J_CPU1_SA_CA<2>'
 '@T6G_MB_LIB.T6G(SCH_1):M_J_CPU1_SA_CA'<2>:
 C_SIGNAL='@t6g_mb_lib.t6g(sch_1):m_j_cpu1_sa_ca(2)';
NODE_NAME     U26 AY18
 '@T6G_MB_LIB.T6G(SCH_1):PAGE46_I159@PURE_QUANTA.GENOA_SP5(CHIPS)':
 'MJA_CA2': CDS_PINID='MJA_CA2';
NODE_NAME     J29 68
 '@T6G_MB_LIB.T6G(SCH_1):PAGE106_I22@PURE_QUANTA.SCONN288_DDR506112002KQ(CHIPS)':
 'CA2_A': CDS_PINID='CA2_A';
NET_NAME
'M_J_CPU1_SA_CA<3>'
 '@T6G_MB_LIB.T6G(SCH_1):M_J_CPU1_SA_CA'<3>:
 C_SIGNAL='@t6g_mb_lib.t6g(sch_1):m_j_cpu1_sa_ca(3)';
NODE_NAME     U26 BA17
 '@T6G_MB_LIB.T6G(SCH_1):PAGE46_I159@PURE_QUANTA.GENOA_SP5(CHIPS)':
 'MJA_CA3': CDS_PINID='MJA_CA3';
NODE_NAME     J29 213
 '@T6G_MB_LIB.T6G(SCH_1):PAGE106_I22@PURE_QUANTA.SCONN288_DDR506112002KQ(CHIPS)':
 'CA3_A': CDS_PINID='CA3_A';
NET_NAME
'M_J_CPU1_SA_CA<4>'
 '@T6G_MB_LIB.T6G(SCH_1):M_J_CPU1_SA_CA'<4>:
 C_SIGNAL='@t6g_mb_lib.t6g(sch_1):m_j_cpu1_sa_ca(4)';
NODE_NAME     U26 BA16
 '@T6G_MB_LIB.T6G(SCH_1):PAGE46_I159@PURE_QUANTA.GENOA_SP5(CHIPS)':
 'MJA_CA4': CDS_PINID='MJA_CA4';
NODE_NAME     J29 70
 '@T6G_MB_LIB.T6G(SCH_1):PAGE106_I22@PURE_QUANTA.SCONN288_DDR506112002KQ(CHIPS)':
 'CA4_A': CDS_PINID='CA4_A';
NET_NAME
'M_J_CPU1_SA_CA<5>'
 '@T6G_MB_LIB.T6G(SCH_1):M_J_CPU1_SA_CA'<5>:
 C_SIGNAL='@t6g_mb_lib.t6g(sch_1):m_j_cpu1_sa_ca(5)';
NODE_NAME     U26 BB16
 '@T6G_MB_LIB.T6G(SCH_1):PAGE46_I159@PURE_QUANTA.GENOA_SP5(CHIPS)':
 'MJA_CA5': CDS_PINID='MJA_CA5';
NODE_NAME     J29 215
 '@T6G_MB_LIB.T6G(SCH_1):PAGE106_I22@PURE_QUANTA.SCONN288_DDR506112002KQ(CHIPS)':
 'CA5_A': CDS_PINID='CA5_A';
NET_NAME
'M_J_CPU1_SA_CA<6>'
 '@T6G_MB_LIB.T6G(SCH_1):M_J_CPU1_SA_CA'<6>:
 C_SIGNAL='@t6g_mb_lib.t6g(sch_1):m_j_cpu1_sa_ca(6)';
NODE_NAME     U26 BB18
 '@T6G_MB_LIB.T6G(SCH_1):PAGE46_I159@PURE_QUANTA.GENOA_SP5(CHIPS)':
 'MJA_CA6': CDS_PINID='MJA_CA6';
NODE_NAME     J29 72
 '@T6G_MB_LIB.T6G(SCH_1):PAGE106_I22@PURE_QUANTA.SCONN288_DDR506112002KQ(CHIPS)':
 'CA6_A': CDS_PINID='CA6_A';
NET_NAME
'M_J_CPU1_SA_CB<0>'
 '@T6G_MB_LIB.T6G(SCH_1):M_J_CPU1_SA_CB'<0>:
 C_SIGNAL='@t6g_mb_lib.t6g(sch_1):m_j_cpu1_sa_cb(0)';
NODE_NAME     U26 AJ16
 '@T6G_MB_LIB.T6G(SCH_1):PAGE46_I159@PURE_QUANTA.GENOA_SP5(CHIPS)':
 'MJA_CHECK0': CDS_PINID='MJA_CHECK0';
NODE_NAME     J29 51
 '@T6G_MB_LIB.T6G(SCH_1):PAGE106_I22@PURE_QUANTA.SCONN288_DDR506112002KQ(CHIPS)':
 'CB0_A': CDS_PINID='CB0_A';
NET_NAME
'M_J_CPU1_SA_CB<1>'
 '@T6G_MB_LIB.T6G(SCH_1):M_J_CPU1_SA_CB'<1>:
 C_SIGNAL='@t6g_mb_lib.t6g(sch_1):m_j_cpu1_sa_cb(1)';
NODE_NAME     U26 AK18
 '@T6G_MB_LIB.T6G(SCH_1):PAGE46_I159@PURE_QUANTA.GENOA_SP5(CHIPS)':
 'MJA_CHECK1': CDS_PINID='MJA_CHECK1';
NODE_NAME     J29 53
 '@T6G_MB_LIB.T6G(SCH_1):PAGE106_I22@PURE_QUANTA.SCONN288_DDR506112002KQ(CHIPS)':
 'CB1_A': CDS_PINID='CB1_A';
NET_NAME
'M_J_CPU1_SA_CB<2>'
 '@T6G_MB_LIB.T6G(SCH_1):M_J_CPU1_SA_CB'<2>:
 C_SIGNAL='@t6g_mb_lib.t6g(sch_1):m_j_cpu1_sa_cb(2)';
NODE_NAME     U26 AK16
 '@T6G_MB_LIB.T6G(SCH_1):PAGE46_I159@PURE_QUANTA.GENOA_SP5(CHIPS)':
 'MJA_CHECK2': CDS_PINID='MJA_CHECK2';
NODE_NAME     J29 196
 '@T6G_MB_LIB.T6G(SCH_1):PAGE106_I22@PURE_QUANTA.SCONN288_DDR506112002KQ(CHIPS)':
 'CB2_A': CDS_PINID='CB2_A';
NET_NAME
'M_J_CPU1_SA_CB<3>'
 '@T6G_MB_LIB.T6G(SCH_1):M_J_CPU1_SA_CB'<3>:
 C_SIGNAL='@t6g_mb_lib.t6g(sch_1):m_j_cpu1_sa_cb(3)';
NODE_NAME     U26 AL17
 '@T6G_MB_LIB.T6G(SCH_1):PAGE46_I159@PURE_QUANTA.GENOA_SP5(CHIPS)':
 'MJA_CHECK3': CDS_PINID='MJA_CHECK3';
NODE_NAME     J29 198
 '@T6G_MB_LIB.T6G(SCH_1):PAGE106_I22@PURE_QUANTA.SCONN288_DDR506112002KQ(CHIPS)':
 'CB3_A': CDS_PINID='CB3_A';
NET_NAME
'M_J_CPU1_SA_CB<4>'
 '@T6G_MB_LIB.T6G(SCH_1):M_J_CPU1_SA_CB'<4>:
 C_SIGNAL='@t6g_mb_lib.t6g(sch_1):m_j_cpu1_sa_cb(4)';
NODE_NAME     U26 AN16
 '@T6G_MB_LIB.T6G(SCH_1):PAGE46_I159@PURE_QUANTA.GENOA_SP5(CHIPS)':
 'MJA_CHECK4': CDS_PINID='MJA_CHECK4';
NODE_NAME     J29 58
 '@T6G_MB_LIB.T6G(SCH_1):PAGE106_I22@PURE_QUANTA.SCONN288_DDR506112002KQ(CHIPS)':
 'CB4_A': CDS_PINID='CB4_A';
NET_NAME
'M_J_CPU1_SA_CB<5>'
 '@T6G_MB_LIB.T6G(SCH_1):M_J_CPU1_SA_CB'<5>:
 C_SIGNAL='@t6g_mb_lib.t6g(sch_1):m_j_cpu1_sa_cb(5)';
NODE_NAME     U26 AP18
 '@T6G_MB_LIB.T6G(SCH_1):PAGE46_I159@PURE_QUANTA.GENOA_SP5(CHIPS)':
 'MJA_CHECK5': CDS_PINID='MJA_CHECK5';
NODE_NAME     J29 60
 '@T6G_MB_LIB.T6G(SCH_1):PAGE106_I22@PURE_QUANTA.SCONN288_DDR506112002KQ(CHIPS)':
 'CB5_A': CDS_PINID='CB5_A';
NET_NAME
'M_J_CPU1_SA_CB<6>'
 '@T6G_MB_LIB.T6G(SCH_1):M_J_CPU1_SA_CB'<6>:
 C_SIGNAL='@t6g_mb_lib.t6g(sch_1):m_j_cpu1_sa_cb(6)';
NODE_NAME     U26 AP16
 '@T6G_MB_LIB.T6G(SCH_1):PAGE46_I159@PURE_QUANTA.GENOA_SP5(CHIPS)':
 'MJA_CHECK6': CDS_PINID='MJA_CHECK6';
NODE_NAME     J29 203
 '@T6G_MB_LIB.T6G(SCH_1):PAGE106_I22@PURE_QUANTA.SCONN288_DDR506112002KQ(CHIPS)':
 'CB6_A': CDS_PINID='CB6_A';
NET_NAME
'M_J_CPU1_SA_CB<7>'
 '@T6G_MB_LIB.T6G(SCH_1):M_J_CPU1_SA_CB'<7>:
 C_SIGNAL='@t6g_mb_lib.t6g(sch_1):m_j_cpu1_sa_cb(7)';
NODE_NAME     U26 AR17
 '@T6G_MB_LIB.T6G(SCH_1):PAGE46_I159@PURE_QUANTA.GENOA_SP5(CHIPS)':
 'MJA_CHECK7': CDS_PINID='MJA_CHECK7';
NODE_NAME     J29 205
 '@T6G_MB_LIB.T6G(SCH_1):PAGE106_I22@PURE_QUANTA.SCONN288_DDR506112002KQ(CHIPS)':
 'CB7_A': CDS_PINID='CB7_A';
NET_NAME
'M_J_CPU1_SA_CS_N<0>'
 '@T6G_MB_LIB.T6G(SCH_1):M_J_CPU1_SA_CS_N'<0>:
 C_SIGNAL='@t6g_mb_lib.t6g(sch_1):m_j_cpu1_sa_cs_n(0)';
NODE_NAME     U26 AU16
 '@T6G_MB_LIB.T6G(SCH_1):PAGE46_I159@PURE_QUANTA.GENOA_SP5(CHIPS)':
 'MJA0_CS_L0': CDS_PINID='MJA0_CS_L0';
NODE_NAME     J29 64
 '@T6G_MB_LIB.T6G(SCH_1):PAGE106_I22@PURE_QUANTA.SCONN288_DDR506112002KQ(CHIPS)':
 'CS0_A_N': CDS_PINID='CS0_A_N';
NET_NAME
'M_J_CPU1_SA_CS_N<1>'
 '@T6G_MB_LIB.T6G(SCH_1):M_J_CPU1_SA_CS_N'<1>:
 C_SIGNAL='@t6g_mb_lib.t6g(sch_1):m_j_cpu1_sa_cs_n(1)';
NODE_NAME     U26 AV18
 '@T6G_MB_LIB.T6G(SCH_1):PAGE46_I159@PURE_QUANTA.GENOA_SP5(CHIPS)':
 'MJA0_CS_L1': CDS_PINID='MJA0_CS_L1';
NODE_NAME     J29 209
 '@T6G_MB_LIB.T6G(SCH_1):PAGE106_I22@PURE_QUANTA.SCONN288_DDR506112002KQ(CHIPS)':
 'CS1_A_N': CDS_PINID='CS1_A_N';
NET_NAME
'M_J_CPU1_SA_DQ<0>'
 '@T6G_MB_LIB.T6G(SCH_1):M_J_CPU1_SA_DQ'<0>:
 C_SIGNAL='@t6g_mb_lib.t6g(sch_1):m_j_cpu1_sa_dq(0)';
NODE_NAME     U26 E16
 '@T6G_MB_LIB.T6G(SCH_1):PAGE46_I159@PURE_QUANTA.GENOA_SP5(CHIPS)':
 'MJA_DATA0': CDS_PINID='MJA_DATA0';
NODE_NAME     J29 7
 '@T6G_MB_LIB.T6G(SCH_1):PAGE106_I22@PURE_QUANTA.SCONN288_DDR506112002KQ(CHIPS)':
 'DQ0_A': CDS_PINID='DQ0_A';
NET_NAME
'M_J_CPU1_SA_DQ<10>'
 '@T6G_MB_LIB.T6G(SCH_1):M_J_CPU1_SA_DQ'<10>:
 C_SIGNAL='@t6g_mb_lib.t6g(sch_1):m_j_cpu1_sa_dq(10)';
NODE_NAME     U26 M16
 '@T6G_MB_LIB.T6G(SCH_1):PAGE46_I159@PURE_QUANTA.GENOA_SP5(CHIPS)':
 'MJA_DATA10': CDS_PINID='MJA_DATA10';
NODE_NAME     J29 163
 '@T6G_MB_LIB.T6G(SCH_1):PAGE106_I22@PURE_QUANTA.SCONN288_DDR506112002KQ(CHIPS)':
 'DQ10_A': CDS_PINID='DQ10_A';
NET_NAME
'M_J_CPU1_SA_DQ<11>'
 '@T6G_MB_LIB.T6G(SCH_1):M_J_CPU1_SA_DQ'<11>:
 C_SIGNAL='@t6g_mb_lib.t6g(sch_1):m_j_cpu1_sa_dq(11)';
NODE_NAME     U26 N17
 '@T6G_MB_LIB.T6G(SCH_1):PAGE46_I159@PURE_QUANTA.GENOA_SP5(CHIPS)':
 'MJA_DATA11': CDS_PINID='MJA_DATA11';
NODE_NAME     J29 165
 '@T6G_MB_LIB.T6G(SCH_1):PAGE106_I22@PURE_QUANTA.SCONN288_DDR506112002KQ(CHIPS)':
 'DQ11_A': CDS_PINID='DQ11_A';
NET_NAME
'M_J_CPU1_SA_DQ<12>'
 '@T6G_MB_LIB.T6G(SCH_1):M_J_CPU1_SA_DQ'<12>:
 C_SIGNAL='@t6g_mb_lib.t6g(sch_1):m_j_cpu1_sa_dq(12)';
NODE_NAME     U26 R16
 '@T6G_MB_LIB.T6G(SCH_1):PAGE46_I159@PURE_QUANTA.GENOA_SP5(CHIPS)':
 'MJA_DATA12': CDS_PINID='MJA_DATA12';
NODE_NAME     J29 25
 '@T6G_MB_LIB.T6G(SCH_1):PAGE106_I22@PURE_QUANTA.SCONN288_DDR506112002KQ(CHIPS)':
 'DQ12_A': CDS_PINID='DQ12_A';
NET_NAME
'M_J_CPU1_SA_DQ<13>'
 '@T6G_MB_LIB.T6G(SCH_1):M_J_CPU1_SA_DQ'<13>:
 C_SIGNAL='@t6g_mb_lib.t6g(sch_1):m_j_cpu1_sa_dq(13)';
NODE_NAME     U26 T18
 '@T6G_MB_LIB.T6G(SCH_1):PAGE46_I159@PURE_QUANTA.GENOA_SP5(CHIPS)':
 'MJA_DATA13': CDS_PINID='MJA_DATA13';
NODE_NAME     J29 27
 '@T6G_MB_LIB.T6G(SCH_1):PAGE106_I22@PURE_QUANTA.SCONN288_DDR506112002KQ(CHIPS)':
 'DQ13_A': CDS_PINID='DQ13_A';
NET_NAME
'M_J_CPU1_SA_DQ<14>'
 '@T6G_MB_LIB.T6G(SCH_1):M_J_CPU1_SA_DQ'<14>:
 C_SIGNAL='@t6g_mb_lib.t6g(sch_1):m_j_cpu1_sa_dq(14)';
NODE_NAME     U26 T16
 '@T6G_MB_LIB.T6G(SCH_1):PAGE46_I159@PURE_QUANTA.GENOA_SP5(CHIPS)':
 'MJA_DATA14': CDS_PINID='MJA_DATA14';
NODE_NAME     J29 170
 '@T6G_MB_LIB.T6G(SCH_1):PAGE106_I22@PURE_QUANTA.SCONN288_DDR506112002KQ(CHIPS)':
 'DQ14_A': CDS_PINID='DQ14_A';
NET_NAME
'M_J_CPU1_SA_DQ<15>'
 '@T6G_MB_LIB.T6G(SCH_1):M_J_CPU1_SA_DQ'<15>:
 C_SIGNAL='@t6g_mb_lib.t6g(sch_1):m_j_cpu1_sa_dq(15)';
NODE_NAME     U26 U17
 '@T6G_MB_LIB.T6G(SCH_1):PAGE46_I159@PURE_QUANTA.GENOA_SP5(CHIPS)':
 'MJA_DATA15': CDS_PINID='MJA_DATA15';
NODE_NAME     J29 172
 '@T6G_MB_LIB.T6G(SCH_1):PAGE106_I22@PURE_QUANTA.SCONN288_DDR506112002KQ(CHIPS)':
 'DQ15_A': CDS_PINID='DQ15_A';
NET_NAME
'M_J_CPU1_SA_DQ<16>'
 '@T6G_MB_LIB.T6G(SCH_1):M_J_CPU1_SA_DQ'<16>:
 C_SIGNAL='@t6g_mb_lib.t6g(sch_1):m_j_cpu1_sa_dq(16)';
NODE_NAME     U26 U16
 '@T6G_MB_LIB.T6G(SCH_1):PAGE46_I159@PURE_QUANTA.GENOA_SP5(CHIPS)':
 'MJA_DATA16': CDS_PINID='MJA_DATA16';
NODE_NAME     J29 29
 '@T6G_MB_LIB.T6G(SCH_1):PAGE106_I22@PURE_QUANTA.SCONN288_DDR506112002KQ(CHIPS)':
 'DQ16_A': CDS_PINID='DQ16_A';
NET_NAME
'M_J_CPU1_SA_DQ<17>'
 '@T6G_MB_LIB.T6G(SCH_1):M_J_CPU1_SA_DQ'<17>:
 C_SIGNAL='@t6g_mb_lib.t6g(sch_1):m_j_cpu1_sa_dq(17)';
NODE_NAME     U26 V18
 '@T6G_MB_LIB.T6G(SCH_1):PAGE46_I159@PURE_QUANTA.GENOA_SP5(CHIPS)':
 'MJA_DATA17': CDS_PINID='MJA_DATA17';
NODE_NAME     J29 31
 '@T6G_MB_LIB.T6G(SCH_1):PAGE106_I22@PURE_QUANTA.SCONN288_DDR506112002KQ(CHIPS)':
 'DQ17_A': CDS_PINID='DQ17_A';
NET_NAME
'M_J_CPU1_SA_DQ<18>'
 '@T6G_MB_LIB.T6G(SCH_1):M_J_CPU1_SA_DQ'<18>:
 C_SIGNAL='@t6g_mb_lib.t6g(sch_1):m_j_cpu1_sa_dq(18)';
NODE_NAME     U26 V16
 '@T6G_MB_LIB.T6G(SCH_1):PAGE46_I159@PURE_QUANTA.GENOA_SP5(CHIPS)':
 'MJA_DATA18': CDS_PINID='MJA_DATA18';
NODE_NAME     J29 174
 '@T6G_MB_LIB.T6G(SCH_1):PAGE106_I22@PURE_QUANTA.SCONN288_DDR506112002KQ(CHIPS)':
 'DQ18_A': CDS_PINID='DQ18_A';
NET_NAME
'M_J_CPU1_SA_DQ<19>'
 '@T6G_MB_LIB.T6G(SCH_1):M_J_CPU1_SA_DQ'<19>:
 C_SIGNAL='@t6g_mb_lib.t6g(sch_1):m_j_cpu1_sa_dq(19)';
NODE_NAME     U26 W17
 '@T6G_MB_LIB.T6G(SCH_1):PAGE46_I159@PURE_QUANTA.GENOA_SP5(CHIPS)':
 'MJA_DATA19': CDS_PINID='MJA_DATA19';
NODE_NAME     J29 176
 '@T6G_MB_LIB.T6G(SCH_1):PAGE106_I22@PURE_QUANTA.SCONN288_DDR506112002KQ(CHIPS)':
 'DQ19_A': CDS_PINID='DQ19_A';
NET_NAME
'M_J_CPU1_SA_DQ<1>'
 '@T6G_MB_LIB.T6G(SCH_1):M_J_CPU1_SA_DQ'<1>:
 C_SIGNAL='@t6g_mb_lib.t6g(sch_1):m_j_cpu1_sa_dq(1)';
NODE_NAME     U26 F18
 '@T6G_MB_LIB.T6G(SCH_1):PAGE46_I159@PURE_QUANTA.GENOA_SP5(CHIPS)':
 'MJA_DATA1': CDS_PINID='MJA_DATA1';
NODE_NAME     J29 9
 '@T6G_MB_LIB.T6G(SCH_1):PAGE106_I22@PURE_QUANTA.SCONN288_DDR506112002KQ(CHIPS)':
 'DQ1_A': CDS_PINID='DQ1_A';
NET_NAME
'M_J_CPU1_SA_DQ<20>'
 '@T6G_MB_LIB.T6G(SCH_1):M_J_CPU1_SA_DQ'<20>:
 C_SIGNAL='@t6g_mb_lib.t6g(sch_1):m_j_cpu1_sa_dq(20)';
NODE_NAME     U26 AA16
 '@T6G_MB_LIB.T6G(SCH_1):PAGE46_I159@PURE_QUANTA.GENOA_SP5(CHIPS)':
 'MJA_DATA20': CDS_PINID='MJA_DATA20';
NODE_NAME     J29 36
 '@T6G_MB_LIB.T6G(SCH_1):PAGE106_I22@PURE_QUANTA.SCONN288_DDR506112002KQ(CHIPS)':
 'DQ20_A': CDS_PINID='DQ20_A';
NET_NAME
'M_J_CPU1_SA_DQ<21>'
 '@T6G_MB_LIB.T6G(SCH_1):M_J_CPU1_SA_DQ'<21>:
 C_SIGNAL='@t6g_mb_lib.t6g(sch_1):m_j_cpu1_sa_dq(21)';
NODE_NAME     U26 AB18
 '@T6G_MB_LIB.T6G(SCH_1):PAGE46_I159@PURE_QUANTA.GENOA_SP5(CHIPS)':
 'MJA_DATA21': CDS_PINID='MJA_DATA21';
NODE_NAME     J29 38
 '@T6G_MB_LIB.T6G(SCH_1):PAGE106_I22@PURE_QUANTA.SCONN288_DDR506112002KQ(CHIPS)':
 'DQ21_A': CDS_PINID='DQ21_A';
NET_NAME
'M_J_CPU1_SA_DQ<22>'
 '@T6G_MB_LIB.T6G(SCH_1):M_J_CPU1_SA_DQ'<22>:
 C_SIGNAL='@t6g_mb_lib.t6g(sch_1):m_j_cpu1_sa_dq(22)';
NODE_NAME     U26 AB16
 '@T6G_MB_LIB.T6G(SCH_1):PAGE46_I159@PURE_QUANTA.GENOA_SP5(CHIPS)':
 'MJA_DATA22': CDS_PINID='MJA_DATA22';
NODE_NAME     J29 181
 '@T6G_MB_LIB.T6G(SCH_1):PAGE106_I22@PURE_QUANTA.SCONN288_DDR506112002KQ(CHIPS)':
 'DQ22_A': CDS_PINID='DQ22_A';
NET_NAME
'M_J_CPU1_SA_DQ<23>'
 '@T6G_MB_LIB.T6G(SCH_1):M_J_CPU1_SA_DQ'<23>:
 C_SIGNAL='@t6g_mb_lib.t6g(sch_1):m_j_cpu1_sa_dq(23)';
NODE_NAME     U26 AC17
 '@T6G_MB_LIB.T6G(SCH_1):PAGE46_I159@PURE_QUANTA.GENOA_SP5(CHIPS)':
 'MJA_DATA23': CDS_PINID='MJA_DATA23';
NODE_NAME     J29 183
 '@T6G_MB_LIB.T6G(SCH_1):PAGE106_I22@PURE_QUANTA.SCONN288_DDR506112002KQ(CHIPS)':
 'DQ23_A': CDS_PINID='DQ23_A';
NET_NAME
'M_J_CPU1_SA_DQ<24>'
 '@T6G_MB_LIB.T6G(SCH_1):M_J_CPU1_SA_DQ'<24>:
 C_SIGNAL='@t6g_mb_lib.t6g(sch_1):m_j_cpu1_sa_dq(24)';
NODE_NAME     U26 AC16
 '@T6G_MB_LIB.T6G(SCH_1):PAGE46_I159@PURE_QUANTA.GENOA_SP5(CHIPS)':
 'MJA_DATA24': CDS_PINID='MJA_DATA24';
NODE_NAME     J29 40
 '@T6G_MB_LIB.T6G(SCH_1):PAGE106_I22@PURE_QUANTA.SCONN288_DDR506112002KQ(CHIPS)':
 'DQ24_A': CDS_PINID='DQ24_A';
NET_NAME
'M_J_CPU1_SA_DQ<25>'
 '@T6G_MB_LIB.T6G(SCH_1):M_J_CPU1_SA_DQ'<25>:
 C_SIGNAL='@t6g_mb_lib.t6g(sch_1):m_j_cpu1_sa_dq(25)';
NODE_NAME     U26 AD18
 '@T6G_MB_LIB.T6G(SCH_1):PAGE46_I159@PURE_QUANTA.GENOA_SP5(CHIPS)':
 'MJA_DATA25': CDS_PINID='MJA_DATA25';
NODE_NAME     J29 42
 '@T6G_MB_LIB.T6G(SCH_1):PAGE106_I22@PURE_QUANTA.SCONN288_DDR506112002KQ(CHIPS)':
 'DQ25_A': CDS_PINID='DQ25_A';
NET_NAME
'M_J_CPU1_SA_DQ<26>'
 '@T6G_MB_LIB.T6G(SCH_1):M_J_CPU1_SA_DQ'<26>:
 C_SIGNAL='@t6g_mb_lib.t6g(sch_1):m_j_cpu1_sa_dq(26)';
NODE_NAME     U26 AD16
 '@T6G_MB_LIB.T6G(SCH_1):PAGE46_I159@PURE_QUANTA.GENOA_SP5(CHIPS)':
 'MJA_DATA26': CDS_PINID='MJA_DATA26';
NODE_NAME     J29 185
 '@T6G_MB_LIB.T6G(SCH_1):PAGE106_I22@PURE_QUANTA.SCONN288_DDR506112002KQ(CHIPS)':
 'DQ26_A': CDS_PINID='DQ26_A';
NET_NAME
'M_J_CPU1_SA_DQ<27>'
 '@T6G_MB_LIB.T6G(SCH_1):M_J_CPU1_SA_DQ'<27>:
 C_SIGNAL='@t6g_mb_lib.t6g(sch_1):m_j_cpu1_sa_dq(27)';
NODE_NAME     U26 AE17
 '@T6G_MB_LIB.T6G(SCH_1):PAGE46_I159@PURE_QUANTA.GENOA_SP5(CHIPS)':
 'MJA_DATA27': CDS_PINID='MJA_DATA27';
NODE_NAME     J29 187
 '@T6G_MB_LIB.T6G(SCH_1):PAGE106_I22@PURE_QUANTA.SCONN288_DDR506112002KQ(CHIPS)':
 'DQ27_A': CDS_PINID='DQ27_A';
NET_NAME
'M_J_CPU1_SA_DQ<28>'
 '@T6G_MB_LIB.T6G(SCH_1):M_J_CPU1_SA_DQ'<28>:
 C_SIGNAL='@t6g_mb_lib.t6g(sch_1):m_j_cpu1_sa_dq(28)';
NODE_NAME     U26 AG16
 '@T6G_MB_LIB.T6G(SCH_1):PAGE46_I159@PURE_QUANTA.GENOA_SP5(CHIPS)':
 'MJA_DATA28': CDS_PINID='MJA_DATA28';
NODE_NAME     J29 47
 '@T6G_MB_LIB.T6G(SCH_1):PAGE106_I22@PURE_QUANTA.SCONN288_DDR506112002KQ(CHIPS)':
 'DQ28_A': CDS_PINID='DQ28_A';
NET_NAME
'M_J_CPU1_SA_DQ<29>'
 '@T6G_MB_LIB.T6G(SCH_1):M_J_CPU1_SA_DQ'<29>:
 C_SIGNAL='@t6g_mb_lib.t6g(sch_1):m_j_cpu1_sa_dq(29)';
NODE_NAME     U26 AH18
 '@T6G_MB_LIB.T6G(SCH_1):PAGE46_I159@PURE_QUANTA.GENOA_SP5(CHIPS)':
 'MJA_DATA29': CDS_PINID='MJA_DATA29';
NODE_NAME     J29 49
 '@T6G_MB_LIB.T6G(SCH_1):PAGE106_I22@PURE_QUANTA.SCONN288_DDR506112002KQ(CHIPS)':
 'DQ29_A': CDS_PINID='DQ29_A';
NET_NAME
'M_J_CPU1_SA_DQ<2>'
 '@T6G_MB_LIB.T6G(SCH_1):M_J_CPU1_SA_DQ'<2>:
 C_SIGNAL='@t6g_mb_lib.t6g(sch_1):m_j_cpu1_sa_dq(2)';
NODE_NAME     U26 F16
 '@T6G_MB_LIB.T6G(SCH_1):PAGE46_I159@PURE_QUANTA.GENOA_SP5(CHIPS)':
 'MJA_DATA2': CDS_PINID='MJA_DATA2';
NODE_NAME     J29 152
 '@T6G_MB_LIB.T6G(SCH_1):PAGE106_I22@PURE_QUANTA.SCONN288_DDR506112002KQ(CHIPS)':
 'DQ2_A': CDS_PINID='DQ2_A';
NET_NAME
'M_J_CPU1_SA_DQ<30>'
 '@T6G_MB_LIB.T6G(SCH_1):M_J_CPU1_SA_DQ'<30>:
 C_SIGNAL='@t6g_mb_lib.t6g(sch_1):m_j_cpu1_sa_dq(30)';
NODE_NAME     U26 AH16
 '@T6G_MB_LIB.T6G(SCH_1):PAGE46_I159@PURE_QUANTA.GENOA_SP5(CHIPS)':
 'MJA_DATA30': CDS_PINID='MJA_DATA30';
NODE_NAME     J29 192
 '@T6G_MB_LIB.T6G(SCH_1):PAGE106_I22@PURE_QUANTA.SCONN288_DDR506112002KQ(CHIPS)':
 'DQ30_A': CDS_PINID='DQ30_A';
NET_NAME
'M_J_CPU1_SA_DQ<31>'
 '@T6G_MB_LIB.T6G(SCH_1):M_J_CPU1_SA_DQ'<31>:
 C_SIGNAL='@t6g_mb_lib.t6g(sch_1):m_j_cpu1_sa_dq(31)';
NODE_NAME     U26 AJ17
 '@T6G_MB_LIB.T6G(SCH_1):PAGE46_I159@PURE_QUANTA.GENOA_SP5(CHIPS)':
 'MJA_DATA31': CDS_PINID='MJA_DATA31';
NODE_NAME     J29 194
 '@T6G_MB_LIB.T6G(SCH_1):PAGE106_I22@PURE_QUANTA.SCONN288_DDR506112002KQ(CHIPS)':
 'DQ31_A': CDS_PINID='DQ31_A';
NET_NAME
'M_J_CPU1_SA_DQ<3>'
 '@T6G_MB_LIB.T6G(SCH_1):M_J_CPU1_SA_DQ'<3>:
 C_SIGNAL='@t6g_mb_lib.t6g(sch_1):m_j_cpu1_sa_dq(3)';
NODE_NAME     U26 G17
 '@T6G_MB_LIB.T6G(SCH_1):PAGE46_I159@PURE_QUANTA.GENOA_SP5(CHIPS)':
 'MJA_DATA3': CDS_PINID='MJA_DATA3';
NODE_NAME     J29 154
 '@T6G_MB_LIB.T6G(SCH_1):PAGE106_I22@PURE_QUANTA.SCONN288_DDR506112002KQ(CHIPS)':
 'DQ3_A': CDS_PINID='DQ3_A';
NET_NAME
'M_J_CPU1_SA_DQ<4>'
 '@T6G_MB_LIB.T6G(SCH_1):M_J_CPU1_SA_DQ'<4>:
 C_SIGNAL='@t6g_mb_lib.t6g(sch_1):m_j_cpu1_sa_dq(4)';
NODE_NAME     U26 J16
 '@T6G_MB_LIB.T6G(SCH_1):PAGE46_I159@PURE_QUANTA.GENOA_SP5(CHIPS)':
 'MJA_DATA4': CDS_PINID='MJA_DATA4';
NODE_NAME     J29 14
 '@T6G_MB_LIB.T6G(SCH_1):PAGE106_I22@PURE_QUANTA.SCONN288_DDR506112002KQ(CHIPS)':
 'DQ4_A': CDS_PINID='DQ4_A';
NET_NAME
'M_J_CPU1_SA_DQ<5>'
 '@T6G_MB_LIB.T6G(SCH_1):M_J_CPU1_SA_DQ'<5>:
 C_SIGNAL='@t6g_mb_lib.t6g(sch_1):m_j_cpu1_sa_dq(5)';
NODE_NAME     U26 K18
 '@T6G_MB_LIB.T6G(SCH_1):PAGE46_I159@PURE_QUANTA.GENOA_SP5(CHIPS)':
 'MJA_DATA5': CDS_PINID='MJA_DATA5';
NODE_NAME     J29 16
 '@T6G_MB_LIB.T6G(SCH_1):PAGE106_I22@PURE_QUANTA.SCONN288_DDR506112002KQ(CHIPS)':
 'DQ5_A': CDS_PINID='DQ5_A';
NET_NAME
'M_J_CPU1_SA_DQ<6>'
 '@T6G_MB_LIB.T6G(SCH_1):M_J_CPU1_SA_DQ'<6>:
 C_SIGNAL='@t6g_mb_lib.t6g(sch_1):m_j_cpu1_sa_dq(6)';
NODE_NAME     U26 K16
 '@T6G_MB_LIB.T6G(SCH_1):PAGE46_I159@PURE_QUANTA.GENOA_SP5(CHIPS)':
 'MJA_DATA6': CDS_PINID='MJA_DATA6';
NODE_NAME     J29 159
 '@T6G_MB_LIB.T6G(SCH_1):PAGE106_I22@PURE_QUANTA.SCONN288_DDR506112002KQ(CHIPS)':
 'DQ6_A': CDS_PINID='DQ6_A';
NET_NAME
'M_J_CPU1_SA_DQ<7>'
 '@T6G_MB_LIB.T6G(SCH_1):M_J_CPU1_SA_DQ'<7>:
 C_SIGNAL='@t6g_mb_lib.t6g(sch_1):m_j_cpu1_sa_dq(7)';
NODE_NAME     U26 L17
 '@T6G_MB_LIB.T6G(SCH_1):PAGE46_I159@PURE_QUANTA.GENOA_SP5(CHIPS)':
 'MJA_DATA7': CDS_PINID='MJA_DATA7';
NODE_NAME     J29 161
 '@T6G_MB_LIB.T6G(SCH_1):PAGE106_I22@PURE_QUANTA.SCONN288_DDR506112002KQ(CHIPS)':
 'DQ7_A': CDS_PINID='DQ7_A';
NET_NAME
'M_J_CPU1_SA_DQ<8>'
 '@T6G_MB_LIB.T6G(SCH_1):M_J_CPU1_SA_DQ'<8>:
 C_SIGNAL='@t6g_mb_lib.t6g(sch_1):m_j_cpu1_sa_dq(8)';
NODE_NAME     U26 L16
 '@T6G_MB_LIB.T6G(SCH_1):PAGE46_I159@PURE_QUANTA.GENOA_SP5(CHIPS)':
 'MJA_DATA8': CDS_PINID='MJA_DATA8';
NODE_NAME     J29 18
 '@T6G_MB_LIB.T6G(SCH_1):PAGE106_I22@PURE_QUANTA.SCONN288_DDR506112002KQ(CHIPS)':
 'DQ8_A': CDS_PINID='DQ8_A';
NET_NAME
'M_J_CPU1_SA_DQ<9>'
 '@T6G_MB_LIB.T6G(SCH_1):M_J_CPU1_SA_DQ'<9>:
 C_SIGNAL='@t6g_mb_lib.t6g(sch_1):m_j_cpu1_sa_dq(9)';
NODE_NAME     U26 M18
 '@T6G_MB_LIB.T6G(SCH_1):PAGE46_I159@PURE_QUANTA.GENOA_SP5(CHIPS)':
 'MJA_DATA9': CDS_PINID='MJA_DATA9';
NODE_NAME     J29 20
 '@T6G_MB_LIB.T6G(SCH_1):PAGE106_I22@PURE_QUANTA.SCONN288_DDR506112002KQ(CHIPS)':
 'DQ9_A': CDS_PINID='DQ9_A';
NET_NAME
'M_J_CPU1_SA_DQS_DN<0>'
 '@T6G_MB_LIB.T6G(SCH_1):M_J_CPU1_SA_DQS_DN'<0>:
 C_SIGNAL='@t6g_mb_lib.t6g(sch_1):m_j_cpu1_sa_dqs_dn(0)';
NODE_NAME     U26 H16
 '@T6G_MB_LIB.T6G(SCH_1):PAGE46_I159@PURE_QUANTA.GENOA_SP5(CHIPS)':
 'MJA_DQS_L0': CDS_PINID='MJA_DQS_L0';
NODE_NAME     J29 12
 '@T6G_MB_LIB.T6G(SCH_1):PAGE106_I236@PURE_QUANTA.SCONN288_DDR506112002KQ(CHIPS)':
 'DQS0_A_C': CDS_PINID='DQS0_A_C';
NET_NAME
'M_J_CPU1_SA_DQS_DN<1>'
 '@T6G_MB_LIB.T6G(SCH_1):M_J_CPU1_SA_DQS_DN'<1>:
 C_SIGNAL='@t6g_mb_lib.t6g(sch_1):m_j_cpu1_sa_dqs_dn(1)';
NODE_NAME     U26 P16
 '@T6G_MB_LIB.T6G(SCH_1):PAGE46_I159@PURE_QUANTA.GENOA_SP5(CHIPS)':
 'MJA_DQS_L1': CDS_PINID='MJA_DQS_L1';
NODE_NAME     J29 23
 '@T6G_MB_LIB.T6G(SCH_1):PAGE106_I236@PURE_QUANTA.SCONN288_DDR506112002KQ(CHIPS)':
 'DQS1_A_C': CDS_PINID='DQS1_A_C';
NET_NAME
'M_J_CPU1_SA_DQS_DN<2>'
 '@T6G_MB_LIB.T6G(SCH_1):M_J_CPU1_SA_DQS_DN'<2>:
 C_SIGNAL='@t6g_mb_lib.t6g(sch_1):m_j_cpu1_sa_dqs_dn(2)';
NODE_NAME     U26 Y16
 '@T6G_MB_LIB.T6G(SCH_1):PAGE46_I159@PURE_QUANTA.GENOA_SP5(CHIPS)':
 'MJA_DQS_L2': CDS_PINID='MJA_DQS_L2';
NODE_NAME     J29 34
 '@T6G_MB_LIB.T6G(SCH_1):PAGE106_I236@PURE_QUANTA.SCONN288_DDR506112002KQ(CHIPS)':
 'DQS2_A_C': CDS_PINID='DQS2_A_C';
NET_NAME
'M_J_CPU1_SA_DQS_DN<3>'
 '@T6G_MB_LIB.T6G(SCH_1):M_J_CPU1_SA_DQS_DN'<3>:
 C_SIGNAL='@t6g_mb_lib.t6g(sch_1):m_j_cpu1_sa_dqs_dn(3)';
NODE_NAME     U26 AF16
 '@T6G_MB_LIB.T6G(SCH_1):PAGE46_I159@PURE_QUANTA.GENOA_SP5(CHIPS)':
 'MJA_DQS_L3': CDS_PINID='MJA_DQS_L3';
NODE_NAME     J29 45
 '@T6G_MB_LIB.T6G(SCH_1):PAGE106_I236@PURE_QUANTA.SCONN288_DDR506112002KQ(CHIPS)':
 'DQS3_A_C': CDS_PINID='DQS3_A_C';
NET_NAME
'M_J_CPU1_SA_DQS_DN<4>'
 '@T6G_MB_LIB.T6G(SCH_1):M_J_CPU1_SA_DQS_DN'<4>:
 C_SIGNAL='@t6g_mb_lib.t6g(sch_1):m_j_cpu1_sa_dqs_dn(4)';
NODE_NAME     U26 AM16
 '@T6G_MB_LIB.T6G(SCH_1):PAGE46_I159@PURE_QUANTA.GENOA_SP5(CHIPS)':
 'MJA_DQS_L4': CDS_PINID='MJA_DQS_L4';
NODE_NAME     J29 56
 '@T6G_MB_LIB.T6G(SCH_1):PAGE106_I236@PURE_QUANTA.SCONN288_DDR506112002KQ(CHIPS)':
 'DQS4_A_C': CDS_PINID='DQS4_A_C';
NET_NAME
'M_J_CPU1_SA_DQS_DN<5>'
 '@T6G_MB_LIB.T6G(SCH_1):M_J_CPU1_SA_DQS_DN'<5>:
 C_SIGNAL='@t6g_mb_lib.t6g(sch_1):m_j_cpu1_sa_dqs_dn(5)';
NODE_NAME     U26 H18
 '@T6G_MB_LIB.T6G(SCH_1):PAGE46_I159@PURE_QUANTA.GENOA_SP5(CHIPS)':
 'MJA_DQS_L5': CDS_PINID='MJA_DQS_L5';
NODE_NAME     J29 156
 '@T6G_MB_LIB.T6G(SCH_1):PAGE106_I236@PURE_QUANTA.SCONN288_DDR506112002KQ(CHIPS)':
 'DQS5_A_C||TDQS5_A_C||DQS5_A_T||TDQS5_A_T': CDS_PINID='\dqs5_a_c||tdqs5_a_c||dqs5_a_t||tdqs5_a_t\';
NET_NAME
'M_J_CPU1_SA_DQS_DN<6>'
 '@T6G_MB_LIB.T6G(SCH_1):M_J_CPU1_SA_DQS_DN'<6>:
 C_SIGNAL='@t6g_mb_lib.t6g(sch_1):m_j_cpu1_sa_dqs_dn(6)';
NODE_NAME     U26 P18
 '@T6G_MB_LIB.T6G(SCH_1):PAGE46_I159@PURE_QUANTA.GENOA_SP5(CHIPS)':
 'MJA_DQS_L6': CDS_PINID='MJA_DQS_L6';
NODE_NAME     J29 167
 '@T6G_MB_LIB.T6G(SCH_1):PAGE106_I236@PURE_QUANTA.SCONN288_DDR506112002KQ(CHIPS)':
 'DQS6_A_C||TDQS6_A_C||DQS6_A_T||TDQS6_A_T': CDS_PINID='\dqs6_a_c||tdqs6_a_c||dqs6_a_t||tdqs6_a_t\';
NET_NAME
'M_J_CPU1_SA_DQS_DN<7>'
 '@T6G_MB_LIB.T6G(SCH_1):M_J_CPU1_SA_DQS_DN'<7>:
 C_SIGNAL='@t6g_mb_lib.t6g(sch_1):m_j_cpu1_sa_dqs_dn(7)';
NODE_NAME     U26 Y18
 '@T6G_MB_LIB.T6G(SCH_1):PAGE46_I159@PURE_QUANTA.GENOA_SP5(CHIPS)':
 'MJA_DQS_L7': CDS_PINID='MJA_DQS_L7';
NODE_NAME     J29 178
 '@T6G_MB_LIB.T6G(SCH_1):PAGE106_I236@PURE_QUANTA.SCONN288_DDR506112002KQ(CHIPS)':
 'DQS7_A_C||TDQS7_A_C': CDS_PINID='\dqs7_a_c||tdqs7_a_c\';
NET_NAME
'M_J_CPU1_SA_DQS_DN<8>'
 '@T6G_MB_LIB.T6G(SCH_1):M_J_CPU1_SA_DQS_DN'<8>:
 C_SIGNAL='@t6g_mb_lib.t6g(sch_1):m_j_cpu1_sa_dqs_dn(8)';
NODE_NAME     U26 AF18
 '@T6G_MB_LIB.T6G(SCH_1):PAGE46_I159@PURE_QUANTA.GENOA_SP5(CHIPS)':
 'MJA_DQS_L8': CDS_PINID='MJA_DQS_L8';
NODE_NAME     J29 189
 '@T6G_MB_LIB.T6G(SCH_1):PAGE106_I236@PURE_QUANTA.SCONN288_DDR506112002KQ(CHIPS)':
 'DQS8_A_C||TDQS8_A_C': CDS_PINID='\dqs8_a_c||tdqs8_a_c\';
NET_NAME
'M_J_CPU1_SA_DQS_DN<9>'
 '@T6G_MB_LIB.T6G(SCH_1):M_J_CPU1_SA_DQS_DN'<9>:
 C_SIGNAL='@t6g_mb_lib.t6g(sch_1):m_j_cpu1_sa_dqs_dn(9)';
NODE_NAME     U26 AM18
 '@T6G_MB_LIB.T6G(SCH_1):PAGE46_I159@PURE_QUANTA.GENOA_SP5(CHIPS)':
 'MJA_DQS_L9': CDS_PINID='MJA_DQS_L9';
NODE_NAME     J29 200
 '@T6G_MB_LIB.T6G(SCH_1):PAGE106_I236@PURE_QUANTA.SCONN288_DDR506112002KQ(CHIPS)':
 'DQS9_A_C||TDQS9_A_C': CDS_PINID='\dqs9_a_c||tdqs9_a_c\';
NET_NAME
'M_J_CPU1_SA_DQS_DP<0>'
 '@T6G_MB_LIB.T6G(SCH_1):M_J_CPU1_SA_DQS_DP'<0>:
 C_SIGNAL='@t6g_mb_lib.t6g(sch_1):m_j_cpu1_sa_dqs_dp(0)';
NODE_NAME     U26 G16
 '@T6G_MB_LIB.T6G(SCH_1):PAGE46_I159@PURE_QUANTA.GENOA_SP5(CHIPS)':
 'MJA_DQS_H0': CDS_PINID='MJA_DQS_H0';
NODE_NAME     J29 11
 '@T6G_MB_LIB.T6G(SCH_1):PAGE106_I236@PURE_QUANTA.SCONN288_DDR506112002KQ(CHIPS)':
 'DQS0_A_T': CDS_PINID='DQS0_A_T';
NET_NAME
'M_J_CPU1_SA_DQS_DP<1>'
 '@T6G_MB_LIB.T6G(SCH_1):M_J_CPU1_SA_DQS_DP'<1>:
 C_SIGNAL='@t6g_mb_lib.t6g(sch_1):m_j_cpu1_sa_dqs_dp(1)';
NODE_NAME     U26 N16
 '@T6G_MB_LIB.T6G(SCH_1):PAGE46_I159@PURE_QUANTA.GENOA_SP5(CHIPS)':
 'MJA_DQS_H1': CDS_PINID='MJA_DQS_H1';
NODE_NAME     J29 22
 '@T6G_MB_LIB.T6G(SCH_1):PAGE106_I236@PURE_QUANTA.SCONN288_DDR506112002KQ(CHIPS)':
 'DQS1_A_T': CDS_PINID='DQS1_A_T';
NET_NAME
'M_J_CPU1_SA_DQS_DP<2>'
 '@T6G_MB_LIB.T6G(SCH_1):M_J_CPU1_SA_DQS_DP'<2>:
 C_SIGNAL='@t6g_mb_lib.t6g(sch_1):m_j_cpu1_sa_dqs_dp(2)';
NODE_NAME     U26 W16
 '@T6G_MB_LIB.T6G(SCH_1):PAGE46_I159@PURE_QUANTA.GENOA_SP5(CHIPS)':
 'MJA_DQS_H2': CDS_PINID='MJA_DQS_H2';
NODE_NAME     J29 33
 '@T6G_MB_LIB.T6G(SCH_1):PAGE106_I236@PURE_QUANTA.SCONN288_DDR506112002KQ(CHIPS)':
 'DQS2_A_T': CDS_PINID='DQS2_A_T';
NET_NAME
'M_J_CPU1_SA_DQS_DP<3>'
 '@T6G_MB_LIB.T6G(SCH_1):M_J_CPU1_SA_DQS_DP'<3>:
 C_SIGNAL='@t6g_mb_lib.t6g(sch_1):m_j_cpu1_sa_dqs_dp(3)';
NODE_NAME     U26 AE16
 '@T6G_MB_LIB.T6G(SCH_1):PAGE46_I159@PURE_QUANTA.GENOA_SP5(CHIPS)':
 'MJA_DQS_H3': CDS_PINID='MJA_DQS_H3';
NODE_NAME     J29 44
 '@T6G_MB_LIB.T6G(SCH_1):PAGE106_I236@PURE_QUANTA.SCONN288_DDR506112002KQ(CHIPS)':
 'DQS3_A_T': CDS_PINID='DQS3_A_T';
NET_NAME
'M_J_CPU1_SA_DQS_DP<4>'
 '@T6G_MB_LIB.T6G(SCH_1):M_J_CPU1_SA_DQS_DP'<4>:
 C_SIGNAL='@t6g_mb_lib.t6g(sch_1):m_j_cpu1_sa_dqs_dp(4)';
NODE_NAME     U26 AL16
 '@T6G_MB_LIB.T6G(SCH_1):PAGE46_I159@PURE_QUANTA.GENOA_SP5(CHIPS)':
 'MJA_DQS_H4': CDS_PINID='MJA_DQS_H4';
NODE_NAME     J29 55
 '@T6G_MB_LIB.T6G(SCH_1):PAGE106_I236@PURE_QUANTA.SCONN288_DDR506112002KQ(CHIPS)':
 'DQS4_A_T': CDS_PINID='DQS4_A_T';
NET_NAME
'M_J_CPU1_SA_DQS_DP<5>'
 '@T6G_MB_LIB.T6G(SCH_1):M_J_CPU1_SA_DQS_DP'<5>:
 C_SIGNAL='@t6g_mb_lib.t6g(sch_1):m_j_cpu1_sa_dqs_dp(5)';
NODE_NAME     U26 J17
 '@T6G_MB_LIB.T6G(SCH_1):PAGE46_I159@PURE_QUANTA.GENOA_SP5(CHIPS)':
 'MJA_DQS_H5': CDS_PINID='MJA_DQS_H5';
NODE_NAME     J29 157
 '@T6G_MB_LIB.T6G(SCH_1):PAGE106_I236@PURE_QUANTA.SCONN288_DDR506112002KQ(CHIPS)':
 'DQS5_A_T||TDQS5_A_T': CDS_PINID='\dqs5_a_t||tdqs5_a_t\';
NET_NAME
'M_J_CPU1_SA_DQS_DP<6>'
 '@T6G_MB_LIB.T6G(SCH_1):M_J_CPU1_SA_DQS_DP'<6>:
 C_SIGNAL='@t6g_mb_lib.t6g(sch_1):m_j_cpu1_sa_dqs_dp(6)';
NODE_NAME     U26 R17
 '@T6G_MB_LIB.T6G(SCH_1):PAGE46_I159@PURE_QUANTA.GENOA_SP5(CHIPS)':
 'MJA_DQS_H6': CDS_PINID='MJA_DQS_H6';
NODE_NAME     J29 168
 '@T6G_MB_LIB.T6G(SCH_1):PAGE106_I236@PURE_QUANTA.SCONN288_DDR506112002KQ(CHIPS)':
 'DQS6_A_T||TDQS6_A_T': CDS_PINID='\dqs6_a_t||tdqs6_a_t\';
NET_NAME
'M_J_CPU1_SA_DQS_DP<7>'
 '@T6G_MB_LIB.T6G(SCH_1):M_J_CPU1_SA_DQS_DP'<7>:
 C_SIGNAL='@t6g_mb_lib.t6g(sch_1):m_j_cpu1_sa_dqs_dp(7)';
NODE_NAME     U26 AA17
 '@T6G_MB_LIB.T6G(SCH_1):PAGE46_I159@PURE_QUANTA.GENOA_SP5(CHIPS)':
 'MJA_DQS_H7': CDS_PINID='MJA_DQS_H7';
NODE_NAME     J29 179
 '@T6G_MB_LIB.T6G(SCH_1):PAGE106_I236@PURE_QUANTA.SCONN288_DDR506112002KQ(CHIPS)':
 'DQS7_A_T||TDQS7_A_T': CDS_PINID='\dqs7_a_t||tdqs7_a_t\';
NET_NAME
'M_J_CPU1_SA_DQS_DP<8>'
 '@T6G_MB_LIB.T6G(SCH_1):M_J_CPU1_SA_DQS_DP'<8>:
 C_SIGNAL='@t6g_mb_lib.t6g(sch_1):m_j_cpu1_sa_dqs_dp(8)';
NODE_NAME     U26 AG17
 '@T6G_MB_LIB.T6G(SCH_1):PAGE46_I159@PURE_QUANTA.GENOA_SP5(CHIPS)':
 'MJA_DQS_H8': CDS_PINID='MJA_DQS_H8';
NODE_NAME     J29 190
 '@T6G_MB_LIB.T6G(SCH_1):PAGE106_I236@PURE_QUANTA.SCONN288_DDR506112002KQ(CHIPS)':
 'DQS8_A_T||TDQS8_A_T': CDS_PINID='\dqs8_a_t||tdqs8_a_t\';
NET_NAME
'M_J_CPU1_SA_DQS_DP<9>'
 '@T6G_MB_LIB.T6G(SCH_1):M_J_CPU1_SA_DQS_DP'<9>:
 C_SIGNAL='@t6g_mb_lib.t6g(sch_1):m_j_cpu1_sa_dqs_dp(9)';
NODE_NAME     U26 AN17
 '@T6G_MB_LIB.T6G(SCH_1):PAGE46_I159@PURE_QUANTA.GENOA_SP5(CHIPS)':
 'MJA_DQS_H9': CDS_PINID='MJA_DQS_H9';
NODE_NAME     J29 201
 '@T6G_MB_LIB.T6G(SCH_1):PAGE106_I236@PURE_QUANTA.SCONN288_DDR506112002KQ(CHIPS)':
 'DQS9_A_T||TDQS9_A_T': CDS_PINID='\dqs9_a_t||tdqs9_a_t\';
NET_NAME
'M_J_CPU1_SA_PAR'
 '@T6G_MB_LIB.T6G(SCH_1):M_J_CPU1_SA_PAR':
 C_SIGNAL='@t6g_mb_lib.t6g(sch_1):m_j_cpu1_sa_par';
NODE_NAME     U26 BC17
 '@T6G_MB_LIB.T6G(SCH_1):PAGE46_I159@PURE_QUANTA.GENOA_SP5(CHIPS)':
 'MJA_PAR': CDS_PINID='MJA_PAR';
NODE_NAME     J29 74
 '@T6G_MB_LIB.T6G(SCH_1):PAGE106_I22@PURE_QUANTA.SCONN288_DDR506112002KQ(CHIPS)':
 'PAR_A': CDS_PINID='PAR_A';
NET_NAME
'M_J_CPU1_SA_RSP<0>'
 '@T6G_MB_LIB.T6G(SCH_1):M_J_CPU1_SA_RSP'<0>:
 C_SIGNAL='@t6g_mb_lib.t6g(sch_1):m_j_cpu1_sa_rsp(0)';
NODE_NAME     U26 BN17
 '@T6G_MB_LIB.T6G(SCH_1):PAGE46_I159@PURE_QUANTA.GENOA_SP5(CHIPS)':
 'MJA0_RSP_L': CDS_PINID='MJA0_RSP_L';
NODE_NAME     J29 86
 '@T6G_MB_LIB.T6G(SCH_1):PAGE106_I22@PURE_QUANTA.SCONN288_DDR506112002KQ(CHIPS)':
 'LBD||RSP_A_N': CDS_PINID='\lbd||rsp_a_n\';
NET_NAME
'M_J_CPU1_SB_CA<0>'
 '@T6G_MB_LIB.T6G(SCH_1):M_J_CPU1_SB_CA'<0>:
 C_SIGNAL='@t6g_mb_lib.t6g(sch_1):m_j_cpu1_sb_ca(0)';
NODE_NAME     U26 BG17
 '@T6G_MB_LIB.T6G(SCH_1):PAGE46_I159@PURE_QUANTA.GENOA_SP5(CHIPS)':
 'MJB_CA0': CDS_PINID='MJB_CA0';
NODE_NAME     J29 76
 '@T6G_MB_LIB.T6G(SCH_1):PAGE106_I22@PURE_QUANTA.SCONN288_DDR506112002KQ(CHIPS)':
 'CA0_B': CDS_PINID='CA0_B';
NET_NAME
'M_J_CPU1_SB_CA<1>'
 '@T6G_MB_LIB.T6G(SCH_1):M_J_CPU1_SB_CA'<1>:
 C_SIGNAL='@t6g_mb_lib.t6g(sch_1):m_j_cpu1_sb_ca(1)';
NODE_NAME     U26 BH18
 '@T6G_MB_LIB.T6G(SCH_1):PAGE46_I159@PURE_QUANTA.GENOA_SP5(CHIPS)':
 'MJB_CA1': CDS_PINID='MJB_CA1';
NODE_NAME     J29 221
 '@T6G_MB_LIB.T6G(SCH_1):PAGE106_I22@PURE_QUANTA.SCONN288_DDR506112002KQ(CHIPS)':
 'CA1_B': CDS_PINID='CA1_B';
NET_NAME
'M_J_CPU1_SB_CA<2>'
 '@T6G_MB_LIB.T6G(SCH_1):M_J_CPU1_SB_CA'<2>:
 C_SIGNAL='@t6g_mb_lib.t6g(sch_1):m_j_cpu1_sb_ca(2)';
NODE_NAME     U26 BH16
 '@T6G_MB_LIB.T6G(SCH_1):PAGE46_I159@PURE_QUANTA.GENOA_SP5(CHIPS)':
 'MJB_CA2': CDS_PINID='MJB_CA2';
NODE_NAME     J29 78
 '@T6G_MB_LIB.T6G(SCH_1):PAGE106_I22@PURE_QUANTA.SCONN288_DDR506112002KQ(CHIPS)':
 'CA2_B': CDS_PINID='CA2_B';
NET_NAME
'M_J_CPU1_SB_CA<3>'
 '@T6G_MB_LIB.T6G(SCH_1):M_J_CPU1_SB_CA'<3>:
 C_SIGNAL='@t6g_mb_lib.t6g(sch_1):m_j_cpu1_sb_ca(3)';
NODE_NAME     U26 BJ16
 '@T6G_MB_LIB.T6G(SCH_1):PAGE46_I159@PURE_QUANTA.GENOA_SP5(CHIPS)':
 'MJB_CA3': CDS_PINID='MJB_CA3';
NODE_NAME     J29 223
 '@T6G_MB_LIB.T6G(SCH_1):PAGE106_I22@PURE_QUANTA.SCONN288_DDR506112002KQ(CHIPS)':
 'CA3_B': CDS_PINID='CA3_B';
NET_NAME
'M_J_CPU1_SB_CA<4>'
 '@T6G_MB_LIB.T6G(SCH_1):M_J_CPU1_SB_CA'<4>:
 C_SIGNAL='@t6g_mb_lib.t6g(sch_1):m_j_cpu1_sb_ca(4)';
NODE_NAME     U26 BJ17
 '@T6G_MB_LIB.T6G(SCH_1):PAGE46_I159@PURE_QUANTA.GENOA_SP5(CHIPS)':
 'MJB_CA4': CDS_PINID='MJB_CA4';
NODE_NAME     J29 80
 '@T6G_MB_LIB.T6G(SCH_1):PAGE106_I22@PURE_QUANTA.SCONN288_DDR506112002KQ(CHIPS)':
 'CA4_B': CDS_PINID='CA4_B';
NET_NAME
'M_J_CPU1_SB_CA<5>'
 '@T6G_MB_LIB.T6G(SCH_1):M_J_CPU1_SB_CA'<5>:
 C_SIGNAL='@t6g_mb_lib.t6g(sch_1):m_j_cpu1_sb_ca(5)';
NODE_NAME     U26 BK18
 '@T6G_MB_LIB.T6G(SCH_1):PAGE46_I159@PURE_QUANTA.GENOA_SP5(CHIPS)':
 'MJB_CA5': CDS_PINID='MJB_CA5';
NODE_NAME     J29 225
 '@T6G_MB_LIB.T6G(SCH_1):PAGE106_I22@PURE_QUANTA.SCONN288_DDR506112002KQ(CHIPS)':
 'CA5_B': CDS_PINID='CA5_B';
NET_NAME
'M_J_CPU1_SB_CA<6>'
 '@T6G_MB_LIB.T6G(SCH_1):M_J_CPU1_SB_CA'<6>:
 C_SIGNAL='@t6g_mb_lib.t6g(sch_1):m_j_cpu1_sb_ca(6)';
NODE_NAME     U26 BK16
 '@T6G_MB_LIB.T6G(SCH_1):PAGE46_I159@PURE_QUANTA.GENOA_SP5(CHIPS)':
 'MJB_CA6': CDS_PINID='MJB_CA6';
NODE_NAME     J29 82
 '@T6G_MB_LIB.T6G(SCH_1):PAGE106_I22@PURE_QUANTA.SCONN288_DDR506112002KQ(CHIPS)':
 'CA6_B': CDS_PINID='CA6_B';
NET_NAME
'M_J_CPU1_SB_CB<0>'
 '@T6G_MB_LIB.T6G(SCH_1):M_J_CPU1_SB_CB'<0>:
 C_SIGNAL='@t6g_mb_lib.t6g(sch_1):m_j_cpu1_sb_cb(0)';
NODE_NAME     U26 BY16
 '@T6G_MB_LIB.T6G(SCH_1):PAGE46_I159@PURE_QUANTA.GENOA_SP5(CHIPS)':
 'MJB_CHECK0': CDS_PINID='MJB_CHECK0';
NODE_NAME     J29 96
 '@T6G_MB_LIB.T6G(SCH_1):PAGE106_I22@PURE_QUANTA.SCONN288_DDR506112002KQ(CHIPS)':
 'CB0_B': CDS_PINID='CB0_B';
NET_NAME
'M_J_CPU1_SB_CB<1>'
 '@T6G_MB_LIB.T6G(SCH_1):M_J_CPU1_SB_CB'<1>:
 C_SIGNAL='@t6g_mb_lib.t6g(sch_1):m_j_cpu1_sb_cb(1)';
NODE_NAME     U26 CA17
 '@T6G_MB_LIB.T6G(SCH_1):PAGE46_I159@PURE_QUANTA.GENOA_SP5(CHIPS)':
 'MJB_CHECK1': CDS_PINID='MJB_CHECK1';
NODE_NAME     J29 98
 '@T6G_MB_LIB.T6G(SCH_1):PAGE106_I22@PURE_QUANTA.SCONN288_DDR506112002KQ(CHIPS)':
 'CB1_B': CDS_PINID='CB1_B';
NET_NAME
'M_J_CPU1_SB_CB<2>'
 '@T6G_MB_LIB.T6G(SCH_1):M_J_CPU1_SB_CB'<2>:
 C_SIGNAL='@t6g_mb_lib.t6g(sch_1):m_j_cpu1_sb_cb(2)';
NODE_NAME     U26 CA16
 '@T6G_MB_LIB.T6G(SCH_1):PAGE46_I159@PURE_QUANTA.GENOA_SP5(CHIPS)':
 'MJB_CHECK2': CDS_PINID='MJB_CHECK2';
NODE_NAME     J29 241
 '@T6G_MB_LIB.T6G(SCH_1):PAGE106_I22@PURE_QUANTA.SCONN288_DDR506112002KQ(CHIPS)':
 'CB2_B': CDS_PINID='CB2_B';
NET_NAME
'M_J_CPU1_SB_CB<3>'
 '@T6G_MB_LIB.T6G(SCH_1):M_J_CPU1_SB_CB'<3>:
 C_SIGNAL='@t6g_mb_lib.t6g(sch_1):m_j_cpu1_sb_cb(3)';
NODE_NAME     U26 CB18
 '@T6G_MB_LIB.T6G(SCH_1):PAGE46_I159@PURE_QUANTA.GENOA_SP5(CHIPS)':
 'MJB_CHECK3': CDS_PINID='MJB_CHECK3';
NODE_NAME     J29 243
 '@T6G_MB_LIB.T6G(SCH_1):PAGE106_I22@PURE_QUANTA.SCONN288_DDR506112002KQ(CHIPS)':
 'CB3_B': CDS_PINID='CB3_B';
NET_NAME
'M_J_CPU1_SB_CB<4>'
 '@T6G_MB_LIB.T6G(SCH_1):M_J_CPU1_SB_CB'<4>:
 C_SIGNAL='@t6g_mb_lib.t6g(sch_1):m_j_cpu1_sb_cb(4)';
NODE_NAME     U26 BT16
 '@T6G_MB_LIB.T6G(SCH_1):PAGE46_I159@PURE_QUANTA.GENOA_SP5(CHIPS)':
 'MJB_CHECK4': CDS_PINID='MJB_CHECK4';
NODE_NAME     J29 89
 '@T6G_MB_LIB.T6G(SCH_1):PAGE106_I22@PURE_QUANTA.SCONN288_DDR506112002KQ(CHIPS)':
 'CB4_B': CDS_PINID='CB4_B';
NET_NAME
'M_J_CPU1_SB_CB<5>'
 '@T6G_MB_LIB.T6G(SCH_1):M_J_CPU1_SB_CB'<5>:
 C_SIGNAL='@t6g_mb_lib.t6g(sch_1):m_j_cpu1_sb_cb(5)';
NODE_NAME     U26 BU17
 '@T6G_MB_LIB.T6G(SCH_1):PAGE46_I159@PURE_QUANTA.GENOA_SP5(CHIPS)':
 'MJB_CHECK5': CDS_PINID='MJB_CHECK5';
NODE_NAME     J29 91
 '@T6G_MB_LIB.T6G(SCH_1):PAGE106_I22@PURE_QUANTA.SCONN288_DDR506112002KQ(CHIPS)':
 'CB5_B': CDS_PINID='CB5_B';
NET_NAME
'M_J_CPU1_SB_CB<6>'
 '@T6G_MB_LIB.T6G(SCH_1):M_J_CPU1_SB_CB'<6>:
 C_SIGNAL='@t6g_mb_lib.t6g(sch_1):m_j_cpu1_sb_cb(6)';
NODE_NAME     U26 BU16
 '@T6G_MB_LIB.T6G(SCH_1):PAGE46_I159@PURE_QUANTA.GENOA_SP5(CHIPS)':
 'MJB_CHECK6': CDS_PINID='MJB_CHECK6';
NODE_NAME     J29 234
 '@T6G_MB_LIB.T6G(SCH_1):PAGE106_I22@PURE_QUANTA.SCONN288_DDR506112002KQ(CHIPS)':
 'CB6_B': CDS_PINID='CB6_B';
NET_NAME
'M_J_CPU1_SB_CB<7>'
 '@T6G_MB_LIB.T6G(SCH_1):M_J_CPU1_SB_CB'<7>:
 C_SIGNAL='@t6g_mb_lib.t6g(sch_1):m_j_cpu1_sb_cb(7)';
NODE_NAME     U26 BV18
 '@T6G_MB_LIB.T6G(SCH_1):PAGE46_I159@PURE_QUANTA.GENOA_SP5(CHIPS)':
 'MJB_CHECK7': CDS_PINID='MJB_CHECK7';
NODE_NAME     J29 236
 '@T6G_MB_LIB.T6G(SCH_1):PAGE106_I22@PURE_QUANTA.SCONN288_DDR506112002KQ(CHIPS)':
 'CB7_B': CDS_PINID='CB7_B';
NET_NAME
'M_J_CPU1_SB_CS_N<0>'
 '@T6G_MB_LIB.T6G(SCH_1):M_J_CPU1_SB_CS_N'<0>:
 C_SIGNAL='@t6g_mb_lib.t6g(sch_1):m_j_cpu1_sb_cs_n(0)';
NODE_NAME     U26 BM18
 '@T6G_MB_LIB.T6G(SCH_1):PAGE46_I159@PURE_QUANTA.GENOA_SP5(CHIPS)':
 'MJB0_CS_L0': CDS_PINID='MJB0_CS_L0';
NODE_NAME     J29 84
 '@T6G_MB_LIB.T6G(SCH_1):PAGE106_I22@PURE_QUANTA.SCONN288_DDR506112002KQ(CHIPS)':
 'CS0_B_N': CDS_PINID='CS0_B_N';
NET_NAME
'M_J_CPU1_SB_CS_N<1>'
 '@T6G_MB_LIB.T6G(SCH_1):M_J_CPU1_SB_CS_N'<1>:
 C_SIGNAL='@t6g_mb_lib.t6g(sch_1):m_j_cpu1_sb_cs_n(1)';
NODE_NAME     U26 BN16
 '@T6G_MB_LIB.T6G(SCH_1):PAGE46_I159@PURE_QUANTA.GENOA_SP5(CHIPS)':
 'MJB0_CS_L1': CDS_PINID='MJB0_CS_L1';
NODE_NAME     J29 229
 '@T6G_MB_LIB.T6G(SCH_1):PAGE106_I22@PURE_QUANTA.SCONN288_DDR506112002KQ(CHIPS)':
 'CS1_B_N': CDS_PINID='CS1_B_N';
NET_NAME
'M_J_CPU1_SB_DQ<0>'
 '@T6G_MB_LIB.T6G(SCH_1):M_J_CPU1_SB_DQ'<0>:
 C_SIGNAL='@t6g_mb_lib.t6g(sch_1):m_j_cpu1_sb_dq(0)';
NODE_NAME     U26 CB16
 '@T6G_MB_LIB.T6G(SCH_1):PAGE46_I159@PURE_QUANTA.GENOA_SP5(CHIPS)':
 'MJB_DATA0': CDS_PINID='MJB_DATA0';
NODE_NAME     J29 100
 '@T6G_MB_LIB.T6G(SCH_1):PAGE106_I22@PURE_QUANTA.SCONN288_DDR506112002KQ(CHIPS)':
 'DQ0_B': CDS_PINID='DQ0_B';
NET_NAME
'M_J_CPU1_SB_DQ<10>'
 '@T6G_MB_LIB.T6G(SCH_1):M_J_CPU1_SB_DQ'<10>:
 C_SIGNAL='@t6g_mb_lib.t6g(sch_1):m_j_cpu1_sb_dq(10)';
NODE_NAME     U26 CJ16
 '@T6G_MB_LIB.T6G(SCH_1):PAGE46_I159@PURE_QUANTA.GENOA_SP5(CHIPS)':
 'MJB_DATA10': CDS_PINID='MJB_DATA10';
NODE_NAME     J29 256
 '@T6G_MB_LIB.T6G(SCH_1):PAGE106_I22@PURE_QUANTA.SCONN288_DDR506112002KQ(CHIPS)':
 'DQ10_B': CDS_PINID='DQ10_B';
NET_NAME
'M_J_CPU1_SB_DQ<11>'
 '@T6G_MB_LIB.T6G(SCH_1):M_J_CPU1_SB_DQ'<11>:
 C_SIGNAL='@t6g_mb_lib.t6g(sch_1):m_j_cpu1_sb_dq(11)';
NODE_NAME     U26 CK18
 '@T6G_MB_LIB.T6G(SCH_1):PAGE46_I159@PURE_QUANTA.GENOA_SP5(CHIPS)':
 'MJB_DATA11': CDS_PINID='MJB_DATA11';
NODE_NAME     J29 258
 '@T6G_MB_LIB.T6G(SCH_1):PAGE106_I22@PURE_QUANTA.SCONN288_DDR506112002KQ(CHIPS)':
 'DQ11_B': CDS_PINID='DQ11_B';
NET_NAME
'M_J_CPU1_SB_DQ<12>'
 '@T6G_MB_LIB.T6G(SCH_1):M_J_CPU1_SB_DQ'<12>:
 C_SIGNAL='@t6g_mb_lib.t6g(sch_1):m_j_cpu1_sb_dq(12)';
NODE_NAME     U26 CM16
 '@T6G_MB_LIB.T6G(SCH_1):PAGE46_I159@PURE_QUANTA.GENOA_SP5(CHIPS)':
 'MJB_DATA12': CDS_PINID='MJB_DATA12';
NODE_NAME     J29 118
 '@T6G_MB_LIB.T6G(SCH_1):PAGE106_I22@PURE_QUANTA.SCONN288_DDR506112002KQ(CHIPS)':
 'DQ12_B': CDS_PINID='DQ12_B';
NET_NAME
'M_J_CPU1_SB_DQ<13>'
 '@T6G_MB_LIB.T6G(SCH_1):M_J_CPU1_SB_DQ'<13>:
 C_SIGNAL='@t6g_mb_lib.t6g(sch_1):m_j_cpu1_sb_dq(13)';
NODE_NAME     U26 CN17
 '@T6G_MB_LIB.T6G(SCH_1):PAGE46_I159@PURE_QUANTA.GENOA_SP5(CHIPS)':
 'MJB_DATA13': CDS_PINID='MJB_DATA13';
NODE_NAME     J29 120
 '@T6G_MB_LIB.T6G(SCH_1):PAGE106_I22@PURE_QUANTA.SCONN288_DDR506112002KQ(CHIPS)':
 'DQ13_B': CDS_PINID='DQ13_B';
NET_NAME
'M_J_CPU1_SB_DQ<14>'
 '@T6G_MB_LIB.T6G(SCH_1):M_J_CPU1_SB_DQ'<14>:
 C_SIGNAL='@t6g_mb_lib.t6g(sch_1):m_j_cpu1_sb_dq(14)';
NODE_NAME     U26 CN16
 '@T6G_MB_LIB.T6G(SCH_1):PAGE46_I159@PURE_QUANTA.GENOA_SP5(CHIPS)':
 'MJB_DATA14': CDS_PINID='MJB_DATA14';
NODE_NAME     J29 263
 '@T6G_MB_LIB.T6G(SCH_1):PAGE106_I22@PURE_QUANTA.SCONN288_DDR506112002KQ(CHIPS)':
 'DQ14_B': CDS_PINID='DQ14_B';
NET_NAME
'M_J_CPU1_SB_DQ<15>'
 '@T6G_MB_LIB.T6G(SCH_1):M_J_CPU1_SB_DQ'<15>:
 C_SIGNAL='@t6g_mb_lib.t6g(sch_1):m_j_cpu1_sb_dq(15)';
NODE_NAME     U26 CP18
 '@T6G_MB_LIB.T6G(SCH_1):PAGE46_I159@PURE_QUANTA.GENOA_SP5(CHIPS)':
 'MJB_DATA15': CDS_PINID='MJB_DATA15';
NODE_NAME     J29 265
 '@T6G_MB_LIB.T6G(SCH_1):PAGE106_I22@PURE_QUANTA.SCONN288_DDR506112002KQ(CHIPS)':
 'DQ15_B': CDS_PINID='DQ15_B';
NET_NAME
'M_J_CPU1_SB_DQ<16>'
 '@T6G_MB_LIB.T6G(SCH_1):M_J_CPU1_SB_DQ'<16>:
 C_SIGNAL='@t6g_mb_lib.t6g(sch_1):m_j_cpu1_sb_dq(16)';
NODE_NAME     U26 CP16
 '@T6G_MB_LIB.T6G(SCH_1):PAGE46_I159@PURE_QUANTA.GENOA_SP5(CHIPS)':
 'MJB_DATA16': CDS_PINID='MJB_DATA16';
NODE_NAME     J29 122
 '@T6G_MB_LIB.T6G(SCH_1):PAGE106_I22@PURE_QUANTA.SCONN288_DDR506112002KQ(CHIPS)':
 'DQ16_B': CDS_PINID='DQ16_B';
NET_NAME
'M_J_CPU1_SB_DQ<17>'
 '@T6G_MB_LIB.T6G(SCH_1):M_J_CPU1_SB_DQ'<17>:
 C_SIGNAL='@t6g_mb_lib.t6g(sch_1):m_j_cpu1_sb_dq(17)';
NODE_NAME     U26 CR17
 '@T6G_MB_LIB.T6G(SCH_1):PAGE46_I159@PURE_QUANTA.GENOA_SP5(CHIPS)':
 'MJB_DATA17': CDS_PINID='MJB_DATA17';
NODE_NAME     J29 124
 '@T6G_MB_LIB.T6G(SCH_1):PAGE106_I22@PURE_QUANTA.SCONN288_DDR506112002KQ(CHIPS)':
 'DQ17_B': CDS_PINID='DQ17_B';
NET_NAME
'M_J_CPU1_SB_DQ<18>'
 '@T6G_MB_LIB.T6G(SCH_1):M_J_CPU1_SB_DQ'<18>:
 C_SIGNAL='@t6g_mb_lib.t6g(sch_1):m_j_cpu1_sb_dq(18)';
NODE_NAME     U26 CR16
 '@T6G_MB_LIB.T6G(SCH_1):PAGE46_I159@PURE_QUANTA.GENOA_SP5(CHIPS)':
 'MJB_DATA18': CDS_PINID='MJB_DATA18';
NODE_NAME     J29 267
 '@T6G_MB_LIB.T6G(SCH_1):PAGE106_I22@PURE_QUANTA.SCONN288_DDR506112002KQ(CHIPS)':
 'DQ18_B': CDS_PINID='DQ18_B';
NET_NAME
'M_J_CPU1_SB_DQ<19>'
 '@T6G_MB_LIB.T6G(SCH_1):M_J_CPU1_SB_DQ'<19>:
 C_SIGNAL='@t6g_mb_lib.t6g(sch_1):m_j_cpu1_sb_dq(19)';
NODE_NAME     U26 CT18
 '@T6G_MB_LIB.T6G(SCH_1):PAGE46_I159@PURE_QUANTA.GENOA_SP5(CHIPS)':
 'MJB_DATA19': CDS_PINID='MJB_DATA19';
NODE_NAME     J29 269
 '@T6G_MB_LIB.T6G(SCH_1):PAGE106_I22@PURE_QUANTA.SCONN288_DDR506112002KQ(CHIPS)':
 'DQ19_B': CDS_PINID='DQ19_B';
NET_NAME
'M_J_CPU1_SB_DQ<1>'
 '@T6G_MB_LIB.T6G(SCH_1):M_J_CPU1_SB_DQ'<1>:
 C_SIGNAL='@t6g_mb_lib.t6g(sch_1):m_j_cpu1_sb_dq(1)';
NODE_NAME     U26 CC17
 '@T6G_MB_LIB.T6G(SCH_1):PAGE46_I159@PURE_QUANTA.GENOA_SP5(CHIPS)':
 'MJB_DATA1': CDS_PINID='MJB_DATA1';
NODE_NAME     J29 102
 '@T6G_MB_LIB.T6G(SCH_1):PAGE106_I22@PURE_QUANTA.SCONN288_DDR506112002KQ(CHIPS)':
 'DQ1_B': CDS_PINID='DQ1_B';
NET_NAME
'M_J_CPU1_SB_DQ<20>'
 '@T6G_MB_LIB.T6G(SCH_1):M_J_CPU1_SB_DQ'<20>:
 C_SIGNAL='@t6g_mb_lib.t6g(sch_1):m_j_cpu1_sb_dq(20)';
NODE_NAME     U26 CV16
 '@T6G_MB_LIB.T6G(SCH_1):PAGE46_I159@PURE_QUANTA.GENOA_SP5(CHIPS)':
 'MJB_DATA20': CDS_PINID='MJB_DATA20';
NODE_NAME     J29 129
 '@T6G_MB_LIB.T6G(SCH_1):PAGE106_I22@PURE_QUANTA.SCONN288_DDR506112002KQ(CHIPS)':
 'DQ20_B': CDS_PINID='DQ20_B';
NET_NAME
'M_J_CPU1_SB_DQ<21>'
 '@T6G_MB_LIB.T6G(SCH_1):M_J_CPU1_SB_DQ'<21>:
 C_SIGNAL='@t6g_mb_lib.t6g(sch_1):m_j_cpu1_sb_dq(21)';
NODE_NAME     U26 CW17
 '@T6G_MB_LIB.T6G(SCH_1):PAGE46_I159@PURE_QUANTA.GENOA_SP5(CHIPS)':
 'MJB_DATA21': CDS_PINID='MJB_DATA21';
NODE_NAME     J29 131
 '@T6G_MB_LIB.T6G(SCH_1):PAGE106_I22@PURE_QUANTA.SCONN288_DDR506112002KQ(CHIPS)':
 'DQ21_B': CDS_PINID='DQ21_B';
NET_NAME
'M_J_CPU1_SB_DQ<22>'
 '@T6G_MB_LIB.T6G(SCH_1):M_J_CPU1_SB_DQ'<22>:
 C_SIGNAL='@t6g_mb_lib.t6g(sch_1):m_j_cpu1_sb_dq(22)';
NODE_NAME     U26 CW16
 '@T6G_MB_LIB.T6G(SCH_1):PAGE46_I159@PURE_QUANTA.GENOA_SP5(CHIPS)':
 'MJB_DATA22': CDS_PINID='MJB_DATA22';
NODE_NAME     J29 274
 '@T6G_MB_LIB.T6G(SCH_1):PAGE106_I22@PURE_QUANTA.SCONN288_DDR506112002KQ(CHIPS)':
 'DQ22_B': CDS_PINID='DQ22_B';
NET_NAME
'M_J_CPU1_SB_DQ<23>'
 '@T6G_MB_LIB.T6G(SCH_1):M_J_CPU1_SB_DQ'<23>:
 C_SIGNAL='@t6g_mb_lib.t6g(sch_1):m_j_cpu1_sb_dq(23)';
NODE_NAME     U26 CY18
 '@T6G_MB_LIB.T6G(SCH_1):PAGE46_I159@PURE_QUANTA.GENOA_SP5(CHIPS)':
 'MJB_DATA23': CDS_PINID='MJB_DATA23';
NODE_NAME     J29 276
 '@T6G_MB_LIB.T6G(SCH_1):PAGE106_I22@PURE_QUANTA.SCONN288_DDR506112002KQ(CHIPS)':
 'DQ23_B': CDS_PINID='DQ23_B';
NET_NAME
'M_J_CPU1_SB_DQ<24>'
 '@T6G_MB_LIB.T6G(SCH_1):M_J_CPU1_SB_DQ'<24>:
 C_SIGNAL='@t6g_mb_lib.t6g(sch_1):m_j_cpu1_sb_dq(24)';
NODE_NAME     U26 CY16
 '@T6G_MB_LIB.T6G(SCH_1):PAGE46_I159@PURE_QUANTA.GENOA_SP5(CHIPS)':
 'MJB_DATA24': CDS_PINID='MJB_DATA24';
NODE_NAME     J29 133
 '@T6G_MB_LIB.T6G(SCH_1):PAGE106_I22@PURE_QUANTA.SCONN288_DDR506112002KQ(CHIPS)':
 'DQ24_B': CDS_PINID='DQ24_B';
NET_NAME
'M_J_CPU1_SB_DQ<25>'
 '@T6G_MB_LIB.T6G(SCH_1):M_J_CPU1_SB_DQ'<25>:
 C_SIGNAL='@t6g_mb_lib.t6g(sch_1):m_j_cpu1_sb_dq(25)';
NODE_NAME     U26 DA17
 '@T6G_MB_LIB.T6G(SCH_1):PAGE46_I159@PURE_QUANTA.GENOA_SP5(CHIPS)':
 'MJB_DATA25': CDS_PINID='MJB_DATA25';
NODE_NAME     J29 135
 '@T6G_MB_LIB.T6G(SCH_1):PAGE106_I22@PURE_QUANTA.SCONN288_DDR506112002KQ(CHIPS)':
 'DQ25_B': CDS_PINID='DQ25_B';
NET_NAME
'M_J_CPU1_SB_DQ<26>'
 '@T6G_MB_LIB.T6G(SCH_1):M_J_CPU1_SB_DQ'<26>:
 C_SIGNAL='@t6g_mb_lib.t6g(sch_1):m_j_cpu1_sb_dq(26)';
NODE_NAME     U26 DA16
 '@T6G_MB_LIB.T6G(SCH_1):PAGE46_I159@PURE_QUANTA.GENOA_SP5(CHIPS)':
 'MJB_DATA26': CDS_PINID='MJB_DATA26';
NODE_NAME     J29 278
 '@T6G_MB_LIB.T6G(SCH_1):PAGE106_I22@PURE_QUANTA.SCONN288_DDR506112002KQ(CHIPS)':
 'DQ26_B': CDS_PINID='DQ26_B';
NET_NAME
'M_J_CPU1_SB_DQ<27>'
 '@T6G_MB_LIB.T6G(SCH_1):M_J_CPU1_SB_DQ'<27>:
 C_SIGNAL='@t6g_mb_lib.t6g(sch_1):m_j_cpu1_sb_dq(27)';
NODE_NAME     U26 DB18
 '@T6G_MB_LIB.T6G(SCH_1):PAGE46_I159@PURE_QUANTA.GENOA_SP5(CHIPS)':
 'MJB_DATA27': CDS_PINID='MJB_DATA27';
NODE_NAME     J29 280
 '@T6G_MB_LIB.T6G(SCH_1):PAGE106_I22@PURE_QUANTA.SCONN288_DDR506112002KQ(CHIPS)':
 'DQ27_B': CDS_PINID='DQ27_B';
NET_NAME
'M_J_CPU1_SB_DQ<28>'
 '@T6G_MB_LIB.T6G(SCH_1):M_J_CPU1_SB_DQ'<28>:
 C_SIGNAL='@t6g_mb_lib.t6g(sch_1):m_j_cpu1_sb_dq(28)';
NODE_NAME     U26 DD16
 '@T6G_MB_LIB.T6G(SCH_1):PAGE46_I159@PURE_QUANTA.GENOA_SP5(CHIPS)':
 'MJB_DATA28': CDS_PINID='MJB_DATA28';
NODE_NAME     J29 140
 '@T6G_MB_LIB.T6G(SCH_1):PAGE106_I22@PURE_QUANTA.SCONN288_DDR506112002KQ(CHIPS)':
 'DQ28_B': CDS_PINID='DQ28_B';
NET_NAME
'M_J_CPU1_SB_DQ<29>'
 '@T6G_MB_LIB.T6G(SCH_1):M_J_CPU1_SB_DQ'<29>:
 C_SIGNAL='@t6g_mb_lib.t6g(sch_1):m_j_cpu1_sb_dq(29)';
NODE_NAME     U26 DE17
 '@T6G_MB_LIB.T6G(SCH_1):PAGE46_I159@PURE_QUANTA.GENOA_SP5(CHIPS)':
 'MJB_DATA29': CDS_PINID='MJB_DATA29';
NODE_NAME     J29 142
 '@T6G_MB_LIB.T6G(SCH_1):PAGE106_I22@PURE_QUANTA.SCONN288_DDR506112002KQ(CHIPS)':
 'DQ29_B': CDS_PINID='DQ29_B';
NET_NAME
'M_J_CPU1_SB_DQ<2>'
 '@T6G_MB_LIB.T6G(SCH_1):M_J_CPU1_SB_DQ'<2>:
 C_SIGNAL='@t6g_mb_lib.t6g(sch_1):m_j_cpu1_sb_dq(2)';
NODE_NAME     U26 CC16
 '@T6G_MB_LIB.T6G(SCH_1):PAGE46_I159@PURE_QUANTA.GENOA_SP5(CHIPS)':
 'MJB_DATA2': CDS_PINID='MJB_DATA2';
NODE_NAME     J29 245
 '@T6G_MB_LIB.T6G(SCH_1):PAGE106_I22@PURE_QUANTA.SCONN288_DDR506112002KQ(CHIPS)':
 'DQ2_B': CDS_PINID='DQ2_B';
NET_NAME
'M_J_CPU1_SB_DQ<30>'
 '@T6G_MB_LIB.T6G(SCH_1):M_J_CPU1_SB_DQ'<30>:
 C_SIGNAL='@t6g_mb_lib.t6g(sch_1):m_j_cpu1_sb_dq(30)';
NODE_NAME     U26 DE16
 '@T6G_MB_LIB.T6G(SCH_1):PAGE46_I159@PURE_QUANTA.GENOA_SP5(CHIPS)':
 'MJB_DATA30': CDS_PINID='MJB_DATA30';
NODE_NAME     J29 285
 '@T6G_MB_LIB.T6G(SCH_1):PAGE106_I22@PURE_QUANTA.SCONN288_DDR506112002KQ(CHIPS)':
 'DQ30_B': CDS_PINID='DQ30_B';
NET_NAME
'M_J_CPU1_SB_DQ<31>'
 '@T6G_MB_LIB.T6G(SCH_1):M_J_CPU1_SB_DQ'<31>:
 C_SIGNAL='@t6g_mb_lib.t6g(sch_1):m_j_cpu1_sb_dq(31)';
NODE_NAME     U26 DF16
 '@T6G_MB_LIB.T6G(SCH_1):PAGE46_I159@PURE_QUANTA.GENOA_SP5(CHIPS)':
 'MJB_DATA31': CDS_PINID='MJB_DATA31';
NODE_NAME     J29 287
 '@T6G_MB_LIB.T6G(SCH_1):PAGE106_I22@PURE_QUANTA.SCONN288_DDR506112002KQ(CHIPS)':
 'DQ31_B': CDS_PINID='DQ31_B';
NET_NAME
'M_J_CPU1_SB_DQ<3>'
 '@T6G_MB_LIB.T6G(SCH_1):M_J_CPU1_SB_DQ'<3>:
 C_SIGNAL='@t6g_mb_lib.t6g(sch_1):m_j_cpu1_sb_dq(3)';
NODE_NAME     U26 CD18
 '@T6G_MB_LIB.T6G(SCH_1):PAGE46_I159@PURE_QUANTA.GENOA_SP5(CHIPS)':
 'MJB_DATA3': CDS_PINID='MJB_DATA3';
NODE_NAME     J29 247
 '@T6G_MB_LIB.T6G(SCH_1):PAGE106_I22@PURE_QUANTA.SCONN288_DDR506112002KQ(CHIPS)':
 'DQ3_B': CDS_PINID='DQ3_B';
NET_NAME
'M_J_CPU1_SB_DQ<4>'
 '@T6G_MB_LIB.T6G(SCH_1):M_J_CPU1_SB_DQ'<4>:
 C_SIGNAL='@t6g_mb_lib.t6g(sch_1):m_j_cpu1_sb_dq(4)';
NODE_NAME     U26 CF16
 '@T6G_MB_LIB.T6G(SCH_1):PAGE46_I159@PURE_QUANTA.GENOA_SP5(CHIPS)':
 'MJB_DATA4': CDS_PINID='MJB_DATA4';
NODE_NAME     J29 107
 '@T6G_MB_LIB.T6G(SCH_1):PAGE106_I22@PURE_QUANTA.SCONN288_DDR506112002KQ(CHIPS)':
 'DQ4_B': CDS_PINID='DQ4_B';
NET_NAME
'M_J_CPU1_SB_DQ<5>'
 '@T6G_MB_LIB.T6G(SCH_1):M_J_CPU1_SB_DQ'<5>:
 C_SIGNAL='@t6g_mb_lib.t6g(sch_1):m_j_cpu1_sb_dq(5)';
NODE_NAME     U26 CG17
 '@T6G_MB_LIB.T6G(SCH_1):PAGE46_I159@PURE_QUANTA.GENOA_SP5(CHIPS)':
 'MJB_DATA5': CDS_PINID='MJB_DATA5';
NODE_NAME     J29 109
 '@T6G_MB_LIB.T6G(SCH_1):PAGE106_I22@PURE_QUANTA.SCONN288_DDR506112002KQ(CHIPS)':
 'DQ5_B': CDS_PINID='DQ5_B';
NET_NAME
'M_J_CPU1_SB_DQ<6>'
 '@T6G_MB_LIB.T6G(SCH_1):M_J_CPU1_SB_DQ'<6>:
 C_SIGNAL='@t6g_mb_lib.t6g(sch_1):m_j_cpu1_sb_dq(6)';
NODE_NAME     U26 CG16
 '@T6G_MB_LIB.T6G(SCH_1):PAGE46_I159@PURE_QUANTA.GENOA_SP5(CHIPS)':
 'MJB_DATA6': CDS_PINID='MJB_DATA6';
NODE_NAME     J29 252
 '@T6G_MB_LIB.T6G(SCH_1):PAGE106_I22@PURE_QUANTA.SCONN288_DDR506112002KQ(CHIPS)':
 'DQ6_B': CDS_PINID='DQ6_B';
NET_NAME
'M_J_CPU1_SB_DQ<7>'
 '@T6G_MB_LIB.T6G(SCH_1):M_J_CPU1_SB_DQ'<7>:
 C_SIGNAL='@t6g_mb_lib.t6g(sch_1):m_j_cpu1_sb_dq(7)';
NODE_NAME     U26 CH18
 '@T6G_MB_LIB.T6G(SCH_1):PAGE46_I159@PURE_QUANTA.GENOA_SP5(CHIPS)':
 'MJB_DATA7': CDS_PINID='MJB_DATA7';
NODE_NAME     J29 254
 '@T6G_MB_LIB.T6G(SCH_1):PAGE106_I22@PURE_QUANTA.SCONN288_DDR506112002KQ(CHIPS)':
 'DQ7_B': CDS_PINID='DQ7_B';
NET_NAME
'M_J_CPU1_SB_DQ<8>'
 '@T6G_MB_LIB.T6G(SCH_1):M_J_CPU1_SB_DQ'<8>:
 C_SIGNAL='@t6g_mb_lib.t6g(sch_1):m_j_cpu1_sb_dq(8)';
NODE_NAME     U26 CH16
 '@T6G_MB_LIB.T6G(SCH_1):PAGE46_I159@PURE_QUANTA.GENOA_SP5(CHIPS)':
 'MJB_DATA8': CDS_PINID='MJB_DATA8';
NODE_NAME     J29 111
 '@T6G_MB_LIB.T6G(SCH_1):PAGE106_I22@PURE_QUANTA.SCONN288_DDR506112002KQ(CHIPS)':
 'DQ8_B': CDS_PINID='DQ8_B';
NET_NAME
'M_J_CPU1_SB_DQ<9>'
 '@T6G_MB_LIB.T6G(SCH_1):M_J_CPU1_SB_DQ'<9>:
 C_SIGNAL='@t6g_mb_lib.t6g(sch_1):m_j_cpu1_sb_dq(9)';
NODE_NAME     U26 CJ17
 '@T6G_MB_LIB.T6G(SCH_1):PAGE46_I159@PURE_QUANTA.GENOA_SP5(CHIPS)':
 'MJB_DATA9': CDS_PINID='MJB_DATA9';
NODE_NAME     J29 113
 '@T6G_MB_LIB.T6G(SCH_1):PAGE106_I22@PURE_QUANTA.SCONN288_DDR506112002KQ(CHIPS)':
 'DQ9_B': CDS_PINID='DQ9_B';
NET_NAME
'M_J_CPU1_SB_DQS_DN<0>'
 '@T6G_MB_LIB.T6G(SCH_1):M_J_CPU1_SB_DQS_DN'<0>:
 C_SIGNAL='@t6g_mb_lib.t6g(sch_1):m_j_cpu1_sb_dqs_dn(0)';
NODE_NAME     U26 CE16
 '@T6G_MB_LIB.T6G(SCH_1):PAGE46_I159@PURE_QUANTA.GENOA_SP5(CHIPS)':
 'MJB_DQS_L0': CDS_PINID='MJB_DQS_L0';
NODE_NAME     J29 105
 '@T6G_MB_LIB.T6G(SCH_1):PAGE106_I236@PURE_QUANTA.SCONN288_DDR506112002KQ(CHIPS)':
 'DQS0_B_C': CDS_PINID='DQS0_B_C';
NET_NAME
'M_J_CPU1_SB_DQS_DN<1>'
 '@T6G_MB_LIB.T6G(SCH_1):M_J_CPU1_SB_DQS_DN'<1>:
 C_SIGNAL='@t6g_mb_lib.t6g(sch_1):m_j_cpu1_sb_dqs_dn(1)';
NODE_NAME     U26 CL16
 '@T6G_MB_LIB.T6G(SCH_1):PAGE46_I159@PURE_QUANTA.GENOA_SP5(CHIPS)':
 'MJB_DQS_L1': CDS_PINID='MJB_DQS_L1';
NODE_NAME     J29 116
 '@T6G_MB_LIB.T6G(SCH_1):PAGE106_I236@PURE_QUANTA.SCONN288_DDR506112002KQ(CHIPS)':
 'DQS1_B_C': CDS_PINID='DQS1_B_C';
NET_NAME
'M_J_CPU1_SB_DQS_DN<2>'
 '@T6G_MB_LIB.T6G(SCH_1):M_J_CPU1_SB_DQS_DN'<2>:
 C_SIGNAL='@t6g_mb_lib.t6g(sch_1):m_j_cpu1_sb_dqs_dn(2)';
NODE_NAME     U26 CU16
 '@T6G_MB_LIB.T6G(SCH_1):PAGE46_I159@PURE_QUANTA.GENOA_SP5(CHIPS)':
 'MJB_DQS_L2': CDS_PINID='MJB_DQS_L2';
NODE_NAME     J29 127
 '@T6G_MB_LIB.T6G(SCH_1):PAGE106_I236@PURE_QUANTA.SCONN288_DDR506112002KQ(CHIPS)':
 'DQS2_B_C': CDS_PINID='DQS2_B_C';
NET_NAME
'M_J_CPU1_SB_DQS_DN<3>'
 '@T6G_MB_LIB.T6G(SCH_1):M_J_CPU1_SB_DQS_DN'<3>:
 C_SIGNAL='@t6g_mb_lib.t6g(sch_1):m_j_cpu1_sb_dqs_dn(3)';
NODE_NAME     U26 DC16
 '@T6G_MB_LIB.T6G(SCH_1):PAGE46_I159@PURE_QUANTA.GENOA_SP5(CHIPS)':
 'MJB_DQS_L3': CDS_PINID='MJB_DQS_L3';
NODE_NAME     J29 138
 '@T6G_MB_LIB.T6G(SCH_1):PAGE106_I236@PURE_QUANTA.SCONN288_DDR506112002KQ(CHIPS)':
 'DQS3_B_C': CDS_PINID='DQS3_B_C';
NET_NAME
'M_J_CPU1_SB_DQS_DN<4>'
 '@T6G_MB_LIB.T6G(SCH_1):M_J_CPU1_SB_DQS_DN'<4>:
 C_SIGNAL='@t6g_mb_lib.t6g(sch_1):m_j_cpu1_sb_dqs_dn(4)';
NODE_NAME     U26 BW17
 '@T6G_MB_LIB.T6G(SCH_1):PAGE46_I159@PURE_QUANTA.GENOA_SP5(CHIPS)':
 'MJB_DQS_L4': CDS_PINID='MJB_DQS_L4';
NODE_NAME     J29 238
 '@T6G_MB_LIB.T6G(SCH_1):PAGE106_I236@PURE_QUANTA.SCONN288_DDR506112002KQ(CHIPS)':
 'DQS4_B_C': CDS_PINID='DQS4_B_C';
NET_NAME
'M_J_CPU1_SB_DQS_DN<5>'
 '@T6G_MB_LIB.T6G(SCH_1):M_J_CPU1_SB_DQS_DN'<5>:
 C_SIGNAL='@t6g_mb_lib.t6g(sch_1):m_j_cpu1_sb_dqs_dn(5)';
NODE_NAME     U26 CE17
 '@T6G_MB_LIB.T6G(SCH_1):PAGE46_I159@PURE_QUANTA.GENOA_SP5(CHIPS)':
 'MJB_DQS_L5': CDS_PINID='MJB_DQS_L5';
NODE_NAME     J29 249
 '@T6G_MB_LIB.T6G(SCH_1):PAGE106_I236@PURE_QUANTA.SCONN288_DDR506112002KQ(CHIPS)':
 'DQS5_B_C||TDQS5_B_C': CDS_PINID='\dqs5_b_c||tdqs5_b_c\';
NET_NAME
'M_J_CPU1_SB_DQS_DN<6>'
 '@T6G_MB_LIB.T6G(SCH_1):M_J_CPU1_SB_DQS_DN'<6>:
 C_SIGNAL='@t6g_mb_lib.t6g(sch_1):m_j_cpu1_sb_dqs_dn(6)';
NODE_NAME     U26 CL17
 '@T6G_MB_LIB.T6G(SCH_1):PAGE46_I159@PURE_QUANTA.GENOA_SP5(CHIPS)':
 'MJB_DQS_L6': CDS_PINID='MJB_DQS_L6';
NODE_NAME     J29 260
 '@T6G_MB_LIB.T6G(SCH_1):PAGE106_I236@PURE_QUANTA.SCONN288_DDR506112002KQ(CHIPS)':
 'DQS6_B_C||TDQS6_B_C': CDS_PINID='\dqs6_b_c||tdqs6_b_c\';
NET_NAME
'M_J_CPU1_SB_DQS_DN<7>'
 '@T6G_MB_LIB.T6G(SCH_1):M_J_CPU1_SB_DQS_DN'<7>:
 C_SIGNAL='@t6g_mb_lib.t6g(sch_1):m_j_cpu1_sb_dqs_dn(7)';
NODE_NAME     U26 CU17
 '@T6G_MB_LIB.T6G(SCH_1):PAGE46_I159@PURE_QUANTA.GENOA_SP5(CHIPS)':
 'MJB_DQS_L7': CDS_PINID='MJB_DQS_L7';
NODE_NAME     J29 271
 '@T6G_MB_LIB.T6G(SCH_1):PAGE106_I236@PURE_QUANTA.SCONN288_DDR506112002KQ(CHIPS)':
 'DQS7_B_C||TDQS7_B_C': CDS_PINID='\dqs7_b_c||tdqs7_b_c\';
NET_NAME
'M_J_CPU1_SB_DQS_DN<8>'
 '@T6G_MB_LIB.T6G(SCH_1):M_J_CPU1_SB_DQS_DN'<8>:
 C_SIGNAL='@t6g_mb_lib.t6g(sch_1):m_j_cpu1_sb_dqs_dn(8)';
NODE_NAME     U26 DC17
 '@T6G_MB_LIB.T6G(SCH_1):PAGE46_I159@PURE_QUANTA.GENOA_SP5(CHIPS)':
 'MJB_DQS_L8': CDS_PINID='MJB_DQS_L8';
NODE_NAME     J29 282
 '@T6G_MB_LIB.T6G(SCH_1):PAGE106_I236@PURE_QUANTA.SCONN288_DDR506112002KQ(CHIPS)':
 'DQS8_B_C||TDQS8_B_C': CDS_PINID='\dqs8_b_c||tdqs8_b_c\';
NET_NAME
'M_J_CPU1_SB_DQS_DN<9>'
 '@T6G_MB_LIB.T6G(SCH_1):M_J_CPU1_SB_DQS_DN'<9>:
 C_SIGNAL='@t6g_mb_lib.t6g(sch_1):m_j_cpu1_sb_dqs_dn(9)';
NODE_NAME     U26 BW16
 '@T6G_MB_LIB.T6G(SCH_1):PAGE46_I159@PURE_QUANTA.GENOA_SP5(CHIPS)':
 'MJB_DQS_L9': CDS_PINID='MJB_DQS_L9';
NODE_NAME     J29 94
 '@T6G_MB_LIB.T6G(SCH_1):PAGE106_I236@PURE_QUANTA.SCONN288_DDR506112002KQ(CHIPS)':
 'DQS9_B_C||TDQS9_B_C': CDS_PINID='\dqs9_b_c||tdqs9_b_c\';
NET_NAME
'M_J_CPU1_SB_DQS_DP<0>'
 '@T6G_MB_LIB.T6G(SCH_1):M_J_CPU1_SB_DQS_DP'<0>:
 C_SIGNAL='@t6g_mb_lib.t6g(sch_1):m_j_cpu1_sb_dqs_dp(0)';
NODE_NAME     U26 CD16
 '@T6G_MB_LIB.T6G(SCH_1):PAGE46_I159@PURE_QUANTA.GENOA_SP5(CHIPS)':
 'MJB_DQS_H0': CDS_PINID='MJB_DQS_H0';
NODE_NAME     J29 104
 '@T6G_MB_LIB.T6G(SCH_1):PAGE106_I236@PURE_QUANTA.SCONN288_DDR506112002KQ(CHIPS)':
 'DQS0_B_T': CDS_PINID='DQS0_B_T';
NET_NAME
'M_J_CPU1_SB_DQS_DP<1>'
 '@T6G_MB_LIB.T6G(SCH_1):M_J_CPU1_SB_DQS_DP'<1>:
 C_SIGNAL='@t6g_mb_lib.t6g(sch_1):m_j_cpu1_sb_dqs_dp(1)';
NODE_NAME     U26 CK16
 '@T6G_MB_LIB.T6G(SCH_1):PAGE46_I159@PURE_QUANTA.GENOA_SP5(CHIPS)':
 'MJB_DQS_H1': CDS_PINID='MJB_DQS_H1';
NODE_NAME     J29 115
 '@T6G_MB_LIB.T6G(SCH_1):PAGE106_I236@PURE_QUANTA.SCONN288_DDR506112002KQ(CHIPS)':
 'DQS1_B_T': CDS_PINID='DQS1_B_T';
NET_NAME
'M_J_CPU1_SB_DQS_DP<2>'
 '@T6G_MB_LIB.T6G(SCH_1):M_J_CPU1_SB_DQS_DP'<2>:
 C_SIGNAL='@t6g_mb_lib.t6g(sch_1):m_j_cpu1_sb_dqs_dp(2)';
NODE_NAME     U26 CT16
 '@T6G_MB_LIB.T6G(SCH_1):PAGE46_I159@PURE_QUANTA.GENOA_SP5(CHIPS)':
 'MJB_DQS_H2': CDS_PINID='MJB_DQS_H2';
NODE_NAME     J29 126
 '@T6G_MB_LIB.T6G(SCH_1):PAGE106_I236@PURE_QUANTA.SCONN288_DDR506112002KQ(CHIPS)':
 'DQS2_B_T': CDS_PINID='DQS2_B_T';
NET_NAME
'M_J_CPU1_SB_DQS_DP<3>'
 '@T6G_MB_LIB.T6G(SCH_1):M_J_CPU1_SB_DQS_DP'<3>:
 C_SIGNAL='@t6g_mb_lib.t6g(sch_1):m_j_cpu1_sb_dqs_dp(3)';
NODE_NAME     U26 DB16
 '@T6G_MB_LIB.T6G(SCH_1):PAGE46_I159@PURE_QUANTA.GENOA_SP5(CHIPS)':
 'MJB_DQS_H3': CDS_PINID='MJB_DQS_H3';
NODE_NAME     J29 137
 '@T6G_MB_LIB.T6G(SCH_1):PAGE106_I236@PURE_QUANTA.SCONN288_DDR506112002KQ(CHIPS)':
 'DQS3_B_T': CDS_PINID='DQS3_B_T';
NET_NAME
'M_J_CPU1_SB_DQS_DP<4>'
 '@T6G_MB_LIB.T6G(SCH_1):M_J_CPU1_SB_DQS_DP'<4>:
 C_SIGNAL='@t6g_mb_lib.t6g(sch_1):m_j_cpu1_sb_dqs_dp(4)';
NODE_NAME     U26 BY18
 '@T6G_MB_LIB.T6G(SCH_1):PAGE46_I159@PURE_QUANTA.GENOA_SP5(CHIPS)':
 'MJB_DQS_H4': CDS_PINID='MJB_DQS_H4';
NODE_NAME     J29 239
 '@T6G_MB_LIB.T6G(SCH_1):PAGE106_I236@PURE_QUANTA.SCONN288_DDR506112002KQ(CHIPS)':
 'DQS4_B_T': CDS_PINID='DQS4_B_T';
NET_NAME
'M_J_CPU1_SB_DQS_DP<5>'
 '@T6G_MB_LIB.T6G(SCH_1):M_J_CPU1_SB_DQS_DP'<5>:
 C_SIGNAL='@t6g_mb_lib.t6g(sch_1):m_j_cpu1_sb_dqs_dp(5)';
NODE_NAME     U26 CF18
 '@T6G_MB_LIB.T6G(SCH_1):PAGE46_I159@PURE_QUANTA.GENOA_SP5(CHIPS)':
 'MJB_DQS_H5': CDS_PINID='MJB_DQS_H5';
NODE_NAME     J29 250
 '@T6G_MB_LIB.T6G(SCH_1):PAGE106_I236@PURE_QUANTA.SCONN288_DDR506112002KQ(CHIPS)':
 'DQS5_B_T||TDQS5_B_T': CDS_PINID='\dqs5_b_t||tdqs5_b_t\';
NET_NAME
'M_J_CPU1_SB_DQS_DP<6>'
 '@T6G_MB_LIB.T6G(SCH_1):M_J_CPU1_SB_DQS_DP'<6>:
 C_SIGNAL='@t6g_mb_lib.t6g(sch_1):m_j_cpu1_sb_dqs_dp(6)';
NODE_NAME     U26 CM18
 '@T6G_MB_LIB.T6G(SCH_1):PAGE46_I159@PURE_QUANTA.GENOA_SP5(CHIPS)':
 'MJB_DQS_H6': CDS_PINID='MJB_DQS_H6';
NODE_NAME     J29 261
 '@T6G_MB_LIB.T6G(SCH_1):PAGE106_I236@PURE_QUANTA.SCONN288_DDR506112002KQ(CHIPS)':
 'DQS6_B_T||TDQS6_B_T': CDS_PINID='\dqs6_b_t||tdqs6_b_t\';
NET_NAME
'M_J_CPU1_SB_DQS_DP<7>'
 '@T6G_MB_LIB.T6G(SCH_1):M_J_CPU1_SB_DQS_DP'<7>:
 C_SIGNAL='@t6g_mb_lib.t6g(sch_1):m_j_cpu1_sb_dqs_dp(7)';
NODE_NAME     U26 CV18
 '@T6G_MB_LIB.T6G(SCH_1):PAGE46_I159@PURE_QUANTA.GENOA_SP5(CHIPS)':
 'MJB_DQS_H7': CDS_PINID='MJB_DQS_H7';
NODE_NAME     J29 272
 '@T6G_MB_LIB.T6G(SCH_1):PAGE106_I236@PURE_QUANTA.SCONN288_DDR506112002KQ(CHIPS)':
 'DQS7_B_T||TDQS7_B_T': CDS_PINID='\dqs7_b_t||tdqs7_b_t\';
NET_NAME
'M_J_CPU1_SB_DQS_DP<8>'
 '@T6G_MB_LIB.T6G(SCH_1):M_J_CPU1_SB_DQS_DP'<8>:
 C_SIGNAL='@t6g_mb_lib.t6g(sch_1):m_j_cpu1_sb_dqs_dp(8)';
NODE_NAME     U26 DD18
 '@T6G_MB_LIB.T6G(SCH_1):PAGE46_I159@PURE_QUANTA.GENOA_SP5(CHIPS)':
 'MJB_DQS_H8': CDS_PINID='MJB_DQS_H8';
NODE_NAME     J29 283
 '@T6G_MB_LIB.T6G(SCH_1):PAGE106_I236@PURE_QUANTA.SCONN288_DDR506112002KQ(CHIPS)':
 'DQS8_B_T||TDQS8_B_T': CDS_PINID='\dqs8_b_t||tdqs8_b_t\';
NET_NAME
'M_J_CPU1_SB_DQS_DP<9>'
 '@T6G_MB_LIB.T6G(SCH_1):M_J_CPU1_SB_DQS_DP'<9>:
 C_SIGNAL='@t6g_mb_lib.t6g(sch_1):m_j_cpu1_sb_dqs_dp(9)';
NODE_NAME     U26 BV16
 '@T6G_MB_LIB.T6G(SCH_1):PAGE46_I159@PURE_QUANTA.GENOA_SP5(CHIPS)':
 'MJB_DQS_H9': CDS_PINID='MJB_DQS_H9';
NODE_NAME     J29 93
 '@T6G_MB_LIB.T6G(SCH_1):PAGE106_I236@PURE_QUANTA.SCONN288_DDR506112002KQ(CHIPS)':
 'DQS9_B_T||TDQS9_B_T||DBI4_B_N': CDS_PINID='\dqs9_b_t||tdqs9_b_t||dbi4_b_n\';
NET_NAME
'M_J_CPU1_SB_PAR'
 '@T6G_MB_LIB.T6G(SCH_1):M_J_CPU1_SB_PAR':
 C_SIGNAL='@t6g_mb_lib.t6g(sch_1):m_j_cpu1_sb_par';
NODE_NAME     U26 BL17
 '@T6G_MB_LIB.T6G(SCH_1):PAGE46_I159@PURE_QUANTA.GENOA_SP5(CHIPS)':
 'MJB_PAR': CDS_PINID='MJB_PAR';
NODE_NAME     J29 227
 '@T6G_MB_LIB.T6G(SCH_1):PAGE106_I22@PURE_QUANTA.SCONN288_DDR506112002KQ(CHIPS)':
 'PAR_B': CDS_PINID='PAR_B';
NET_NAME
'M_J_CPU1_SB_RSP<0>'
 '@T6G_MB_LIB.T6G(SCH_1):M_J_CPU1_SB_RSP'<0>:
 C_SIGNAL='@t6g_mb_lib.t6g(sch_1):m_j_cpu1_sb_rsp(0)';
NODE_NAME     U26 BP16
 '@T6G_MB_LIB.T6G(SCH_1):PAGE46_I159@PURE_QUANTA.GENOA_SP5(CHIPS)':
 'MJB0_RSP_L': CDS_PINID='MJB0_RSP_L';
NODE_NAME     J29 87
 '@T6G_MB_LIB.T6G(SCH_1):PAGE106_I22@PURE_QUANTA.SCONN288_DDR506112002KQ(CHIPS)':
 'LBS||RSP_B_N': CDS_PINID='\lbs||rsp_b_n\';
NET_NAME
'M_K_CPU0_ALERT_N'
 '@T6G_MB_LIB.T6G(SCH_1):M_K_CPU0_ALERT_N':
 C_SIGNAL='@t6g_mb_lib.t6g(sch_1):m_k_cpu0_alert_n';
NODE_NAME     R385 1
 '@T6G_MB_LIB.T6G(SCH_1):PAGE20_I314@PURE_QUANTA.Q_RES(CHIPS)':
 'A': CDS_PINID='A';
NODE_NAME     J20 62
 '@T6G_MB_LIB.T6G(SCH_1):PAGE95_I22@PURE_QUANTA.SCONN288_DDR506112002KQ(CHIPS)':
 'ALERT_N': CDS_PINID='ALERT_N';
NET_NAME
'M_K_CPU0_ALERT_R_N'
 '@T6G_MB_LIB.T6G(SCH_1):M_K_CPU0_ALERT_R_N':
 C_SIGNAL='@t6g_mb_lib.t6g(sch_1):m_k_cpu0_alert_r_n';
NODE_NAME     U25 AT7
 '@T6G_MB_LIB.T6G(SCH_1):PAGE20_I159@PURE_QUANTA.GENOA_SP5(CHIPS)':
 'MK_ALERT_L': CDS_PINID='MK_ALERT_L';
NODE_NAME     R385 2
 '@T6G_MB_LIB.T6G(SCH_1):PAGE20_I314@PURE_QUANTA.Q_RES(CHIPS)':
 'B': CDS_PINID='B';
NET_NAME
'M_K_CPU0_CLK_DN<0>'
 '@T6G_MB_LIB.T6G(SCH_1):M_K_CPU0_CLK_DN'<0>:
 C_SIGNAL='@t6g_mb_lib.t6g(sch_1):m_k_cpu0_clk_dn(0)';
NODE_NAME     U25 BD6
 '@T6G_MB_LIB.T6G(SCH_1):PAGE20_I159@PURE_QUANTA.GENOA_SP5(CHIPS)':
 'MK0_CLK_L': CDS_PINID='MK0_CLK_L';
NODE_NAME     J20 218
 '@T6G_MB_LIB.T6G(SCH_1):PAGE95_I22@PURE_QUANTA.SCONN288_DDR506112002KQ(CHIPS)':
 'CK_C': CDS_PINID='CK_C';
NET_NAME
'M_K_CPU0_CLK_DP<0>'
 '@T6G_MB_LIB.T6G(SCH_1):M_K_CPU0_CLK_DP'<0>:
 C_SIGNAL='@t6g_mb_lib.t6g(sch_1):m_k_cpu0_clk_dp(0)';
NODE_NAME     U25 BC5
 '@T6G_MB_LIB.T6G(SCH_1):PAGE20_I159@PURE_QUANTA.GENOA_SP5(CHIPS)':
 'MK0_CLK_H': CDS_PINID='MK0_CLK_H';
NODE_NAME     J20 217
 '@T6G_MB_LIB.T6G(SCH_1):PAGE95_I22@PURE_QUANTA.SCONN288_DDR506112002KQ(CHIPS)':
 'CK_T': CDS_PINID='CK_T';
NET_NAME
'M_K_CPU0_RESET_N'
 '@T6G_MB_LIB.T6G(SCH_1):M_K_CPU0_RESET_N':
 C_SIGNAL='@t6g_mb_lib.t6g(sch_1):m_k_cpu0_reset_n';
NODE_NAME     U25 AU7
 '@T6G_MB_LIB.T6G(SCH_1):PAGE20_I159@PURE_QUANTA.GENOA_SP5(CHIPS)':
 'MK_RESET_L': CDS_PINID='MK_RESET_L';
NODE_NAME     J20 207
 '@T6G_MB_LIB.T6G(SCH_1):PAGE95_I22@PURE_QUANTA.SCONN288_DDR506112002KQ(CHIPS)':
 'RESET_N': CDS_PINID='RESET_N';
NET_NAME
'M_K_CPU0_SA_CA<0>'
 '@T6G_MB_LIB.T6G(SCH_1):M_K_CPU0_SA_CA'<0>:
 C_SIGNAL='@t6g_mb_lib.t6g(sch_1):m_k_cpu0_sa_ca(0)';
NODE_NAME     U25 AW5
 '@T6G_MB_LIB.T6G(SCH_1):PAGE20_I159@PURE_QUANTA.GENOA_SP5(CHIPS)':
 'MKA_CA0': CDS_PINID='MKA_CA0';
NODE_NAME     J20 66
 '@T6G_MB_LIB.T6G(SCH_1):PAGE95_I22@PURE_QUANTA.SCONN288_DDR506112002KQ(CHIPS)':
 'CA0_A': CDS_PINID='CA0_A';
NET_NAME
'M_K_CPU0_SA_CA<1>'
 '@T6G_MB_LIB.T6G(SCH_1):M_K_CPU0_SA_CA'<1>:
 C_SIGNAL='@t6g_mb_lib.t6g(sch_1):m_k_cpu0_sa_ca(1)';
NODE_NAME     U25 AY6
 '@T6G_MB_LIB.T6G(SCH_1):PAGE20_I159@PURE_QUANTA.GENOA_SP5(CHIPS)':
 'MKA_CA1': CDS_PINID='MKA_CA1';
NODE_NAME     J20 211
 '@T6G_MB_LIB.T6G(SCH_1):PAGE95_I22@PURE_QUANTA.SCONN288_DDR506112002KQ(CHIPS)':
 'CA1_A': CDS_PINID='CA1_A';
NET_NAME
'M_K_CPU0_SA_CA<2>'
 '@T6G_MB_LIB.T6G(SCH_1):M_K_CPU0_SA_CA'<2>:
 C_SIGNAL='@t6g_mb_lib.t6g(sch_1):m_k_cpu0_sa_ca(2)';
NODE_NAME     U25 AY7
 '@T6G_MB_LIB.T6G(SCH_1):PAGE20_I159@PURE_QUANTA.GENOA_SP5(CHIPS)':
 'MKA_CA2': CDS_PINID='MKA_CA2';
NODE_NAME     J20 68
 '@T6G_MB_LIB.T6G(SCH_1):PAGE95_I22@PURE_QUANTA.SCONN288_DDR506112002KQ(CHIPS)':
 'CA2_A': CDS_PINID='CA2_A';
NET_NAME
'M_K_CPU0_SA_CA<3>'
 '@T6G_MB_LIB.T6G(SCH_1):M_K_CPU0_SA_CA'<3>:
 C_SIGNAL='@t6g_mb_lib.t6g(sch_1):m_k_cpu0_sa_ca(3)';
NODE_NAME     U25 BA7
 '@T6G_MB_LIB.T6G(SCH_1):PAGE20_I159@PURE_QUANTA.GENOA_SP5(CHIPS)':
 'MKA_CA3': CDS_PINID='MKA_CA3';
NODE_NAME     J20 213
 '@T6G_MB_LIB.T6G(SCH_1):PAGE95_I22@PURE_QUANTA.SCONN288_DDR506112002KQ(CHIPS)':
 'CA3_A': CDS_PINID='CA3_A';
NET_NAME
'M_K_CPU0_SA_CA<4>'
 '@T6G_MB_LIB.T6G(SCH_1):M_K_CPU0_SA_CA'<4>:
 C_SIGNAL='@t6g_mb_lib.t6g(sch_1):m_k_cpu0_sa_ca(4)';
NODE_NAME     U25 BA5
 '@T6G_MB_LIB.T6G(SCH_1):PAGE20_I159@PURE_QUANTA.GENOA_SP5(CHIPS)':
 'MKA_CA4': CDS_PINID='MKA_CA4';
NODE_NAME     J20 70
 '@T6G_MB_LIB.T6G(SCH_1):PAGE95_I22@PURE_QUANTA.SCONN288_DDR506112002KQ(CHIPS)':
 'CA4_A': CDS_PINID='CA4_A';
NET_NAME
'M_K_CPU0_SA_CA<5>'
 '@T6G_MB_LIB.T6G(SCH_1):M_K_CPU0_SA_CA'<5>:
 C_SIGNAL='@t6g_mb_lib.t6g(sch_1):m_k_cpu0_sa_ca(5)';
NODE_NAME     U25 BB6
 '@T6G_MB_LIB.T6G(SCH_1):PAGE20_I159@PURE_QUANTA.GENOA_SP5(CHIPS)':
 'MKA_CA5': CDS_PINID='MKA_CA5';
NODE_NAME     J20 215
 '@T6G_MB_LIB.T6G(SCH_1):PAGE95_I22@PURE_QUANTA.SCONN288_DDR506112002KQ(CHIPS)':
 'CA5_A': CDS_PINID='CA5_A';
NET_NAME
'M_K_CPU0_SA_CA<6>'
 '@T6G_MB_LIB.T6G(SCH_1):M_K_CPU0_SA_CA'<6>:
 C_SIGNAL='@t6g_mb_lib.t6g(sch_1):m_k_cpu0_sa_ca(6)';
NODE_NAME     U25 BB7
 '@T6G_MB_LIB.T6G(SCH_1):PAGE20_I159@PURE_QUANTA.GENOA_SP5(CHIPS)':
 'MKA_CA6': CDS_PINID='MKA_CA6';
NODE_NAME     J20 72
 '@T6G_MB_LIB.T6G(SCH_1):PAGE95_I22@PURE_QUANTA.SCONN288_DDR506112002KQ(CHIPS)':
 'CA6_A': CDS_PINID='CA6_A';
NET_NAME
'M_K_CPU0_SA_CB<0>'
 '@T6G_MB_LIB.T6G(SCH_1):M_K_CPU0_SA_CB'<0>:
 C_SIGNAL='@t6g_mb_lib.t6g(sch_1):m_k_cpu0_sa_cb(0)';
NODE_NAME     U25 AJ5
 '@T6G_MB_LIB.T6G(SCH_1):PAGE20_I159@PURE_QUANTA.GENOA_SP5(CHIPS)':
 'MKA_CHECK0': CDS_PINID='MKA_CHECK0';
NODE_NAME     J20 51
 '@T6G_MB_LIB.T6G(SCH_1):PAGE95_I22@PURE_QUANTA.SCONN288_DDR506112002KQ(CHIPS)':
 'CB0_A': CDS_PINID='CB0_A';
NET_NAME
'M_K_CPU0_SA_CB<1>'
 '@T6G_MB_LIB.T6G(SCH_1):M_K_CPU0_SA_CB'<1>:
 C_SIGNAL='@t6g_mb_lib.t6g(sch_1):m_k_cpu0_sa_cb(1)';
NODE_NAME     U25 AK7
 '@T6G_MB_LIB.T6G(SCH_1):PAGE20_I159@PURE_QUANTA.GENOA_SP5(CHIPS)':
 'MKA_CHECK1': CDS_PINID='MKA_CHECK1';
NODE_NAME     J20 53
 '@T6G_MB_LIB.T6G(SCH_1):PAGE95_I22@PURE_QUANTA.SCONN288_DDR506112002KQ(CHIPS)':
 'CB1_A': CDS_PINID='CB1_A';
NET_NAME
'M_K_CPU0_SA_CB<2>'
 '@T6G_MB_LIB.T6G(SCH_1):M_K_CPU0_SA_CB'<2>:
 C_SIGNAL='@t6g_mb_lib.t6g(sch_1):m_k_cpu0_sa_cb(2)';
NODE_NAME     U25 AK6
 '@T6G_MB_LIB.T6G(SCH_1):PAGE20_I159@PURE_QUANTA.GENOA_SP5(CHIPS)':
 'MKA_CHECK2': CDS_PINID='MKA_CHECK2';
NODE_NAME     J20 196
 '@T6G_MB_LIB.T6G(SCH_1):PAGE95_I22@PURE_QUANTA.SCONN288_DDR506112002KQ(CHIPS)':
 'CB2_A': CDS_PINID='CB2_A';
NET_NAME
'M_K_CPU0_SA_CB<3>'
 '@T6G_MB_LIB.T6G(SCH_1):M_K_CPU0_SA_CB'<3>:
 C_SIGNAL='@t6g_mb_lib.t6g(sch_1):m_k_cpu0_sa_cb(3)';
NODE_NAME     U25 AL7
 '@T6G_MB_LIB.T6G(SCH_1):PAGE20_I159@PURE_QUANTA.GENOA_SP5(CHIPS)':
 'MKA_CHECK3': CDS_PINID='MKA_CHECK3';
NODE_NAME     J20 198
 '@T6G_MB_LIB.T6G(SCH_1):PAGE95_I22@PURE_QUANTA.SCONN288_DDR506112002KQ(CHIPS)':
 'CB3_A': CDS_PINID='CB3_A';
NET_NAME
'M_K_CPU0_SA_CB<4>'
 '@T6G_MB_LIB.T6G(SCH_1):M_K_CPU0_SA_CB'<4>:
 C_SIGNAL='@t6g_mb_lib.t6g(sch_1):m_k_cpu0_sa_cb(4)';
NODE_NAME     U25 AN5
 '@T6G_MB_LIB.T6G(SCH_1):PAGE20_I159@PURE_QUANTA.GENOA_SP5(CHIPS)':
 'MKA_CHECK4': CDS_PINID='MKA_CHECK4';
NODE_NAME     J20 58
 '@T6G_MB_LIB.T6G(SCH_1):PAGE95_I22@PURE_QUANTA.SCONN288_DDR506112002KQ(CHIPS)':
 'CB4_A': CDS_PINID='CB4_A';
NET_NAME
'M_K_CPU0_SA_CB<5>'
 '@T6G_MB_LIB.T6G(SCH_1):M_K_CPU0_SA_CB'<5>:
 C_SIGNAL='@t6g_mb_lib.t6g(sch_1):m_k_cpu0_sa_cb(5)';
NODE_NAME     U25 AP7
 '@T6G_MB_LIB.T6G(SCH_1):PAGE20_I159@PURE_QUANTA.GENOA_SP5(CHIPS)':
 'MKA_CHECK5': CDS_PINID='MKA_CHECK5';
NODE_NAME     J20 60
 '@T6G_MB_LIB.T6G(SCH_1):PAGE95_I22@PURE_QUANTA.SCONN288_DDR506112002KQ(CHIPS)':
 'CB5_A': CDS_PINID='CB5_A';
NET_NAME
'M_K_CPU0_SA_CB<6>'
 '@T6G_MB_LIB.T6G(SCH_1):M_K_CPU0_SA_CB'<6>:
 C_SIGNAL='@t6g_mb_lib.t6g(sch_1):m_k_cpu0_sa_cb(6)';
NODE_NAME     U25 AP6
 '@T6G_MB_LIB.T6G(SCH_1):PAGE20_I159@PURE_QUANTA.GENOA_SP5(CHIPS)':
 'MKA_CHECK6': CDS_PINID='MKA_CHECK6';
NODE_NAME     J20 203
 '@T6G_MB_LIB.T6G(SCH_1):PAGE95_I22@PURE_QUANTA.SCONN288_DDR506112002KQ(CHIPS)':
 'CB6_A': CDS_PINID='CB6_A';
NET_NAME
'M_K_CPU0_SA_CB<7>'
 '@T6G_MB_LIB.T6G(SCH_1):M_K_CPU0_SA_CB'<7>:
 C_SIGNAL='@t6g_mb_lib.t6g(sch_1):m_k_cpu0_sa_cb(7)';
NODE_NAME     U25 AR7
 '@T6G_MB_LIB.T6G(SCH_1):PAGE20_I159@PURE_QUANTA.GENOA_SP5(CHIPS)':
 'MKA_CHECK7': CDS_PINID='MKA_CHECK7';
NODE_NAME     J20 205
 '@T6G_MB_LIB.T6G(SCH_1):PAGE95_I22@PURE_QUANTA.SCONN288_DDR506112002KQ(CHIPS)':
 'CB7_A': CDS_PINID='CB7_A';
NET_NAME
'M_K_CPU0_SA_CS_N<0>'
 '@T6G_MB_LIB.T6G(SCH_1):M_K_CPU0_SA_CS_N'<0>:
 C_SIGNAL='@t6g_mb_lib.t6g(sch_1):m_k_cpu0_sa_cs_n(0)';
NODE_NAME     U25 AU5
 '@T6G_MB_LIB.T6G(SCH_1):PAGE20_I159@PURE_QUANTA.GENOA_SP5(CHIPS)':
 'MKA0_CS_L0': CDS_PINID='MKA0_CS_L0';
NODE_NAME     J20 64
 '@T6G_MB_LIB.T6G(SCH_1):PAGE95_I22@PURE_QUANTA.SCONN288_DDR506112002KQ(CHIPS)':
 'CS0_A_N': CDS_PINID='CS0_A_N';
NET_NAME
'M_K_CPU0_SA_CS_N<1>'
 '@T6G_MB_LIB.T6G(SCH_1):M_K_CPU0_SA_CS_N'<1>:
 C_SIGNAL='@t6g_mb_lib.t6g(sch_1):m_k_cpu0_sa_cs_n(1)';
NODE_NAME     U25 AV7
 '@T6G_MB_LIB.T6G(SCH_1):PAGE20_I159@PURE_QUANTA.GENOA_SP5(CHIPS)':
 'MKA0_CS_L1': CDS_PINID='MKA0_CS_L1';
NODE_NAME     J20 209
 '@T6G_MB_LIB.T6G(SCH_1):PAGE95_I22@PURE_QUANTA.SCONN288_DDR506112002KQ(CHIPS)':
 'CS1_A_N': CDS_PINID='CS1_A_N';
NET_NAME
'M_K_CPU0_SA_DQ<0>'
 '@T6G_MB_LIB.T6G(SCH_1):M_K_CPU0_SA_DQ'<0>:
 C_SIGNAL='@t6g_mb_lib.t6g(sch_1):m_k_cpu0_sa_dq(0)';
NODE_NAME     U25 E5
 '@T6G_MB_LIB.T6G(SCH_1):PAGE20_I159@PURE_QUANTA.GENOA_SP5(CHIPS)':
 'MKA_DATA0': CDS_PINID='MKA_DATA0';
NODE_NAME     J20 7
 '@T6G_MB_LIB.T6G(SCH_1):PAGE95_I22@PURE_QUANTA.SCONN288_DDR506112002KQ(CHIPS)':
 'DQ0_A': CDS_PINID='DQ0_A';
NET_NAME
'M_K_CPU0_SA_DQ<10>'
 '@T6G_MB_LIB.T6G(SCH_1):M_K_CPU0_SA_DQ'<10>:
 C_SIGNAL='@t6g_mb_lib.t6g(sch_1):m_k_cpu0_sa_dq(10)';
NODE_NAME     U25 M6
 '@T6G_MB_LIB.T6G(SCH_1):PAGE20_I159@PURE_QUANTA.GENOA_SP5(CHIPS)':
 'MKA_DATA10': CDS_PINID='MKA_DATA10';
NODE_NAME     J20 163
 '@T6G_MB_LIB.T6G(SCH_1):PAGE95_I22@PURE_QUANTA.SCONN288_DDR506112002KQ(CHIPS)':
 'DQ10_A': CDS_PINID='DQ10_A';
NET_NAME
'M_K_CPU0_SA_DQ<11>'
 '@T6G_MB_LIB.T6G(SCH_1):M_K_CPU0_SA_DQ'<11>:
 C_SIGNAL='@t6g_mb_lib.t6g(sch_1):m_k_cpu0_sa_dq(11)';
NODE_NAME     U25 N7
 '@T6G_MB_LIB.T6G(SCH_1):PAGE20_I159@PURE_QUANTA.GENOA_SP5(CHIPS)':
 'MKA_DATA11': CDS_PINID='MKA_DATA11';
NODE_NAME     J20 165
 '@T6G_MB_LIB.T6G(SCH_1):PAGE95_I22@PURE_QUANTA.SCONN288_DDR506112002KQ(CHIPS)':
 'DQ11_A': CDS_PINID='DQ11_A';
NET_NAME
'M_K_CPU0_SA_DQ<12>'
 '@T6G_MB_LIB.T6G(SCH_1):M_K_CPU0_SA_DQ'<12>:
 C_SIGNAL='@t6g_mb_lib.t6g(sch_1):m_k_cpu0_sa_dq(12)';
NODE_NAME     U25 R5
 '@T6G_MB_LIB.T6G(SCH_1):PAGE20_I159@PURE_QUANTA.GENOA_SP5(CHIPS)':
 'MKA_DATA12': CDS_PINID='MKA_DATA12';
NODE_NAME     J20 25
 '@T6G_MB_LIB.T6G(SCH_1):PAGE95_I22@PURE_QUANTA.SCONN288_DDR506112002KQ(CHIPS)':
 'DQ12_A': CDS_PINID='DQ12_A';
NET_NAME
'M_K_CPU0_SA_DQ<13>'
 '@T6G_MB_LIB.T6G(SCH_1):M_K_CPU0_SA_DQ'<13>:
 C_SIGNAL='@t6g_mb_lib.t6g(sch_1):m_k_cpu0_sa_dq(13)';
NODE_NAME     U25 T7
 '@T6G_MB_LIB.T6G(SCH_1):PAGE20_I159@PURE_QUANTA.GENOA_SP5(CHIPS)':
 'MKA_DATA13': CDS_PINID='MKA_DATA13';
NODE_NAME     J20 27
 '@T6G_MB_LIB.T6G(SCH_1):PAGE95_I22@PURE_QUANTA.SCONN288_DDR506112002KQ(CHIPS)':
 'DQ13_A': CDS_PINID='DQ13_A';
NET_NAME
'M_K_CPU0_SA_DQ<14>'
 '@T6G_MB_LIB.T6G(SCH_1):M_K_CPU0_SA_DQ'<14>:
 C_SIGNAL='@t6g_mb_lib.t6g(sch_1):m_k_cpu0_sa_dq(14)';
NODE_NAME     U25 T6
 '@T6G_MB_LIB.T6G(SCH_1):PAGE20_I159@PURE_QUANTA.GENOA_SP5(CHIPS)':
 'MKA_DATA14': CDS_PINID='MKA_DATA14';
NODE_NAME     J20 170
 '@T6G_MB_LIB.T6G(SCH_1):PAGE95_I22@PURE_QUANTA.SCONN288_DDR506112002KQ(CHIPS)':
 'DQ14_A': CDS_PINID='DQ14_A';
NET_NAME
'M_K_CPU0_SA_DQ<15>'
 '@T6G_MB_LIB.T6G(SCH_1):M_K_CPU0_SA_DQ'<15>:
 C_SIGNAL='@t6g_mb_lib.t6g(sch_1):m_k_cpu0_sa_dq(15)';
NODE_NAME     U25 U7
 '@T6G_MB_LIB.T6G(SCH_1):PAGE20_I159@PURE_QUANTA.GENOA_SP5(CHIPS)':
 'MKA_DATA15': CDS_PINID='MKA_DATA15';
NODE_NAME     J20 172
 '@T6G_MB_LIB.T6G(SCH_1):PAGE95_I22@PURE_QUANTA.SCONN288_DDR506112002KQ(CHIPS)':
 'DQ15_A': CDS_PINID='DQ15_A';
NET_NAME
'M_K_CPU0_SA_DQ<16>'
 '@T6G_MB_LIB.T6G(SCH_1):M_K_CPU0_SA_DQ'<16>:
 C_SIGNAL='@t6g_mb_lib.t6g(sch_1):m_k_cpu0_sa_dq(16)';
NODE_NAME     U25 U5
 '@T6G_MB_LIB.T6G(SCH_1):PAGE20_I159@PURE_QUANTA.GENOA_SP5(CHIPS)':
 'MKA_DATA16': CDS_PINID='MKA_DATA16';
NODE_NAME     J20 29
 '@T6G_MB_LIB.T6G(SCH_1):PAGE95_I22@PURE_QUANTA.SCONN288_DDR506112002KQ(CHIPS)':
 'DQ16_A': CDS_PINID='DQ16_A';
NET_NAME
'M_K_CPU0_SA_DQ<17>'
 '@T6G_MB_LIB.T6G(SCH_1):M_K_CPU0_SA_DQ'<17>:
 C_SIGNAL='@t6g_mb_lib.t6g(sch_1):m_k_cpu0_sa_dq(17)';
NODE_NAME     U25 V7
 '@T6G_MB_LIB.T6G(SCH_1):PAGE20_I159@PURE_QUANTA.GENOA_SP5(CHIPS)':
 'MKA_DATA17': CDS_PINID='MKA_DATA17';
NODE_NAME     J20 31
 '@T6G_MB_LIB.T6G(SCH_1):PAGE95_I22@PURE_QUANTA.SCONN288_DDR506112002KQ(CHIPS)':
 'DQ17_A': CDS_PINID='DQ17_A';
NET_NAME
'M_K_CPU0_SA_DQ<18>'
 '@T6G_MB_LIB.T6G(SCH_1):M_K_CPU0_SA_DQ'<18>:
 C_SIGNAL='@t6g_mb_lib.t6g(sch_1):m_k_cpu0_sa_dq(18)';
NODE_NAME     U25 V6
 '@T6G_MB_LIB.T6G(SCH_1):PAGE20_I159@PURE_QUANTA.GENOA_SP5(CHIPS)':
 'MKA_DATA18': CDS_PINID='MKA_DATA18';
NODE_NAME     J20 174
 '@T6G_MB_LIB.T6G(SCH_1):PAGE95_I22@PURE_QUANTA.SCONN288_DDR506112002KQ(CHIPS)':
 'DQ18_A': CDS_PINID='DQ18_A';
NET_NAME
'M_K_CPU0_SA_DQ<19>'
 '@T6G_MB_LIB.T6G(SCH_1):M_K_CPU0_SA_DQ'<19>:
 C_SIGNAL='@t6g_mb_lib.t6g(sch_1):m_k_cpu0_sa_dq(19)';
NODE_NAME     U25 W7
 '@T6G_MB_LIB.T6G(SCH_1):PAGE20_I159@PURE_QUANTA.GENOA_SP5(CHIPS)':
 'MKA_DATA19': CDS_PINID='MKA_DATA19';
NODE_NAME     J20 176
 '@T6G_MB_LIB.T6G(SCH_1):PAGE95_I22@PURE_QUANTA.SCONN288_DDR506112002KQ(CHIPS)':
 'DQ19_A': CDS_PINID='DQ19_A';
NET_NAME
'M_K_CPU0_SA_DQ<1>'
 '@T6G_MB_LIB.T6G(SCH_1):M_K_CPU0_SA_DQ'<1>:
 C_SIGNAL='@t6g_mb_lib.t6g(sch_1):m_k_cpu0_sa_dq(1)';
NODE_NAME     U25 F7
 '@T6G_MB_LIB.T6G(SCH_1):PAGE20_I159@PURE_QUANTA.GENOA_SP5(CHIPS)':
 'MKA_DATA1': CDS_PINID='MKA_DATA1';
NODE_NAME     J20 9
 '@T6G_MB_LIB.T6G(SCH_1):PAGE95_I22@PURE_QUANTA.SCONN288_DDR506112002KQ(CHIPS)':
 'DQ1_A': CDS_PINID='DQ1_A';
NET_NAME
'M_K_CPU0_SA_DQ<20>'
 '@T6G_MB_LIB.T6G(SCH_1):M_K_CPU0_SA_DQ'<20>:
 C_SIGNAL='@t6g_mb_lib.t6g(sch_1):m_k_cpu0_sa_dq(20)';
NODE_NAME     U25 AA5
 '@T6G_MB_LIB.T6G(SCH_1):PAGE20_I159@PURE_QUANTA.GENOA_SP5(CHIPS)':
 'MKA_DATA20': CDS_PINID='MKA_DATA20';
NODE_NAME     J20 36
 '@T6G_MB_LIB.T6G(SCH_1):PAGE95_I22@PURE_QUANTA.SCONN288_DDR506112002KQ(CHIPS)':
 'DQ20_A': CDS_PINID='DQ20_A';
NET_NAME
'M_K_CPU0_SA_DQ<21>'
 '@T6G_MB_LIB.T6G(SCH_1):M_K_CPU0_SA_DQ'<21>:
 C_SIGNAL='@t6g_mb_lib.t6g(sch_1):m_k_cpu0_sa_dq(21)';
NODE_NAME     U25 AB7
 '@T6G_MB_LIB.T6G(SCH_1):PAGE20_I159@PURE_QUANTA.GENOA_SP5(CHIPS)':
 'MKA_DATA21': CDS_PINID='MKA_DATA21';
NODE_NAME     J20 38
 '@T6G_MB_LIB.T6G(SCH_1):PAGE95_I22@PURE_QUANTA.SCONN288_DDR506112002KQ(CHIPS)':
 'DQ21_A': CDS_PINID='DQ21_A';
NET_NAME
'M_K_CPU0_SA_DQ<22>'
 '@T6G_MB_LIB.T6G(SCH_1):M_K_CPU0_SA_DQ'<22>:
 C_SIGNAL='@t6g_mb_lib.t6g(sch_1):m_k_cpu0_sa_dq(22)';
NODE_NAME     U25 AB6
 '@T6G_MB_LIB.T6G(SCH_1):PAGE20_I159@PURE_QUANTA.GENOA_SP5(CHIPS)':
 'MKA_DATA22': CDS_PINID='MKA_DATA22';
NODE_NAME     J20 181
 '@T6G_MB_LIB.T6G(SCH_1):PAGE95_I22@PURE_QUANTA.SCONN288_DDR506112002KQ(CHIPS)':
 'DQ22_A': CDS_PINID='DQ22_A';
NET_NAME
'M_K_CPU0_SA_DQ<23>'
 '@T6G_MB_LIB.T6G(SCH_1):M_K_CPU0_SA_DQ'<23>:
 C_SIGNAL='@t6g_mb_lib.t6g(sch_1):m_k_cpu0_sa_dq(23)';
NODE_NAME     U25 AC7
 '@T6G_MB_LIB.T6G(SCH_1):PAGE20_I159@PURE_QUANTA.GENOA_SP5(CHIPS)':
 'MKA_DATA23': CDS_PINID='MKA_DATA23';
NODE_NAME     J20 183
 '@T6G_MB_LIB.T6G(SCH_1):PAGE95_I22@PURE_QUANTA.SCONN288_DDR506112002KQ(CHIPS)':
 'DQ23_A': CDS_PINID='DQ23_A';
NET_NAME
'M_K_CPU0_SA_DQ<24>'
 '@T6G_MB_LIB.T6G(SCH_1):M_K_CPU0_SA_DQ'<24>:
 C_SIGNAL='@t6g_mb_lib.t6g(sch_1):m_k_cpu0_sa_dq(24)';
NODE_NAME     U25 AC5
 '@T6G_MB_LIB.T6G(SCH_1):PAGE20_I159@PURE_QUANTA.GENOA_SP5(CHIPS)':
 'MKA_DATA24': CDS_PINID='MKA_DATA24';
NODE_NAME     J20 40
 '@T6G_MB_LIB.T6G(SCH_1):PAGE95_I22@PURE_QUANTA.SCONN288_DDR506112002KQ(CHIPS)':
 'DQ24_A': CDS_PINID='DQ24_A';
NET_NAME
'M_K_CPU0_SA_DQ<25>'
 '@T6G_MB_LIB.T6G(SCH_1):M_K_CPU0_SA_DQ'<25>:
 C_SIGNAL='@t6g_mb_lib.t6g(sch_1):m_k_cpu0_sa_dq(25)';
NODE_NAME     U25 AD7
 '@T6G_MB_LIB.T6G(SCH_1):PAGE20_I159@PURE_QUANTA.GENOA_SP5(CHIPS)':
 'MKA_DATA25': CDS_PINID='MKA_DATA25';
NODE_NAME     J20 42
 '@T6G_MB_LIB.T6G(SCH_1):PAGE95_I22@PURE_QUANTA.SCONN288_DDR506112002KQ(CHIPS)':
 'DQ25_A': CDS_PINID='DQ25_A';
NET_NAME
'M_K_CPU0_SA_DQ<26>'
 '@T6G_MB_LIB.T6G(SCH_1):M_K_CPU0_SA_DQ'<26>:
 C_SIGNAL='@t6g_mb_lib.t6g(sch_1):m_k_cpu0_sa_dq(26)';
NODE_NAME     U25 AD6
 '@T6G_MB_LIB.T6G(SCH_1):PAGE20_I159@PURE_QUANTA.GENOA_SP5(CHIPS)':
 'MKA_DATA26': CDS_PINID='MKA_DATA26';
NODE_NAME     J20 185
 '@T6G_MB_LIB.T6G(SCH_1):PAGE95_I22@PURE_QUANTA.SCONN288_DDR506112002KQ(CHIPS)':
 'DQ26_A': CDS_PINID='DQ26_A';
NET_NAME
'M_K_CPU0_SA_DQ<27>'
 '@T6G_MB_LIB.T6G(SCH_1):M_K_CPU0_SA_DQ'<27>:
 C_SIGNAL='@t6g_mb_lib.t6g(sch_1):m_k_cpu0_sa_dq(27)';
NODE_NAME     U25 AE7
 '@T6G_MB_LIB.T6G(SCH_1):PAGE20_I159@PURE_QUANTA.GENOA_SP5(CHIPS)':
 'MKA_DATA27': CDS_PINID='MKA_DATA27';
NODE_NAME     J20 187
 '@T6G_MB_LIB.T6G(SCH_1):PAGE95_I22@PURE_QUANTA.SCONN288_DDR506112002KQ(CHIPS)':
 'DQ27_A': CDS_PINID='DQ27_A';
NET_NAME
'M_K_CPU0_SA_DQ<28>'
 '@T6G_MB_LIB.T6G(SCH_1):M_K_CPU0_SA_DQ'<28>:
 C_SIGNAL='@t6g_mb_lib.t6g(sch_1):m_k_cpu0_sa_dq(28)';
NODE_NAME     U25 AG5
 '@T6G_MB_LIB.T6G(SCH_1):PAGE20_I159@PURE_QUANTA.GENOA_SP5(CHIPS)':
 'MKA_DATA28': CDS_PINID='MKA_DATA28';
NODE_NAME     J20 47
 '@T6G_MB_LIB.T6G(SCH_1):PAGE95_I22@PURE_QUANTA.SCONN288_DDR506112002KQ(CHIPS)':
 'DQ28_A': CDS_PINID='DQ28_A';
NET_NAME
'M_K_CPU0_SA_DQ<29>'
 '@T6G_MB_LIB.T6G(SCH_1):M_K_CPU0_SA_DQ'<29>:
 C_SIGNAL='@t6g_mb_lib.t6g(sch_1):m_k_cpu0_sa_dq(29)';
NODE_NAME     U25 AH7
 '@T6G_MB_LIB.T6G(SCH_1):PAGE20_I159@PURE_QUANTA.GENOA_SP5(CHIPS)':
 'MKA_DATA29': CDS_PINID='MKA_DATA29';
NODE_NAME     J20 49
 '@T6G_MB_LIB.T6G(SCH_1):PAGE95_I22@PURE_QUANTA.SCONN288_DDR506112002KQ(CHIPS)':
 'DQ29_A': CDS_PINID='DQ29_A';
NET_NAME
'M_K_CPU0_SA_DQ<2>'
 '@T6G_MB_LIB.T6G(SCH_1):M_K_CPU0_SA_DQ'<2>:
 C_SIGNAL='@t6g_mb_lib.t6g(sch_1):m_k_cpu0_sa_dq(2)';
NODE_NAME     U25 F6
 '@T6G_MB_LIB.T6G(SCH_1):PAGE20_I159@PURE_QUANTA.GENOA_SP5(CHIPS)':
 'MKA_DATA2': CDS_PINID='MKA_DATA2';
NODE_NAME     J20 152
 '@T6G_MB_LIB.T6G(SCH_1):PAGE95_I22@PURE_QUANTA.SCONN288_DDR506112002KQ(CHIPS)':
 'DQ2_A': CDS_PINID='DQ2_A';
NET_NAME
'M_K_CPU0_SA_DQ<30>'
 '@T6G_MB_LIB.T6G(SCH_1):M_K_CPU0_SA_DQ'<30>:
 C_SIGNAL='@t6g_mb_lib.t6g(sch_1):m_k_cpu0_sa_dq(30)';
NODE_NAME     U25 AH6
 '@T6G_MB_LIB.T6G(SCH_1):PAGE20_I159@PURE_QUANTA.GENOA_SP5(CHIPS)':
 'MKA_DATA30': CDS_PINID='MKA_DATA30';
NODE_NAME     J20 192
 '@T6G_MB_LIB.T6G(SCH_1):PAGE95_I22@PURE_QUANTA.SCONN288_DDR506112002KQ(CHIPS)':
 'DQ30_A': CDS_PINID='DQ30_A';
NET_NAME
'M_K_CPU0_SA_DQ<31>'
 '@T6G_MB_LIB.T6G(SCH_1):M_K_CPU0_SA_DQ'<31>:
 C_SIGNAL='@t6g_mb_lib.t6g(sch_1):m_k_cpu0_sa_dq(31)';
NODE_NAME     U25 AJ7
 '@T6G_MB_LIB.T6G(SCH_1):PAGE20_I159@PURE_QUANTA.GENOA_SP5(CHIPS)':
 'MKA_DATA31': CDS_PINID='MKA_DATA31';
NODE_NAME     J20 194
 '@T6G_MB_LIB.T6G(SCH_1):PAGE95_I22@PURE_QUANTA.SCONN288_DDR506112002KQ(CHIPS)':
 'DQ31_A': CDS_PINID='DQ31_A';
NET_NAME
'M_K_CPU0_SA_DQ<3>'
 '@T6G_MB_LIB.T6G(SCH_1):M_K_CPU0_SA_DQ'<3>:
 C_SIGNAL='@t6g_mb_lib.t6g(sch_1):m_k_cpu0_sa_dq(3)';
NODE_NAME     U25 G7
 '@T6G_MB_LIB.T6G(SCH_1):PAGE20_I159@PURE_QUANTA.GENOA_SP5(CHIPS)':
 'MKA_DATA3': CDS_PINID='MKA_DATA3';
NODE_NAME     J20 154
 '@T6G_MB_LIB.T6G(SCH_1):PAGE95_I22@PURE_QUANTA.SCONN288_DDR506112002KQ(CHIPS)':
 'DQ3_A': CDS_PINID='DQ3_A';
NET_NAME
'M_K_CPU0_SA_DQ<4>'
 '@T6G_MB_LIB.T6G(SCH_1):M_K_CPU0_SA_DQ'<4>:
 C_SIGNAL='@t6g_mb_lib.t6g(sch_1):m_k_cpu0_sa_dq(4)';
NODE_NAME     U25 J5
 '@T6G_MB_LIB.T6G(SCH_1):PAGE20_I159@PURE_QUANTA.GENOA_SP5(CHIPS)':
 'MKA_DATA4': CDS_PINID='MKA_DATA4';
NODE_NAME     J20 14
 '@T6G_MB_LIB.T6G(SCH_1):PAGE95_I22@PURE_QUANTA.SCONN288_DDR506112002KQ(CHIPS)':
 'DQ4_A': CDS_PINID='DQ4_A';
NET_NAME
'M_K_CPU0_SA_DQ<5>'
 '@T6G_MB_LIB.T6G(SCH_1):M_K_CPU0_SA_DQ'<5>:
 C_SIGNAL='@t6g_mb_lib.t6g(sch_1):m_k_cpu0_sa_dq(5)';
NODE_NAME     U25 K7
 '@T6G_MB_LIB.T6G(SCH_1):PAGE20_I159@PURE_QUANTA.GENOA_SP5(CHIPS)':
 'MKA_DATA5': CDS_PINID='MKA_DATA5';
NODE_NAME     J20 16
 '@T6G_MB_LIB.T6G(SCH_1):PAGE95_I22@PURE_QUANTA.SCONN288_DDR506112002KQ(CHIPS)':
 'DQ5_A': CDS_PINID='DQ5_A';
NET_NAME
'M_K_CPU0_SA_DQ<6>'
 '@T6G_MB_LIB.T6G(SCH_1):M_K_CPU0_SA_DQ'<6>:
 C_SIGNAL='@t6g_mb_lib.t6g(sch_1):m_k_cpu0_sa_dq(6)';
NODE_NAME     U25 K6
 '@T6G_MB_LIB.T6G(SCH_1):PAGE20_I159@PURE_QUANTA.GENOA_SP5(CHIPS)':
 'MKA_DATA6': CDS_PINID='MKA_DATA6';
NODE_NAME     J20 159
 '@T6G_MB_LIB.T6G(SCH_1):PAGE95_I22@PURE_QUANTA.SCONN288_DDR506112002KQ(CHIPS)':
 'DQ6_A': CDS_PINID='DQ6_A';
NET_NAME
'M_K_CPU0_SA_DQ<7>'
 '@T6G_MB_LIB.T6G(SCH_1):M_K_CPU0_SA_DQ'<7>:
 C_SIGNAL='@t6g_mb_lib.t6g(sch_1):m_k_cpu0_sa_dq(7)';
NODE_NAME     U25 L7
 '@T6G_MB_LIB.T6G(SCH_1):PAGE20_I159@PURE_QUANTA.GENOA_SP5(CHIPS)':
 'MKA_DATA7': CDS_PINID='MKA_DATA7';
NODE_NAME     J20 161
 '@T6G_MB_LIB.T6G(SCH_1):PAGE95_I22@PURE_QUANTA.SCONN288_DDR506112002KQ(CHIPS)':
 'DQ7_A': CDS_PINID='DQ7_A';
NET_NAME
'M_K_CPU0_SA_DQ<8>'
 '@T6G_MB_LIB.T6G(SCH_1):M_K_CPU0_SA_DQ'<8>:
 C_SIGNAL='@t6g_mb_lib.t6g(sch_1):m_k_cpu0_sa_dq(8)';
NODE_NAME     U25 L5
 '@T6G_MB_LIB.T6G(SCH_1):PAGE20_I159@PURE_QUANTA.GENOA_SP5(CHIPS)':
 'MKA_DATA8': CDS_PINID='MKA_DATA8';
NODE_NAME     J20 18
 '@T6G_MB_LIB.T6G(SCH_1):PAGE95_I22@PURE_QUANTA.SCONN288_DDR506112002KQ(CHIPS)':
 'DQ8_A': CDS_PINID='DQ8_A';
NET_NAME
'M_K_CPU0_SA_DQ<9>'
 '@T6G_MB_LIB.T6G(SCH_1):M_K_CPU0_SA_DQ'<9>:
 C_SIGNAL='@t6g_mb_lib.t6g(sch_1):m_k_cpu0_sa_dq(9)';
NODE_NAME     U25 M7
 '@T6G_MB_LIB.T6G(SCH_1):PAGE20_I159@PURE_QUANTA.GENOA_SP5(CHIPS)':
 'MKA_DATA9': CDS_PINID='MKA_DATA9';
NODE_NAME     J20 20
 '@T6G_MB_LIB.T6G(SCH_1):PAGE95_I22@PURE_QUANTA.SCONN288_DDR506112002KQ(CHIPS)':
 'DQ9_A': CDS_PINID='DQ9_A';
NET_NAME
'M_K_CPU0_SA_DQS_DN<0>'
 '@T6G_MB_LIB.T6G(SCH_1):M_K_CPU0_SA_DQS_DN'<0>:
 C_SIGNAL='@t6g_mb_lib.t6g(sch_1):m_k_cpu0_sa_dqs_dn(0)';
NODE_NAME     U25 H6
 '@T6G_MB_LIB.T6G(SCH_1):PAGE20_I159@PURE_QUANTA.GENOA_SP5(CHIPS)':
 'MKA_DQS_L0': CDS_PINID='MKA_DQS_L0';
NODE_NAME     J20 12
 '@T6G_MB_LIB.T6G(SCH_1):PAGE95_I236@PURE_QUANTA.SCONN288_DDR506112002KQ(CHIPS)':
 'DQS0_A_C': CDS_PINID='DQS0_A_C';
NET_NAME
'M_K_CPU0_SA_DQS_DN<1>'
 '@T6G_MB_LIB.T6G(SCH_1):M_K_CPU0_SA_DQS_DN'<1>:
 C_SIGNAL='@t6g_mb_lib.t6g(sch_1):m_k_cpu0_sa_dqs_dn(1)';
NODE_NAME     U25 P6
 '@T6G_MB_LIB.T6G(SCH_1):PAGE20_I159@PURE_QUANTA.GENOA_SP5(CHIPS)':
 'MKA_DQS_L1': CDS_PINID='MKA_DQS_L1';
NODE_NAME     J20 23
 '@T6G_MB_LIB.T6G(SCH_1):PAGE95_I236@PURE_QUANTA.SCONN288_DDR506112002KQ(CHIPS)':
 'DQS1_A_C': CDS_PINID='DQS1_A_C';
NET_NAME
'M_K_CPU0_SA_DQS_DN<2>'
 '@T6G_MB_LIB.T6G(SCH_1):M_K_CPU0_SA_DQS_DN'<2>:
 C_SIGNAL='@t6g_mb_lib.t6g(sch_1):m_k_cpu0_sa_dqs_dn(2)';
NODE_NAME     U25 Y6
 '@T6G_MB_LIB.T6G(SCH_1):PAGE20_I159@PURE_QUANTA.GENOA_SP5(CHIPS)':
 'MKA_DQS_L2': CDS_PINID='MKA_DQS_L2';
NODE_NAME     J20 34
 '@T6G_MB_LIB.T6G(SCH_1):PAGE95_I236@PURE_QUANTA.SCONN288_DDR506112002KQ(CHIPS)':
 'DQS2_A_C': CDS_PINID='DQS2_A_C';
NET_NAME
'M_K_CPU0_SA_DQS_DN<3>'
 '@T6G_MB_LIB.T6G(SCH_1):M_K_CPU0_SA_DQS_DN'<3>:
 C_SIGNAL='@t6g_mb_lib.t6g(sch_1):m_k_cpu0_sa_dqs_dn(3)';
NODE_NAME     U25 AF6
 '@T6G_MB_LIB.T6G(SCH_1):PAGE20_I159@PURE_QUANTA.GENOA_SP5(CHIPS)':
 'MKA_DQS_L3': CDS_PINID='MKA_DQS_L3';
NODE_NAME     J20 45
 '@T6G_MB_LIB.T6G(SCH_1):PAGE95_I236@PURE_QUANTA.SCONN288_DDR506112002KQ(CHIPS)':
 'DQS3_A_C': CDS_PINID='DQS3_A_C';
NET_NAME
'M_K_CPU0_SA_DQS_DN<4>'
 '@T6G_MB_LIB.T6G(SCH_1):M_K_CPU0_SA_DQS_DN'<4>:
 C_SIGNAL='@t6g_mb_lib.t6g(sch_1):m_k_cpu0_sa_dqs_dn(4)';
NODE_NAME     U25 AM6
 '@T6G_MB_LIB.T6G(SCH_1):PAGE20_I159@PURE_QUANTA.GENOA_SP5(CHIPS)':
 'MKA_DQS_L4': CDS_PINID='MKA_DQS_L4';
NODE_NAME     J20 56
 '@T6G_MB_LIB.T6G(SCH_1):PAGE95_I236@PURE_QUANTA.SCONN288_DDR506112002KQ(CHIPS)':
 'DQS4_A_C': CDS_PINID='DQS4_A_C';
NET_NAME
'M_K_CPU0_SA_DQS_DN<5>'
 '@T6G_MB_LIB.T6G(SCH_1):M_K_CPU0_SA_DQS_DN'<5>:
 C_SIGNAL='@t6g_mb_lib.t6g(sch_1):m_k_cpu0_sa_dqs_dn(5)';
NODE_NAME     U25 H7
 '@T6G_MB_LIB.T6G(SCH_1):PAGE20_I159@PURE_QUANTA.GENOA_SP5(CHIPS)':
 'MKA_DQS_L5': CDS_PINID='MKA_DQS_L5';
NODE_NAME     J20 156
 '@T6G_MB_LIB.T6G(SCH_1):PAGE95_I236@PURE_QUANTA.SCONN288_DDR506112002KQ(CHIPS)':
 'DQS5_A_C||TDQS5_A_C||DQS5_A_T||TDQS5_A_T': CDS_PINID='\dqs5_a_c||tdqs5_a_c||dqs5_a_t||tdqs5_a_t\';
NET_NAME
'M_K_CPU0_SA_DQS_DN<6>'
 '@T6G_MB_LIB.T6G(SCH_1):M_K_CPU0_SA_DQS_DN'<6>:
 C_SIGNAL='@t6g_mb_lib.t6g(sch_1):m_k_cpu0_sa_dqs_dn(6)';
NODE_NAME     U25 P7
 '@T6G_MB_LIB.T6G(SCH_1):PAGE20_I159@PURE_QUANTA.GENOA_SP5(CHIPS)':
 'MKA_DQS_L6': CDS_PINID='MKA_DQS_L6';
NODE_NAME     J20 167
 '@T6G_MB_LIB.T6G(SCH_1):PAGE95_I236@PURE_QUANTA.SCONN288_DDR506112002KQ(CHIPS)':
 'DQS6_A_C||TDQS6_A_C||DQS6_A_T||TDQS6_A_T': CDS_PINID='\dqs6_a_c||tdqs6_a_c||dqs6_a_t||tdqs6_a_t\';
NET_NAME
'M_K_CPU0_SA_DQS_DN<7>'
 '@T6G_MB_LIB.T6G(SCH_1):M_K_CPU0_SA_DQS_DN'<7>:
 C_SIGNAL='@t6g_mb_lib.t6g(sch_1):m_k_cpu0_sa_dqs_dn(7)';
NODE_NAME     U25 Y7
 '@T6G_MB_LIB.T6G(SCH_1):PAGE20_I159@PURE_QUANTA.GENOA_SP5(CHIPS)':
 'MKA_DQS_L7': CDS_PINID='MKA_DQS_L7';
NODE_NAME     J20 178
 '@T6G_MB_LIB.T6G(SCH_1):PAGE95_I236@PURE_QUANTA.SCONN288_DDR506112002KQ(CHIPS)':
 'DQS7_A_C||TDQS7_A_C': CDS_PINID='\dqs7_a_c||tdqs7_a_c\';
NET_NAME
'M_K_CPU0_SA_DQS_DN<8>'
 '@T6G_MB_LIB.T6G(SCH_1):M_K_CPU0_SA_DQS_DN'<8>:
 C_SIGNAL='@t6g_mb_lib.t6g(sch_1):m_k_cpu0_sa_dqs_dn(8)';
NODE_NAME     U25 AF7
 '@T6G_MB_LIB.T6G(SCH_1):PAGE20_I159@PURE_QUANTA.GENOA_SP5(CHIPS)':
 'MKA_DQS_L8': CDS_PINID='MKA_DQS_L8';
NODE_NAME     J20 189
 '@T6G_MB_LIB.T6G(SCH_1):PAGE95_I236@PURE_QUANTA.SCONN288_DDR506112002KQ(CHIPS)':
 'DQS8_A_C||TDQS8_A_C': CDS_PINID='\dqs8_a_c||tdqs8_a_c\';
NET_NAME
'M_K_CPU0_SA_DQS_DN<9>'
 '@T6G_MB_LIB.T6G(SCH_1):M_K_CPU0_SA_DQS_DN'<9>:
 C_SIGNAL='@t6g_mb_lib.t6g(sch_1):m_k_cpu0_sa_dqs_dn(9)';
NODE_NAME     U25 AM7
 '@T6G_MB_LIB.T6G(SCH_1):PAGE20_I159@PURE_QUANTA.GENOA_SP5(CHIPS)':
 'MKA_DQS_L9': CDS_PINID='MKA_DQS_L9';
NODE_NAME     J20 200
 '@T6G_MB_LIB.T6G(SCH_1):PAGE95_I236@PURE_QUANTA.SCONN288_DDR506112002KQ(CHIPS)':
 'DQS9_A_C||TDQS9_A_C': CDS_PINID='\dqs9_a_c||tdqs9_a_c\';
NET_NAME
'M_K_CPU0_SA_DQS_DP<0>'
 '@T6G_MB_LIB.T6G(SCH_1):M_K_CPU0_SA_DQS_DP'<0>:
 C_SIGNAL='@t6g_mb_lib.t6g(sch_1):m_k_cpu0_sa_dqs_dp(0)';
NODE_NAME     U25 G5
 '@T6G_MB_LIB.T6G(SCH_1):PAGE20_I159@PURE_QUANTA.GENOA_SP5(CHIPS)':
 'MKA_DQS_H0': CDS_PINID='MKA_DQS_H0';
NODE_NAME     J20 11
 '@T6G_MB_LIB.T6G(SCH_1):PAGE95_I236@PURE_QUANTA.SCONN288_DDR506112002KQ(CHIPS)':
 'DQS0_A_T': CDS_PINID='DQS0_A_T';
NET_NAME
'M_K_CPU0_SA_DQS_DP<1>'
 '@T6G_MB_LIB.T6G(SCH_1):M_K_CPU0_SA_DQS_DP'<1>:
 C_SIGNAL='@t6g_mb_lib.t6g(sch_1):m_k_cpu0_sa_dqs_dp(1)';
NODE_NAME     U25 N5
 '@T6G_MB_LIB.T6G(SCH_1):PAGE20_I159@PURE_QUANTA.GENOA_SP5(CHIPS)':
 'MKA_DQS_H1': CDS_PINID='MKA_DQS_H1';
NODE_NAME     J20 22
 '@T6G_MB_LIB.T6G(SCH_1):PAGE95_I236@PURE_QUANTA.SCONN288_DDR506112002KQ(CHIPS)':
 'DQS1_A_T': CDS_PINID='DQS1_A_T';
NET_NAME
'M_K_CPU0_SA_DQS_DP<2>'
 '@T6G_MB_LIB.T6G(SCH_1):M_K_CPU0_SA_DQS_DP'<2>:
 C_SIGNAL='@t6g_mb_lib.t6g(sch_1):m_k_cpu0_sa_dqs_dp(2)';
NODE_NAME     U25 W5
 '@T6G_MB_LIB.T6G(SCH_1):PAGE20_I159@PURE_QUANTA.GENOA_SP5(CHIPS)':
 'MKA_DQS_H2': CDS_PINID='MKA_DQS_H2';
NODE_NAME     J20 33
 '@T6G_MB_LIB.T6G(SCH_1):PAGE95_I236@PURE_QUANTA.SCONN288_DDR506112002KQ(CHIPS)':
 'DQS2_A_T': CDS_PINID='DQS2_A_T';
NET_NAME
'M_K_CPU0_SA_DQS_DP<3>'
 '@T6G_MB_LIB.T6G(SCH_1):M_K_CPU0_SA_DQS_DP'<3>:
 C_SIGNAL='@t6g_mb_lib.t6g(sch_1):m_k_cpu0_sa_dqs_dp(3)';
NODE_NAME     U25 AE5
 '@T6G_MB_LIB.T6G(SCH_1):PAGE20_I159@PURE_QUANTA.GENOA_SP5(CHIPS)':
 'MKA_DQS_H3': CDS_PINID='MKA_DQS_H3';
NODE_NAME     J20 44
 '@T6G_MB_LIB.T6G(SCH_1):PAGE95_I236@PURE_QUANTA.SCONN288_DDR506112002KQ(CHIPS)':
 'DQS3_A_T': CDS_PINID='DQS3_A_T';
NET_NAME
'M_K_CPU0_SA_DQS_DP<4>'
 '@T6G_MB_LIB.T6G(SCH_1):M_K_CPU0_SA_DQS_DP'<4>:
 C_SIGNAL='@t6g_mb_lib.t6g(sch_1):m_k_cpu0_sa_dqs_dp(4)';
NODE_NAME     U25 AL5
 '@T6G_MB_LIB.T6G(SCH_1):PAGE20_I159@PURE_QUANTA.GENOA_SP5(CHIPS)':
 'MKA_DQS_H4': CDS_PINID='MKA_DQS_H4';
NODE_NAME     J20 55
 '@T6G_MB_LIB.T6G(SCH_1):PAGE95_I236@PURE_QUANTA.SCONN288_DDR506112002KQ(CHIPS)':
 'DQS4_A_T': CDS_PINID='DQS4_A_T';
NET_NAME
'M_K_CPU0_SA_DQS_DP<5>'
 '@T6G_MB_LIB.T6G(SCH_1):M_K_CPU0_SA_DQS_DP'<5>:
 C_SIGNAL='@t6g_mb_lib.t6g(sch_1):m_k_cpu0_sa_dqs_dp(5)';
NODE_NAME     U25 J7
 '@T6G_MB_LIB.T6G(SCH_1):PAGE20_I159@PURE_QUANTA.GENOA_SP5(CHIPS)':
 'MKA_DQS_H5': CDS_PINID='MKA_DQS_H5';
NODE_NAME     J20 157
 '@T6G_MB_LIB.T6G(SCH_1):PAGE95_I236@PURE_QUANTA.SCONN288_DDR506112002KQ(CHIPS)':
 'DQS5_A_T||TDQS5_A_T': CDS_PINID='\dqs5_a_t||tdqs5_a_t\';
NET_NAME
'M_K_CPU0_SA_DQS_DP<6>'
 '@T6G_MB_LIB.T6G(SCH_1):M_K_CPU0_SA_DQS_DP'<6>:
 C_SIGNAL='@t6g_mb_lib.t6g(sch_1):m_k_cpu0_sa_dqs_dp(6)';
NODE_NAME     U25 R7
 '@T6G_MB_LIB.T6G(SCH_1):PAGE20_I159@PURE_QUANTA.GENOA_SP5(CHIPS)':
 'MKA_DQS_H6': CDS_PINID='MKA_DQS_H6';
NODE_NAME     J20 168
 '@T6G_MB_LIB.T6G(SCH_1):PAGE95_I236@PURE_QUANTA.SCONN288_DDR506112002KQ(CHIPS)':
 'DQS6_A_T||TDQS6_A_T': CDS_PINID='\dqs6_a_t||tdqs6_a_t\';
NET_NAME
'M_K_CPU0_SA_DQS_DP<7>'
 '@T6G_MB_LIB.T6G(SCH_1):M_K_CPU0_SA_DQS_DP'<7>:
 C_SIGNAL='@t6g_mb_lib.t6g(sch_1):m_k_cpu0_sa_dqs_dp(7)';
NODE_NAME     U25 AA7
 '@T6G_MB_LIB.T6G(SCH_1):PAGE20_I159@PURE_QUANTA.GENOA_SP5(CHIPS)':
 'MKA_DQS_H7': CDS_PINID='MKA_DQS_H7';
NODE_NAME     J20 179
 '@T6G_MB_LIB.T6G(SCH_1):PAGE95_I236@PURE_QUANTA.SCONN288_DDR506112002KQ(CHIPS)':
 'DQS7_A_T||TDQS7_A_T': CDS_PINID='\dqs7_a_t||tdqs7_a_t\';
NET_NAME
'M_K_CPU0_SA_DQS_DP<8>'
 '@T6G_MB_LIB.T6G(SCH_1):M_K_CPU0_SA_DQS_DP'<8>:
 C_SIGNAL='@t6g_mb_lib.t6g(sch_1):m_k_cpu0_sa_dqs_dp(8)';
NODE_NAME     U25 AG7
 '@T6G_MB_LIB.T6G(SCH_1):PAGE20_I159@PURE_QUANTA.GENOA_SP5(CHIPS)':
 'MKA_DQS_H8': CDS_PINID='MKA_DQS_H8';
NODE_NAME     J20 190
 '@T6G_MB_LIB.T6G(SCH_1):PAGE95_I236@PURE_QUANTA.SCONN288_DDR506112002KQ(CHIPS)':
 'DQS8_A_T||TDQS8_A_T': CDS_PINID='\dqs8_a_t||tdqs8_a_t\';
NET_NAME
'M_K_CPU0_SA_DQS_DP<9>'
 '@T6G_MB_LIB.T6G(SCH_1):M_K_CPU0_SA_DQS_DP'<9>:
 C_SIGNAL='@t6g_mb_lib.t6g(sch_1):m_k_cpu0_sa_dqs_dp(9)';
NODE_NAME     U25 AN7
 '@T6G_MB_LIB.T6G(SCH_1):PAGE20_I159@PURE_QUANTA.GENOA_SP5(CHIPS)':
 'MKA_DQS_H9': CDS_PINID='MKA_DQS_H9';
NODE_NAME     J20 201
 '@T6G_MB_LIB.T6G(SCH_1):PAGE95_I236@PURE_QUANTA.SCONN288_DDR506112002KQ(CHIPS)':
 'DQS9_A_T||TDQS9_A_T': CDS_PINID='\dqs9_a_t||tdqs9_a_t\';
NET_NAME
'M_K_CPU0_SA_PAR'
 '@T6G_MB_LIB.T6G(SCH_1):M_K_CPU0_SA_PAR':
 C_SIGNAL='@t6g_mb_lib.t6g(sch_1):m_k_cpu0_sa_par';
NODE_NAME     U25 BC7
 '@T6G_MB_LIB.T6G(SCH_1):PAGE20_I159@PURE_QUANTA.GENOA_SP5(CHIPS)':
 'MKA_PAR': CDS_PINID='MKA_PAR';
NODE_NAME     J20 74
 '@T6G_MB_LIB.T6G(SCH_1):PAGE95_I22@PURE_QUANTA.SCONN288_DDR506112002KQ(CHIPS)':
 'PAR_A': CDS_PINID='PAR_A';
NET_NAME
'M_K_CPU0_SA_RSP<0>'
 '@T6G_MB_LIB.T6G(SCH_1):M_K_CPU0_SA_RSP'<0>:
 C_SIGNAL='@t6g_mb_lib.t6g(sch_1):m_k_cpu0_sa_rsp(0)';
NODE_NAME     U25 BN7
 '@T6G_MB_LIB.T6G(SCH_1):PAGE20_I159@PURE_QUANTA.GENOA_SP5(CHIPS)':
 'MKA0_RSP_L': CDS_PINID='MKA0_RSP_L';
NODE_NAME     J20 86
 '@T6G_MB_LIB.T6G(SCH_1):PAGE95_I22@PURE_QUANTA.SCONN288_DDR506112002KQ(CHIPS)':
 'LBD||RSP_A_N': CDS_PINID='\lbd||rsp_a_n\';
NET_NAME
'M_K_CPU0_SB_CA<0>'
 '@T6G_MB_LIB.T6G(SCH_1):M_K_CPU0_SB_CA'<0>:
 C_SIGNAL='@t6g_mb_lib.t6g(sch_1):m_k_cpu0_sb_ca(0)';
NODE_NAME     U25 BG7
 '@T6G_MB_LIB.T6G(SCH_1):PAGE20_I159@PURE_QUANTA.GENOA_SP5(CHIPS)':
 'MKB_CA0': CDS_PINID='MKB_CA0';
NODE_NAME     J20 76
 '@T6G_MB_LIB.T6G(SCH_1):PAGE95_I22@PURE_QUANTA.SCONN288_DDR506112002KQ(CHIPS)':
 'CA0_B': CDS_PINID='CA0_B';
NET_NAME
'M_K_CPU0_SB_CA<1>'
 '@T6G_MB_LIB.T6G(SCH_1):M_K_CPU0_SB_CA'<1>:
 C_SIGNAL='@t6g_mb_lib.t6g(sch_1):m_k_cpu0_sb_ca(1)';
NODE_NAME     U25 BH7
 '@T6G_MB_LIB.T6G(SCH_1):PAGE20_I159@PURE_QUANTA.GENOA_SP5(CHIPS)':
 'MKB_CA1': CDS_PINID='MKB_CA1';
NODE_NAME     J20 221
 '@T6G_MB_LIB.T6G(SCH_1):PAGE95_I22@PURE_QUANTA.SCONN288_DDR506112002KQ(CHIPS)':
 'CA1_B': CDS_PINID='CA1_B';
NET_NAME
'M_K_CPU0_SB_CA<2>'
 '@T6G_MB_LIB.T6G(SCH_1):M_K_CPU0_SB_CA'<2>:
 C_SIGNAL='@t6g_mb_lib.t6g(sch_1):m_k_cpu0_sb_ca(2)';
NODE_NAME     U25 BH6
 '@T6G_MB_LIB.T6G(SCH_1):PAGE20_I159@PURE_QUANTA.GENOA_SP5(CHIPS)':
 'MKB_CA2': CDS_PINID='MKB_CA2';
NODE_NAME     J20 78
 '@T6G_MB_LIB.T6G(SCH_1):PAGE95_I22@PURE_QUANTA.SCONN288_DDR506112002KQ(CHIPS)':
 'CA2_B': CDS_PINID='CA2_B';
NET_NAME
'M_K_CPU0_SB_CA<3>'
 '@T6G_MB_LIB.T6G(SCH_1):M_K_CPU0_SB_CA'<3>:
 C_SIGNAL='@t6g_mb_lib.t6g(sch_1):m_k_cpu0_sb_ca(3)';
NODE_NAME     U25 BJ5
 '@T6G_MB_LIB.T6G(SCH_1):PAGE20_I159@PURE_QUANTA.GENOA_SP5(CHIPS)':
 'MKB_CA3': CDS_PINID='MKB_CA3';
NODE_NAME     J20 223
 '@T6G_MB_LIB.T6G(SCH_1):PAGE95_I22@PURE_QUANTA.SCONN288_DDR506112002KQ(CHIPS)':
 'CA3_B': CDS_PINID='CA3_B';
NET_NAME
'M_K_CPU0_SB_CA<4>'
 '@T6G_MB_LIB.T6G(SCH_1):M_K_CPU0_SB_CA'<4>:
 C_SIGNAL='@t6g_mb_lib.t6g(sch_1):m_k_cpu0_sb_ca(4)';
NODE_NAME     U25 BJ7
 '@T6G_MB_LIB.T6G(SCH_1):PAGE20_I159@PURE_QUANTA.GENOA_SP5(CHIPS)':
 'MKB_CA4': CDS_PINID='MKB_CA4';
NODE_NAME     J20 80
 '@T6G_MB_LIB.T6G(SCH_1):PAGE95_I22@PURE_QUANTA.SCONN288_DDR506112002KQ(CHIPS)':
 'CA4_B': CDS_PINID='CA4_B';
NET_NAME
'M_K_CPU0_SB_CA<5>'
 '@T6G_MB_LIB.T6G(SCH_1):M_K_CPU0_SB_CA'<5>:
 C_SIGNAL='@t6g_mb_lib.t6g(sch_1):m_k_cpu0_sb_ca(5)';
NODE_NAME     U25 BK7
 '@T6G_MB_LIB.T6G(SCH_1):PAGE20_I159@PURE_QUANTA.GENOA_SP5(CHIPS)':
 'MKB_CA5': CDS_PINID='MKB_CA5';
NODE_NAME     J20 225
 '@T6G_MB_LIB.T6G(SCH_1):PAGE95_I22@PURE_QUANTA.SCONN288_DDR506112002KQ(CHIPS)':
 'CA5_B': CDS_PINID='CA5_B';
NET_NAME
'M_K_CPU0_SB_CA<6>'
 '@T6G_MB_LIB.T6G(SCH_1):M_K_CPU0_SB_CA'<6>:
 C_SIGNAL='@t6g_mb_lib.t6g(sch_1):m_k_cpu0_sb_ca(6)';
NODE_NAME     U25 BK6
 '@T6G_MB_LIB.T6G(SCH_1):PAGE20_I159@PURE_QUANTA.GENOA_SP5(CHIPS)':
 'MKB_CA6': CDS_PINID='MKB_CA6';
NODE_NAME     J20 82
 '@T6G_MB_LIB.T6G(SCH_1):PAGE95_I22@PURE_QUANTA.SCONN288_DDR506112002KQ(CHIPS)':
 'CA6_B': CDS_PINID='CA6_B';
NET_NAME
'M_K_CPU0_SB_CB<0>'
 '@T6G_MB_LIB.T6G(SCH_1):M_K_CPU0_SB_CB'<0>:
 C_SIGNAL='@t6g_mb_lib.t6g(sch_1):m_k_cpu0_sb_cb(0)';
NODE_NAME     U25 BY6
 '@T6G_MB_LIB.T6G(SCH_1):PAGE20_I159@PURE_QUANTA.GENOA_SP5(CHIPS)':
 'MKB_CHECK0': CDS_PINID='MKB_CHECK0';
NODE_NAME     J20 96
 '@T6G_MB_LIB.T6G(SCH_1):PAGE95_I22@PURE_QUANTA.SCONN288_DDR506112002KQ(CHIPS)':
 'CB0_B': CDS_PINID='CB0_B';
NET_NAME
'M_K_CPU0_SB_CB<1>'
 '@T6G_MB_LIB.T6G(SCH_1):M_K_CPU0_SB_CB'<1>:
 C_SIGNAL='@t6g_mb_lib.t6g(sch_1):m_k_cpu0_sb_cb(1)';
NODE_NAME     U25 CA7
 '@T6G_MB_LIB.T6G(SCH_1):PAGE20_I159@PURE_QUANTA.GENOA_SP5(CHIPS)':
 'MKB_CHECK1': CDS_PINID='MKB_CHECK1';
NODE_NAME     J20 98
 '@T6G_MB_LIB.T6G(SCH_1):PAGE95_I22@PURE_QUANTA.SCONN288_DDR506112002KQ(CHIPS)':
 'CB1_B': CDS_PINID='CB1_B';
NET_NAME
'M_K_CPU0_SB_CB<2>'
 '@T6G_MB_LIB.T6G(SCH_1):M_K_CPU0_SB_CB'<2>:
 C_SIGNAL='@t6g_mb_lib.t6g(sch_1):m_k_cpu0_sb_cb(2)';
NODE_NAME     U25 CA5
 '@T6G_MB_LIB.T6G(SCH_1):PAGE20_I159@PURE_QUANTA.GENOA_SP5(CHIPS)':
 'MKB_CHECK2': CDS_PINID='MKB_CHECK2';
NODE_NAME     J20 241
 '@T6G_MB_LIB.T6G(SCH_1):PAGE95_I22@PURE_QUANTA.SCONN288_DDR506112002KQ(CHIPS)':
 'CB2_B': CDS_PINID='CB2_B';
NET_NAME
'M_K_CPU0_SB_CB<3>'
 '@T6G_MB_LIB.T6G(SCH_1):M_K_CPU0_SB_CB'<3>:
 C_SIGNAL='@t6g_mb_lib.t6g(sch_1):m_k_cpu0_sb_cb(3)';
NODE_NAME     U25 CB7
 '@T6G_MB_LIB.T6G(SCH_1):PAGE20_I159@PURE_QUANTA.GENOA_SP5(CHIPS)':
 'MKB_CHECK3': CDS_PINID='MKB_CHECK3';
NODE_NAME     J20 243
 '@T6G_MB_LIB.T6G(SCH_1):PAGE95_I22@PURE_QUANTA.SCONN288_DDR506112002KQ(CHIPS)':
 'CB3_B': CDS_PINID='CB3_B';
NET_NAME
'M_K_CPU0_SB_CB<4>'
 '@T6G_MB_LIB.T6G(SCH_1):M_K_CPU0_SB_CB'<4>:
 C_SIGNAL='@t6g_mb_lib.t6g(sch_1):m_k_cpu0_sb_cb(4)';
NODE_NAME     U25 BT6
 '@T6G_MB_LIB.T6G(SCH_1):PAGE20_I159@PURE_QUANTA.GENOA_SP5(CHIPS)':
 'MKB_CHECK4': CDS_PINID='MKB_CHECK4';
NODE_NAME     J20 89
 '@T6G_MB_LIB.T6G(SCH_1):PAGE95_I22@PURE_QUANTA.SCONN288_DDR506112002KQ(CHIPS)':
 'CB4_B': CDS_PINID='CB4_B';
NET_NAME
'M_K_CPU0_SB_CB<5>'
 '@T6G_MB_LIB.T6G(SCH_1):M_K_CPU0_SB_CB'<5>:
 C_SIGNAL='@t6g_mb_lib.t6g(sch_1):m_k_cpu0_sb_cb(5)';
NODE_NAME     U25 BU7
 '@T6G_MB_LIB.T6G(SCH_1):PAGE20_I159@PURE_QUANTA.GENOA_SP5(CHIPS)':
 'MKB_CHECK5': CDS_PINID='MKB_CHECK5';
NODE_NAME     J20 91
 '@T6G_MB_LIB.T6G(SCH_1):PAGE95_I22@PURE_QUANTA.SCONN288_DDR506112002KQ(CHIPS)':
 'CB5_B': CDS_PINID='CB5_B';
NET_NAME
'M_K_CPU0_SB_CB<6>'
 '@T6G_MB_LIB.T6G(SCH_1):M_K_CPU0_SB_CB'<6>:
 C_SIGNAL='@t6g_mb_lib.t6g(sch_1):m_k_cpu0_sb_cb(6)';
NODE_NAME     U25 BU5
 '@T6G_MB_LIB.T6G(SCH_1):PAGE20_I159@PURE_QUANTA.GENOA_SP5(CHIPS)':
 'MKB_CHECK6': CDS_PINID='MKB_CHECK6';
NODE_NAME     J20 234
 '@T6G_MB_LIB.T6G(SCH_1):PAGE95_I22@PURE_QUANTA.SCONN288_DDR506112002KQ(CHIPS)':
 'CB6_B': CDS_PINID='CB6_B';
NET_NAME
'M_K_CPU0_SB_CB<7>'
 '@T6G_MB_LIB.T6G(SCH_1):M_K_CPU0_SB_CB'<7>:
 C_SIGNAL='@t6g_mb_lib.t6g(sch_1):m_k_cpu0_sb_cb(7)';
NODE_NAME     U25 BV7
 '@T6G_MB_LIB.T6G(SCH_1):PAGE20_I159@PURE_QUANTA.GENOA_SP5(CHIPS)':
 'MKB_CHECK7': CDS_PINID='MKB_CHECK7';
NODE_NAME     J20 236
 '@T6G_MB_LIB.T6G(SCH_1):PAGE95_I22@PURE_QUANTA.SCONN288_DDR506112002KQ(CHIPS)':
 'CB7_B': CDS_PINID='CB7_B';
NET_NAME
'M_K_CPU0_SB_CS_N<0>'
 '@T6G_MB_LIB.T6G(SCH_1):M_K_CPU0_SB_CS_N'<0>:
 C_SIGNAL='@t6g_mb_lib.t6g(sch_1):m_k_cpu0_sb_cs_n(0)';
NODE_NAME     U25 BM7
 '@T6G_MB_LIB.T6G(SCH_1):PAGE20_I159@PURE_QUANTA.GENOA_SP5(CHIPS)':
 'MKB0_CS_L0': CDS_PINID='MKB0_CS_L0';
NODE_NAME     J20 84
 '@T6G_MB_LIB.T6G(SCH_1):PAGE95_I22@PURE_QUANTA.SCONN288_DDR506112002KQ(CHIPS)':
 'CS0_B_N': CDS_PINID='CS0_B_N';
NET_NAME
'M_K_CPU0_SB_CS_N<1>'
 '@T6G_MB_LIB.T6G(SCH_1):M_K_CPU0_SB_CS_N'<1>:
 C_SIGNAL='@t6g_mb_lib.t6g(sch_1):m_k_cpu0_sb_cs_n(1)';
NODE_NAME     U25 BN5
 '@T6G_MB_LIB.T6G(SCH_1):PAGE20_I159@PURE_QUANTA.GENOA_SP5(CHIPS)':
 'MKB0_CS_L1': CDS_PINID='MKB0_CS_L1';
NODE_NAME     J20 229
 '@T6G_MB_LIB.T6G(SCH_1):PAGE95_I22@PURE_QUANTA.SCONN288_DDR506112002KQ(CHIPS)':
 'CS1_B_N': CDS_PINID='CS1_B_N';
NET_NAME
'M_K_CPU0_SB_DQ<0>'
 '@T6G_MB_LIB.T6G(SCH_1):M_K_CPU0_SB_DQ'<0>:
 C_SIGNAL='@t6g_mb_lib.t6g(sch_1):m_k_cpu0_sb_dq(0)';
NODE_NAME     U25 CB6
 '@T6G_MB_LIB.T6G(SCH_1):PAGE20_I159@PURE_QUANTA.GENOA_SP5(CHIPS)':
 'MKB_DATA0': CDS_PINID='MKB_DATA0';
NODE_NAME     J20 100
 '@T6G_MB_LIB.T6G(SCH_1):PAGE95_I22@PURE_QUANTA.SCONN288_DDR506112002KQ(CHIPS)':
 'DQ0_B': CDS_PINID='DQ0_B';
NET_NAME
'M_K_CPU0_SB_DQ<10>'
 '@T6G_MB_LIB.T6G(SCH_1):M_K_CPU0_SB_DQ'<10>:
 C_SIGNAL='@t6g_mb_lib.t6g(sch_1):m_k_cpu0_sb_dq(10)';
NODE_NAME     U25 CJ5
 '@T6G_MB_LIB.T6G(SCH_1):PAGE20_I159@PURE_QUANTA.GENOA_SP5(CHIPS)':
 'MKB_DATA10': CDS_PINID='MKB_DATA10';
NODE_NAME     J20 256
 '@T6G_MB_LIB.T6G(SCH_1):PAGE95_I22@PURE_QUANTA.SCONN288_DDR506112002KQ(CHIPS)':
 'DQ10_B': CDS_PINID='DQ10_B';
NET_NAME
'M_K_CPU0_SB_DQ<11>'
 '@T6G_MB_LIB.T6G(SCH_1):M_K_CPU0_SB_DQ'<11>:
 C_SIGNAL='@t6g_mb_lib.t6g(sch_1):m_k_cpu0_sb_dq(11)';
NODE_NAME     U25 CK7
 '@T6G_MB_LIB.T6G(SCH_1):PAGE20_I159@PURE_QUANTA.GENOA_SP5(CHIPS)':
 'MKB_DATA11': CDS_PINID='MKB_DATA11';
NODE_NAME     J20 258
 '@T6G_MB_LIB.T6G(SCH_1):PAGE95_I22@PURE_QUANTA.SCONN288_DDR506112002KQ(CHIPS)':
 'DQ11_B': CDS_PINID='DQ11_B';
NET_NAME
'M_K_CPU0_SB_DQ<12>'
 '@T6G_MB_LIB.T6G(SCH_1):M_K_CPU0_SB_DQ'<12>:
 C_SIGNAL='@t6g_mb_lib.t6g(sch_1):m_k_cpu0_sb_dq(12)';
NODE_NAME     U25 CM6
 '@T6G_MB_LIB.T6G(SCH_1):PAGE20_I159@PURE_QUANTA.GENOA_SP5(CHIPS)':
 'MKB_DATA12': CDS_PINID='MKB_DATA12';
NODE_NAME     J20 118
 '@T6G_MB_LIB.T6G(SCH_1):PAGE95_I22@PURE_QUANTA.SCONN288_DDR506112002KQ(CHIPS)':
 'DQ12_B': CDS_PINID='DQ12_B';
NET_NAME
'M_K_CPU0_SB_DQ<13>'
 '@T6G_MB_LIB.T6G(SCH_1):M_K_CPU0_SB_DQ'<13>:
 C_SIGNAL='@t6g_mb_lib.t6g(sch_1):m_k_cpu0_sb_dq(13)';
NODE_NAME     U25 CN7
 '@T6G_MB_LIB.T6G(SCH_1):PAGE20_I159@PURE_QUANTA.GENOA_SP5(CHIPS)':
 'MKB_DATA13': CDS_PINID='MKB_DATA13';
NODE_NAME     J20 120
 '@T6G_MB_LIB.T6G(SCH_1):PAGE95_I22@PURE_QUANTA.SCONN288_DDR506112002KQ(CHIPS)':
 'DQ13_B': CDS_PINID='DQ13_B';
NET_NAME
'M_K_CPU0_SB_DQ<14>'
 '@T6G_MB_LIB.T6G(SCH_1):M_K_CPU0_SB_DQ'<14>:
 C_SIGNAL='@t6g_mb_lib.t6g(sch_1):m_k_cpu0_sb_dq(14)';
NODE_NAME     U25 CN5
 '@T6G_MB_LIB.T6G(SCH_1):PAGE20_I159@PURE_QUANTA.GENOA_SP5(CHIPS)':
 'MKB_DATA14': CDS_PINID='MKB_DATA14';
NODE_NAME     J20 263
 '@T6G_MB_LIB.T6G(SCH_1):PAGE95_I22@PURE_QUANTA.SCONN288_DDR506112002KQ(CHIPS)':
 'DQ14_B': CDS_PINID='DQ14_B';
NET_NAME
'M_K_CPU0_SB_DQ<15>'
 '@T6G_MB_LIB.T6G(SCH_1):M_K_CPU0_SB_DQ'<15>:
 C_SIGNAL='@t6g_mb_lib.t6g(sch_1):m_k_cpu0_sb_dq(15)';
NODE_NAME     U25 CP7
 '@T6G_MB_LIB.T6G(SCH_1):PAGE20_I159@PURE_QUANTA.GENOA_SP5(CHIPS)':
 'MKB_DATA15': CDS_PINID='MKB_DATA15';
NODE_NAME     J20 265
 '@T6G_MB_LIB.T6G(SCH_1):PAGE95_I22@PURE_QUANTA.SCONN288_DDR506112002KQ(CHIPS)':
 'DQ15_B': CDS_PINID='DQ15_B';
NET_NAME
'M_K_CPU0_SB_DQ<16>'
 '@T6G_MB_LIB.T6G(SCH_1):M_K_CPU0_SB_DQ'<16>:
 C_SIGNAL='@t6g_mb_lib.t6g(sch_1):m_k_cpu0_sb_dq(16)';
NODE_NAME     U25 CP6
 '@T6G_MB_LIB.T6G(SCH_1):PAGE20_I159@PURE_QUANTA.GENOA_SP5(CHIPS)':
 'MKB_DATA16': CDS_PINID='MKB_DATA16';
NODE_NAME     J20 122
 '@T6G_MB_LIB.T6G(SCH_1):PAGE95_I22@PURE_QUANTA.SCONN288_DDR506112002KQ(CHIPS)':
 'DQ16_B': CDS_PINID='DQ16_B';
NET_NAME
'M_K_CPU0_SB_DQ<17>'
 '@T6G_MB_LIB.T6G(SCH_1):M_K_CPU0_SB_DQ'<17>:
 C_SIGNAL='@t6g_mb_lib.t6g(sch_1):m_k_cpu0_sb_dq(17)';
NODE_NAME     U25 CR7
 '@T6G_MB_LIB.T6G(SCH_1):PAGE20_I159@PURE_QUANTA.GENOA_SP5(CHIPS)':
 'MKB_DATA17': CDS_PINID='MKB_DATA17';
NODE_NAME     J20 124
 '@T6G_MB_LIB.T6G(SCH_1):PAGE95_I22@PURE_QUANTA.SCONN288_DDR506112002KQ(CHIPS)':
 'DQ17_B': CDS_PINID='DQ17_B';
NET_NAME
'M_K_CPU0_SB_DQ<18>'
 '@T6G_MB_LIB.T6G(SCH_1):M_K_CPU0_SB_DQ'<18>:
 C_SIGNAL='@t6g_mb_lib.t6g(sch_1):m_k_cpu0_sb_dq(18)';
NODE_NAME     U25 CR5
 '@T6G_MB_LIB.T6G(SCH_1):PAGE20_I159@PURE_QUANTA.GENOA_SP5(CHIPS)':
 'MKB_DATA18': CDS_PINID='MKB_DATA18';
NODE_NAME     J20 267
 '@T6G_MB_LIB.T6G(SCH_1):PAGE95_I22@PURE_QUANTA.SCONN288_DDR506112002KQ(CHIPS)':
 'DQ18_B': CDS_PINID='DQ18_B';
NET_NAME
'M_K_CPU0_SB_DQ<19>'
 '@T6G_MB_LIB.T6G(SCH_1):M_K_CPU0_SB_DQ'<19>:
 C_SIGNAL='@t6g_mb_lib.t6g(sch_1):m_k_cpu0_sb_dq(19)';
NODE_NAME     U25 CT7
 '@T6G_MB_LIB.T6G(SCH_1):PAGE20_I159@PURE_QUANTA.GENOA_SP5(CHIPS)':
 'MKB_DATA19': CDS_PINID='MKB_DATA19';
NODE_NAME     J20 269
 '@T6G_MB_LIB.T6G(SCH_1):PAGE95_I22@PURE_QUANTA.SCONN288_DDR506112002KQ(CHIPS)':
 'DQ19_B': CDS_PINID='DQ19_B';
NET_NAME
'M_K_CPU0_SB_DQ<1>'
 '@T6G_MB_LIB.T6G(SCH_1):M_K_CPU0_SB_DQ'<1>:
 C_SIGNAL='@t6g_mb_lib.t6g(sch_1):m_k_cpu0_sb_dq(1)';
NODE_NAME     U25 CC7
 '@T6G_MB_LIB.T6G(SCH_1):PAGE20_I159@PURE_QUANTA.GENOA_SP5(CHIPS)':
 'MKB_DATA1': CDS_PINID='MKB_DATA1';
NODE_NAME     J20 102
 '@T6G_MB_LIB.T6G(SCH_1):PAGE95_I22@PURE_QUANTA.SCONN288_DDR506112002KQ(CHIPS)':
 'DQ1_B': CDS_PINID='DQ1_B';
NET_NAME
'M_K_CPU0_SB_DQ<20>'
 '@T6G_MB_LIB.T6G(SCH_1):M_K_CPU0_SB_DQ'<20>:
 C_SIGNAL='@t6g_mb_lib.t6g(sch_1):m_k_cpu0_sb_dq(20)';
NODE_NAME     U25 CV6
 '@T6G_MB_LIB.T6G(SCH_1):PAGE20_I159@PURE_QUANTA.GENOA_SP5(CHIPS)':
 'MKB_DATA20': CDS_PINID='MKB_DATA20';
NODE_NAME     J20 129
 '@T6G_MB_LIB.T6G(SCH_1):PAGE95_I22@PURE_QUANTA.SCONN288_DDR506112002KQ(CHIPS)':
 'DQ20_B': CDS_PINID='DQ20_B';
NET_NAME
'M_K_CPU0_SB_DQ<21>'
 '@T6G_MB_LIB.T6G(SCH_1):M_K_CPU0_SB_DQ'<21>:
 C_SIGNAL='@t6g_mb_lib.t6g(sch_1):m_k_cpu0_sb_dq(21)';
NODE_NAME     U25 CW7
 '@T6G_MB_LIB.T6G(SCH_1):PAGE20_I159@PURE_QUANTA.GENOA_SP5(CHIPS)':
 'MKB_DATA21': CDS_PINID='MKB_DATA21';
NODE_NAME     J20 131
 '@T6G_MB_LIB.T6G(SCH_1):PAGE95_I22@PURE_QUANTA.SCONN288_DDR506112002KQ(CHIPS)':
 'DQ21_B': CDS_PINID='DQ21_B';
NET_NAME
'M_K_CPU0_SB_DQ<22>'
 '@T6G_MB_LIB.T6G(SCH_1):M_K_CPU0_SB_DQ'<22>:
 C_SIGNAL='@t6g_mb_lib.t6g(sch_1):m_k_cpu0_sb_dq(22)';
NODE_NAME     U25 CW5
 '@T6G_MB_LIB.T6G(SCH_1):PAGE20_I159@PURE_QUANTA.GENOA_SP5(CHIPS)':
 'MKB_DATA22': CDS_PINID='MKB_DATA22';
NODE_NAME     J20 274
 '@T6G_MB_LIB.T6G(SCH_1):PAGE95_I22@PURE_QUANTA.SCONN288_DDR506112002KQ(CHIPS)':
 'DQ22_B': CDS_PINID='DQ22_B';
NET_NAME
'M_K_CPU0_SB_DQ<23>'
 '@T6G_MB_LIB.T6G(SCH_1):M_K_CPU0_SB_DQ'<23>:
 C_SIGNAL='@t6g_mb_lib.t6g(sch_1):m_k_cpu0_sb_dq(23)';
NODE_NAME     U25 CY7
 '@T6G_MB_LIB.T6G(SCH_1):PAGE20_I159@PURE_QUANTA.GENOA_SP5(CHIPS)':
 'MKB_DATA23': CDS_PINID='MKB_DATA23';
NODE_NAME     J20 276
 '@T6G_MB_LIB.T6G(SCH_1):PAGE95_I22@PURE_QUANTA.SCONN288_DDR506112002KQ(CHIPS)':
 'DQ23_B': CDS_PINID='DQ23_B';
NET_NAME
'M_K_CPU0_SB_DQ<24>'
 '@T6G_MB_LIB.T6G(SCH_1):M_K_CPU0_SB_DQ'<24>:
 C_SIGNAL='@t6g_mb_lib.t6g(sch_1):m_k_cpu0_sb_dq(24)';
NODE_NAME     U25 CY6
 '@T6G_MB_LIB.T6G(SCH_1):PAGE20_I159@PURE_QUANTA.GENOA_SP5(CHIPS)':
 'MKB_DATA24': CDS_PINID='MKB_DATA24';
NODE_NAME     J20 133
 '@T6G_MB_LIB.T6G(SCH_1):PAGE95_I22@PURE_QUANTA.SCONN288_DDR506112002KQ(CHIPS)':
 'DQ24_B': CDS_PINID='DQ24_B';
NET_NAME
'M_K_CPU0_SB_DQ<25>'
 '@T6G_MB_LIB.T6G(SCH_1):M_K_CPU0_SB_DQ'<25>:
 C_SIGNAL='@t6g_mb_lib.t6g(sch_1):m_k_cpu0_sb_dq(25)';
NODE_NAME     U25 DA7
 '@T6G_MB_LIB.T6G(SCH_1):PAGE20_I159@PURE_QUANTA.GENOA_SP5(CHIPS)':
 'MKB_DATA25': CDS_PINID='MKB_DATA25';
NODE_NAME     J20 135
 '@T6G_MB_LIB.T6G(SCH_1):PAGE95_I22@PURE_QUANTA.SCONN288_DDR506112002KQ(CHIPS)':
 'DQ25_B': CDS_PINID='DQ25_B';
NET_NAME
'M_K_CPU0_SB_DQ<26>'
 '@T6G_MB_LIB.T6G(SCH_1):M_K_CPU0_SB_DQ'<26>:
 C_SIGNAL='@t6g_mb_lib.t6g(sch_1):m_k_cpu0_sb_dq(26)';
NODE_NAME     U25 DA5
 '@T6G_MB_LIB.T6G(SCH_1):PAGE20_I159@PURE_QUANTA.GENOA_SP5(CHIPS)':
 'MKB_DATA26': CDS_PINID='MKB_DATA26';
NODE_NAME     J20 278
 '@T6G_MB_LIB.T6G(SCH_1):PAGE95_I22@PURE_QUANTA.SCONN288_DDR506112002KQ(CHIPS)':
 'DQ26_B': CDS_PINID='DQ26_B';
NET_NAME
'M_K_CPU0_SB_DQ<27>'
 '@T6G_MB_LIB.T6G(SCH_1):M_K_CPU0_SB_DQ'<27>:
 C_SIGNAL='@t6g_mb_lib.t6g(sch_1):m_k_cpu0_sb_dq(27)';
NODE_NAME     U25 DB7
 '@T6G_MB_LIB.T6G(SCH_1):PAGE20_I159@PURE_QUANTA.GENOA_SP5(CHIPS)':
 'MKB_DATA27': CDS_PINID='MKB_DATA27';
NODE_NAME     J20 280
 '@T6G_MB_LIB.T6G(SCH_1):PAGE95_I22@PURE_QUANTA.SCONN288_DDR506112002KQ(CHIPS)':
 'DQ27_B': CDS_PINID='DQ27_B';
NET_NAME
'M_K_CPU0_SB_DQ<28>'
 '@T6G_MB_LIB.T6G(SCH_1):M_K_CPU0_SB_DQ'<28>:
 C_SIGNAL='@t6g_mb_lib.t6g(sch_1):m_k_cpu0_sb_dq(28)';
NODE_NAME     U25 DD6
 '@T6G_MB_LIB.T6G(SCH_1):PAGE20_I159@PURE_QUANTA.GENOA_SP5(CHIPS)':
 'MKB_DATA28': CDS_PINID='MKB_DATA28';
NODE_NAME     J20 140
 '@T6G_MB_LIB.T6G(SCH_1):PAGE95_I22@PURE_QUANTA.SCONN288_DDR506112002KQ(CHIPS)':
 'DQ28_B': CDS_PINID='DQ28_B';
NET_NAME
'M_K_CPU0_SB_DQ<29>'
 '@T6G_MB_LIB.T6G(SCH_1):M_K_CPU0_SB_DQ'<29>:
 C_SIGNAL='@t6g_mb_lib.t6g(sch_1):m_k_cpu0_sb_dq(29)';
NODE_NAME     U25 DE7
 '@T6G_MB_LIB.T6G(SCH_1):PAGE20_I159@PURE_QUANTA.GENOA_SP5(CHIPS)':
 'MKB_DATA29': CDS_PINID='MKB_DATA29';
NODE_NAME     J20 142
 '@T6G_MB_LIB.T6G(SCH_1):PAGE95_I22@PURE_QUANTA.SCONN288_DDR506112002KQ(CHIPS)':
 'DQ29_B': CDS_PINID='DQ29_B';
NET_NAME
'M_K_CPU0_SB_DQ<2>'
 '@T6G_MB_LIB.T6G(SCH_1):M_K_CPU0_SB_DQ'<2>:
 C_SIGNAL='@t6g_mb_lib.t6g(sch_1):m_k_cpu0_sb_dq(2)';
NODE_NAME     U25 CC5
 '@T6G_MB_LIB.T6G(SCH_1):PAGE20_I159@PURE_QUANTA.GENOA_SP5(CHIPS)':
 'MKB_DATA2': CDS_PINID='MKB_DATA2';
NODE_NAME     J20 245
 '@T6G_MB_LIB.T6G(SCH_1):PAGE95_I22@PURE_QUANTA.SCONN288_DDR506112002KQ(CHIPS)':
 'DQ2_B': CDS_PINID='DQ2_B';
NET_NAME
'M_K_CPU0_SB_DQ<30>'
 '@T6G_MB_LIB.T6G(SCH_1):M_K_CPU0_SB_DQ'<30>:
 C_SIGNAL='@t6g_mb_lib.t6g(sch_1):m_k_cpu0_sb_dq(30)';
NODE_NAME     U25 DE5
 '@T6G_MB_LIB.T6G(SCH_1):PAGE20_I159@PURE_QUANTA.GENOA_SP5(CHIPS)':
 'MKB_DATA30': CDS_PINID='MKB_DATA30';
NODE_NAME     J20 285
 '@T6G_MB_LIB.T6G(SCH_1):PAGE95_I22@PURE_QUANTA.SCONN288_DDR506112002KQ(CHIPS)':
 'DQ30_B': CDS_PINID='DQ30_B';
NET_NAME
'M_K_CPU0_SB_DQ<31>'
 '@T6G_MB_LIB.T6G(SCH_1):M_K_CPU0_SB_DQ'<31>:
 C_SIGNAL='@t6g_mb_lib.t6g(sch_1):m_k_cpu0_sb_dq(31)';
NODE_NAME     U25 DF7
 '@T6G_MB_LIB.T6G(SCH_1):PAGE20_I159@PURE_QUANTA.GENOA_SP5(CHIPS)':
 'MKB_DATA31': CDS_PINID='MKB_DATA31';
NODE_NAME     J20 287
 '@T6G_MB_LIB.T6G(SCH_1):PAGE95_I22@PURE_QUANTA.SCONN288_DDR506112002KQ(CHIPS)':
 'DQ31_B': CDS_PINID='DQ31_B';
NET_NAME
'M_K_CPU0_SB_DQ<3>'
 '@T6G_MB_LIB.T6G(SCH_1):M_K_CPU0_SB_DQ'<3>:
 C_SIGNAL='@t6g_mb_lib.t6g(sch_1):m_k_cpu0_sb_dq(3)';
NODE_NAME     U25 CD7
 '@T6G_MB_LIB.T6G(SCH_1):PAGE20_I159@PURE_QUANTA.GENOA_SP5(CHIPS)':
 'MKB_DATA3': CDS_PINID='MKB_DATA3';
NODE_NAME     J20 247
 '@T6G_MB_LIB.T6G(SCH_1):PAGE95_I22@PURE_QUANTA.SCONN288_DDR506112002KQ(CHIPS)':
 'DQ3_B': CDS_PINID='DQ3_B';
NET_NAME
'M_K_CPU0_SB_DQ<4>'
 '@T6G_MB_LIB.T6G(SCH_1):M_K_CPU0_SB_DQ'<4>:
 C_SIGNAL='@t6g_mb_lib.t6g(sch_1):m_k_cpu0_sb_dq(4)';
NODE_NAME     U25 CF6
 '@T6G_MB_LIB.T6G(SCH_1):PAGE20_I159@PURE_QUANTA.GENOA_SP5(CHIPS)':
 'MKB_DATA4': CDS_PINID='MKB_DATA4';
NODE_NAME     J20 107
 '@T6G_MB_LIB.T6G(SCH_1):PAGE95_I22@PURE_QUANTA.SCONN288_DDR506112002KQ(CHIPS)':
 'DQ4_B': CDS_PINID='DQ4_B';
NET_NAME
'M_K_CPU0_SB_DQ<5>'
 '@T6G_MB_LIB.T6G(SCH_1):M_K_CPU0_SB_DQ'<5>:
 C_SIGNAL='@t6g_mb_lib.t6g(sch_1):m_k_cpu0_sb_dq(5)';
NODE_NAME     U25 CG7
 '@T6G_MB_LIB.T6G(SCH_1):PAGE20_I159@PURE_QUANTA.GENOA_SP5(CHIPS)':
 'MKB_DATA5': CDS_PINID='MKB_DATA5';
NODE_NAME     J20 109
 '@T6G_MB_LIB.T6G(SCH_1):PAGE95_I22@PURE_QUANTA.SCONN288_DDR506112002KQ(CHIPS)':
 'DQ5_B': CDS_PINID='DQ5_B';
NET_NAME
'M_K_CPU0_SB_DQ<6>'
 '@T6G_MB_LIB.T6G(SCH_1):M_K_CPU0_SB_DQ'<6>:
 C_SIGNAL='@t6g_mb_lib.t6g(sch_1):m_k_cpu0_sb_dq(6)';
NODE_NAME     U25 CG5
 '@T6G_MB_LIB.T6G(SCH_1):PAGE20_I159@PURE_QUANTA.GENOA_SP5(CHIPS)':
 'MKB_DATA6': CDS_PINID='MKB_DATA6';
NODE_NAME     J20 252
 '@T6G_MB_LIB.T6G(SCH_1):PAGE95_I22@PURE_QUANTA.SCONN288_DDR506112002KQ(CHIPS)':
 'DQ6_B': CDS_PINID='DQ6_B';
NET_NAME
'M_K_CPU0_SB_DQ<7>'
 '@T6G_MB_LIB.T6G(SCH_1):M_K_CPU0_SB_DQ'<7>:
 C_SIGNAL='@t6g_mb_lib.t6g(sch_1):m_k_cpu0_sb_dq(7)';
NODE_NAME     U25 CH7
 '@T6G_MB_LIB.T6G(SCH_1):PAGE20_I159@PURE_QUANTA.GENOA_SP5(CHIPS)':
 'MKB_DATA7': CDS_PINID='MKB_DATA7';
NODE_NAME     J20 254
 '@T6G_MB_LIB.T6G(SCH_1):PAGE95_I22@PURE_QUANTA.SCONN288_DDR506112002KQ(CHIPS)':
 'DQ7_B': CDS_PINID='DQ7_B';
NET_NAME
'M_K_CPU0_SB_DQ<8>'
 '@T6G_MB_LIB.T6G(SCH_1):M_K_CPU0_SB_DQ'<8>:
 C_SIGNAL='@t6g_mb_lib.t6g(sch_1):m_k_cpu0_sb_dq(8)';
NODE_NAME     U25 CH6
 '@T6G_MB_LIB.T6G(SCH_1):PAGE20_I159@PURE_QUANTA.GENOA_SP5(CHIPS)':
 'MKB_DATA8': CDS_PINID='MKB_DATA8';
NODE_NAME     J20 111
 '@T6G_MB_LIB.T6G(SCH_1):PAGE95_I22@PURE_QUANTA.SCONN288_DDR506112002KQ(CHIPS)':
 'DQ8_B': CDS_PINID='DQ8_B';
NET_NAME
'M_K_CPU0_SB_DQ<9>'
 '@T6G_MB_LIB.T6G(SCH_1):M_K_CPU0_SB_DQ'<9>:
 C_SIGNAL='@t6g_mb_lib.t6g(sch_1):m_k_cpu0_sb_dq(9)';
NODE_NAME     U25 CJ7
 '@T6G_MB_LIB.T6G(SCH_1):PAGE20_I159@PURE_QUANTA.GENOA_SP5(CHIPS)':
 'MKB_DATA9': CDS_PINID='MKB_DATA9';
NODE_NAME     J20 113
 '@T6G_MB_LIB.T6G(SCH_1):PAGE95_I22@PURE_QUANTA.SCONN288_DDR506112002KQ(CHIPS)':
 'DQ9_B': CDS_PINID='DQ9_B';
NET_NAME
'M_K_CPU0_SB_DQS_DN<0>'
 '@T6G_MB_LIB.T6G(SCH_1):M_K_CPU0_SB_DQS_DN'<0>:
 C_SIGNAL='@t6g_mb_lib.t6g(sch_1):m_k_cpu0_sb_dqs_dn(0)';
NODE_NAME     U25 CE5
 '@T6G_MB_LIB.T6G(SCH_1):PAGE20_I159@PURE_QUANTA.GENOA_SP5(CHIPS)':
 'MKB_DQS_L0': CDS_PINID='MKB_DQS_L0';
NODE_NAME     J20 105
 '@T6G_MB_LIB.T6G(SCH_1):PAGE95_I236@PURE_QUANTA.SCONN288_DDR506112002KQ(CHIPS)':
 'DQS0_B_C': CDS_PINID='DQS0_B_C';
NET_NAME
'M_K_CPU0_SB_DQS_DN<1>'
 '@T6G_MB_LIB.T6G(SCH_1):M_K_CPU0_SB_DQS_DN'<1>:
 C_SIGNAL='@t6g_mb_lib.t6g(sch_1):m_k_cpu0_sb_dqs_dn(1)';
NODE_NAME     U25 CL5
 '@T6G_MB_LIB.T6G(SCH_1):PAGE20_I159@PURE_QUANTA.GENOA_SP5(CHIPS)':
 'MKB_DQS_L1': CDS_PINID='MKB_DQS_L1';
NODE_NAME     J20 116
 '@T6G_MB_LIB.T6G(SCH_1):PAGE95_I236@PURE_QUANTA.SCONN288_DDR506112002KQ(CHIPS)':
 'DQS1_B_C': CDS_PINID='DQS1_B_C';
NET_NAME
'M_K_CPU0_SB_DQS_DN<2>'
 '@T6G_MB_LIB.T6G(SCH_1):M_K_CPU0_SB_DQS_DN'<2>:
 C_SIGNAL='@t6g_mb_lib.t6g(sch_1):m_k_cpu0_sb_dqs_dn(2)';
NODE_NAME     U25 CU5
 '@T6G_MB_LIB.T6G(SCH_1):PAGE20_I159@PURE_QUANTA.GENOA_SP5(CHIPS)':
 'MKB_DQS_L2': CDS_PINID='MKB_DQS_L2';
NODE_NAME     J20 127
 '@T6G_MB_LIB.T6G(SCH_1):PAGE95_I236@PURE_QUANTA.SCONN288_DDR506112002KQ(CHIPS)':
 'DQS2_B_C': CDS_PINID='DQS2_B_C';
NET_NAME
'M_K_CPU0_SB_DQS_DN<3>'
 '@T6G_MB_LIB.T6G(SCH_1):M_K_CPU0_SB_DQS_DN'<3>:
 C_SIGNAL='@t6g_mb_lib.t6g(sch_1):m_k_cpu0_sb_dqs_dn(3)';
NODE_NAME     U25 DC5
 '@T6G_MB_LIB.T6G(SCH_1):PAGE20_I159@PURE_QUANTA.GENOA_SP5(CHIPS)':
 'MKB_DQS_L3': CDS_PINID='MKB_DQS_L3';
NODE_NAME     J20 138
 '@T6G_MB_LIB.T6G(SCH_1):PAGE95_I236@PURE_QUANTA.SCONN288_DDR506112002KQ(CHIPS)':
 'DQS3_B_C': CDS_PINID='DQS3_B_C';
NET_NAME
'M_K_CPU0_SB_DQS_DN<4>'
 '@T6G_MB_LIB.T6G(SCH_1):M_K_CPU0_SB_DQS_DN'<4>:
 C_SIGNAL='@t6g_mb_lib.t6g(sch_1):m_k_cpu0_sb_dqs_dn(4)';
NODE_NAME     U25 BW7
 '@T6G_MB_LIB.T6G(SCH_1):PAGE20_I159@PURE_QUANTA.GENOA_SP5(CHIPS)':
 'MKB_DQS_L4': CDS_PINID='MKB_DQS_L4';
NODE_NAME     J20 238
 '@T6G_MB_LIB.T6G(SCH_1):PAGE95_I236@PURE_QUANTA.SCONN288_DDR506112002KQ(CHIPS)':
 'DQS4_B_C': CDS_PINID='DQS4_B_C';
NET_NAME
'M_K_CPU0_SB_DQS_DN<5>'
 '@T6G_MB_LIB.T6G(SCH_1):M_K_CPU0_SB_DQS_DN'<5>:
 C_SIGNAL='@t6g_mb_lib.t6g(sch_1):m_k_cpu0_sb_dqs_dn(5)';
NODE_NAME     U25 CE7
 '@T6G_MB_LIB.T6G(SCH_1):PAGE20_I159@PURE_QUANTA.GENOA_SP5(CHIPS)':
 'MKB_DQS_L5': CDS_PINID='MKB_DQS_L5';
NODE_NAME     J20 249
 '@T6G_MB_LIB.T6G(SCH_1):PAGE95_I236@PURE_QUANTA.SCONN288_DDR506112002KQ(CHIPS)':
 'DQS5_B_C||TDQS5_B_C': CDS_PINID='\dqs5_b_c||tdqs5_b_c\';
NET_NAME
'M_K_CPU0_SB_DQS_DN<6>'
 '@T6G_MB_LIB.T6G(SCH_1):M_K_CPU0_SB_DQS_DN'<6>:
 C_SIGNAL='@t6g_mb_lib.t6g(sch_1):m_k_cpu0_sb_dqs_dn(6)';
NODE_NAME     U25 CL7
 '@T6G_MB_LIB.T6G(SCH_1):PAGE20_I159@PURE_QUANTA.GENOA_SP5(CHIPS)':
 'MKB_DQS_L6': CDS_PINID='MKB_DQS_L6';
NODE_NAME     J20 260
 '@T6G_MB_LIB.T6G(SCH_1):PAGE95_I236@PURE_QUANTA.SCONN288_DDR506112002KQ(CHIPS)':
 'DQS6_B_C||TDQS6_B_C': CDS_PINID='\dqs6_b_c||tdqs6_b_c\';
NET_NAME
'M_K_CPU0_SB_DQS_DN<7>'
 '@T6G_MB_LIB.T6G(SCH_1):M_K_CPU0_SB_DQS_DN'<7>:
 C_SIGNAL='@t6g_mb_lib.t6g(sch_1):m_k_cpu0_sb_dqs_dn(7)';
NODE_NAME     U25 CU7
 '@T6G_MB_LIB.T6G(SCH_1):PAGE20_I159@PURE_QUANTA.GENOA_SP5(CHIPS)':
 'MKB_DQS_L7': CDS_PINID='MKB_DQS_L7';
NODE_NAME     J20 271
 '@T6G_MB_LIB.T6G(SCH_1):PAGE95_I236@PURE_QUANTA.SCONN288_DDR506112002KQ(CHIPS)':
 'DQS7_B_C||TDQS7_B_C': CDS_PINID='\dqs7_b_c||tdqs7_b_c\';
NET_NAME
'M_K_CPU0_SB_DQS_DN<8>'
 '@T6G_MB_LIB.T6G(SCH_1):M_K_CPU0_SB_DQS_DN'<8>:
 C_SIGNAL='@t6g_mb_lib.t6g(sch_1):m_k_cpu0_sb_dqs_dn(8)';
NODE_NAME     U25 DC7
 '@T6G_MB_LIB.T6G(SCH_1):PAGE20_I159@PURE_QUANTA.GENOA_SP5(CHIPS)':
 'MKB_DQS_L8': CDS_PINID='MKB_DQS_L8';
NODE_NAME     J20 282
 '@T6G_MB_LIB.T6G(SCH_1):PAGE95_I236@PURE_QUANTA.SCONN288_DDR506112002KQ(CHIPS)':
 'DQS8_B_C||TDQS8_B_C': CDS_PINID='\dqs8_b_c||tdqs8_b_c\';
NET_NAME
'M_K_CPU0_SB_DQS_DN<9>'
 '@T6G_MB_LIB.T6G(SCH_1):M_K_CPU0_SB_DQS_DN'<9>:
 C_SIGNAL='@t6g_mb_lib.t6g(sch_1):m_k_cpu0_sb_dqs_dn(9)';
NODE_NAME     U25 BW5
 '@T6G_MB_LIB.T6G(SCH_1):PAGE20_I159@PURE_QUANTA.GENOA_SP5(CHIPS)':
 'MKB_DQS_L9': CDS_PINID='MKB_DQS_L9';
NODE_NAME     J20 94
 '@T6G_MB_LIB.T6G(SCH_1):PAGE95_I236@PURE_QUANTA.SCONN288_DDR506112002KQ(CHIPS)':
 'DQS9_B_C||TDQS9_B_C': CDS_PINID='\dqs9_b_c||tdqs9_b_c\';
NET_NAME
'M_K_CPU0_SB_DQS_DP<0>'
 '@T6G_MB_LIB.T6G(SCH_1):M_K_CPU0_SB_DQS_DP'<0>:
 C_SIGNAL='@t6g_mb_lib.t6g(sch_1):m_k_cpu0_sb_dqs_dp(0)';
NODE_NAME     U25 CD6
 '@T6G_MB_LIB.T6G(SCH_1):PAGE20_I159@PURE_QUANTA.GENOA_SP5(CHIPS)':
 'MKB_DQS_H0': CDS_PINID='MKB_DQS_H0';
NODE_NAME     J20 104
 '@T6G_MB_LIB.T6G(SCH_1):PAGE95_I236@PURE_QUANTA.SCONN288_DDR506112002KQ(CHIPS)':
 'DQS0_B_T': CDS_PINID='DQS0_B_T';
NET_NAME
'M_K_CPU0_SB_DQS_DP<1>'
 '@T6G_MB_LIB.T6G(SCH_1):M_K_CPU0_SB_DQS_DP'<1>:
 C_SIGNAL='@t6g_mb_lib.t6g(sch_1):m_k_cpu0_sb_dqs_dp(1)';
NODE_NAME     U25 CK6
 '@T6G_MB_LIB.T6G(SCH_1):PAGE20_I159@PURE_QUANTA.GENOA_SP5(CHIPS)':
 'MKB_DQS_H1': CDS_PINID='MKB_DQS_H1';
NODE_NAME     J20 115
 '@T6G_MB_LIB.T6G(SCH_1):PAGE95_I236@PURE_QUANTA.SCONN288_DDR506112002KQ(CHIPS)':
 'DQS1_B_T': CDS_PINID='DQS1_B_T';
NET_NAME
'M_K_CPU0_SB_DQS_DP<2>'
 '@T6G_MB_LIB.T6G(SCH_1):M_K_CPU0_SB_DQS_DP'<2>:
 C_SIGNAL='@t6g_mb_lib.t6g(sch_1):m_k_cpu0_sb_dqs_dp(2)';
NODE_NAME     U25 CT6
 '@T6G_MB_LIB.T6G(SCH_1):PAGE20_I159@PURE_QUANTA.GENOA_SP5(CHIPS)':
 'MKB_DQS_H2': CDS_PINID='MKB_DQS_H2';
NODE_NAME     J20 126
 '@T6G_MB_LIB.T6G(SCH_1):PAGE95_I236@PURE_QUANTA.SCONN288_DDR506112002KQ(CHIPS)':
 'DQS2_B_T': CDS_PINID='DQS2_B_T';
NET_NAME
'M_K_CPU0_SB_DQS_DP<3>'
 '@T6G_MB_LIB.T6G(SCH_1):M_K_CPU0_SB_DQS_DP'<3>:
 C_SIGNAL='@t6g_mb_lib.t6g(sch_1):m_k_cpu0_sb_dqs_dp(3)';
NODE_NAME     U25 DB6
 '@T6G_MB_LIB.T6G(SCH_1):PAGE20_I159@PURE_QUANTA.GENOA_SP5(CHIPS)':
 'MKB_DQS_H3': CDS_PINID='MKB_DQS_H3';
NODE_NAME     J20 137
 '@T6G_MB_LIB.T6G(SCH_1):PAGE95_I236@PURE_QUANTA.SCONN288_DDR506112002KQ(CHIPS)':
 'DQS3_B_T': CDS_PINID='DQS3_B_T';
NET_NAME
'M_K_CPU0_SB_DQS_DP<4>'
 '@T6G_MB_LIB.T6G(SCH_1):M_K_CPU0_SB_DQS_DP'<4>:
 C_SIGNAL='@t6g_mb_lib.t6g(sch_1):m_k_cpu0_sb_dqs_dp(4)';
NODE_NAME     U25 BY7
 '@T6G_MB_LIB.T6G(SCH_1):PAGE20_I159@PURE_QUANTA.GENOA_SP5(CHIPS)':
 'MKB_DQS_H4': CDS_PINID='MKB_DQS_H4';
NODE_NAME     J20 239
 '@T6G_MB_LIB.T6G(SCH_1):PAGE95_I236@PURE_QUANTA.SCONN288_DDR506112002KQ(CHIPS)':
 'DQS4_B_T': CDS_PINID='DQS4_B_T';
NET_NAME
'M_K_CPU0_SB_DQS_DP<5>'
 '@T6G_MB_LIB.T6G(SCH_1):M_K_CPU0_SB_DQS_DP'<5>:
 C_SIGNAL='@t6g_mb_lib.t6g(sch_1):m_k_cpu0_sb_dqs_dp(5)';
NODE_NAME     U25 CF7
 '@T6G_MB_LIB.T6G(SCH_1):PAGE20_I159@PURE_QUANTA.GENOA_SP5(CHIPS)':
 'MKB_DQS_H5': CDS_PINID='MKB_DQS_H5';
NODE_NAME     J20 250
 '@T6G_MB_LIB.T6G(SCH_1):PAGE95_I236@PURE_QUANTA.SCONN288_DDR506112002KQ(CHIPS)':
 'DQS5_B_T||TDQS5_B_T': CDS_PINID='\dqs5_b_t||tdqs5_b_t\';
NET_NAME
'M_K_CPU0_SB_DQS_DP<6>'
 '@T6G_MB_LIB.T6G(SCH_1):M_K_CPU0_SB_DQS_DP'<6>:
 C_SIGNAL='@t6g_mb_lib.t6g(sch_1):m_k_cpu0_sb_dqs_dp(6)';
NODE_NAME     U25 CM7
 '@T6G_MB_LIB.T6G(SCH_1):PAGE20_I159@PURE_QUANTA.GENOA_SP5(CHIPS)':
 'MKB_DQS_H6': CDS_PINID='MKB_DQS_H6';
NODE_NAME     J20 261
 '@T6G_MB_LIB.T6G(SCH_1):PAGE95_I236@PURE_QUANTA.SCONN288_DDR506112002KQ(CHIPS)':
 'DQS6_B_T||TDQS6_B_T': CDS_PINID='\dqs6_b_t||tdqs6_b_t\';
NET_NAME
'M_K_CPU0_SB_DQS_DP<7>'
 '@T6G_MB_LIB.T6G(SCH_1):M_K_CPU0_SB_DQS_DP'<7>:
 C_SIGNAL='@t6g_mb_lib.t6g(sch_1):m_k_cpu0_sb_dqs_dp(7)';
NODE_NAME     U25 CV7
 '@T6G_MB_LIB.T6G(SCH_1):PAGE20_I159@PURE_QUANTA.GENOA_SP5(CHIPS)':
 'MKB_DQS_H7': CDS_PINID='MKB_DQS_H7';
NODE_NAME     J20 272
 '@T6G_MB_LIB.T6G(SCH_1):PAGE95_I236@PURE_QUANTA.SCONN288_DDR506112002KQ(CHIPS)':
 'DQS7_B_T||TDQS7_B_T': CDS_PINID='\dqs7_b_t||tdqs7_b_t\';
NET_NAME
'M_K_CPU0_SB_DQS_DP<8>'
 '@T6G_MB_LIB.T6G(SCH_1):M_K_CPU0_SB_DQS_DP'<8>:
 C_SIGNAL='@t6g_mb_lib.t6g(sch_1):m_k_cpu0_sb_dqs_dp(8)';
NODE_NAME     U25 DD7
 '@T6G_MB_LIB.T6G(SCH_1):PAGE20_I159@PURE_QUANTA.GENOA_SP5(CHIPS)':
 'MKB_DQS_H8': CDS_PINID='MKB_DQS_H8';
NODE_NAME     J20 283
 '@T6G_MB_LIB.T6G(SCH_1):PAGE95_I236@PURE_QUANTA.SCONN288_DDR506112002KQ(CHIPS)':
 'DQS8_B_T||TDQS8_B_T': CDS_PINID='\dqs8_b_t||tdqs8_b_t\';
NET_NAME
'M_K_CPU0_SB_DQS_DP<9>'
 '@T6G_MB_LIB.T6G(SCH_1):M_K_CPU0_SB_DQS_DP'<9>:
 C_SIGNAL='@t6g_mb_lib.t6g(sch_1):m_k_cpu0_sb_dqs_dp(9)';
NODE_NAME     U25 BV6
 '@T6G_MB_LIB.T6G(SCH_1):PAGE20_I159@PURE_QUANTA.GENOA_SP5(CHIPS)':
 'MKB_DQS_H9': CDS_PINID='MKB_DQS_H9';
NODE_NAME     J20 93
 '@T6G_MB_LIB.T6G(SCH_1):PAGE95_I236@PURE_QUANTA.SCONN288_DDR506112002KQ(CHIPS)':
 'DQS9_B_T||TDQS9_B_T||DBI4_B_N': CDS_PINID='\dqs9_b_t||tdqs9_b_t||dbi4_b_n\';
NET_NAME
'M_K_CPU0_SB_PAR'
 '@T6G_MB_LIB.T6G(SCH_1):M_K_CPU0_SB_PAR':
 C_SIGNAL='@t6g_mb_lib.t6g(sch_1):m_k_cpu0_sb_par';
NODE_NAME     U25 BL7
 '@T6G_MB_LIB.T6G(SCH_1):PAGE20_I159@PURE_QUANTA.GENOA_SP5(CHIPS)':
 'MKB_PAR': CDS_PINID='MKB_PAR';
NODE_NAME     J20 227
 '@T6G_MB_LIB.T6G(SCH_1):PAGE95_I22@PURE_QUANTA.SCONN288_DDR506112002KQ(CHIPS)':
 'PAR_B': CDS_PINID='PAR_B';
NET_NAME
'M_K_CPU0_SB_RSP<0>'
 '@T6G_MB_LIB.T6G(SCH_1):M_K_CPU0_SB_RSP'<0>:
 C_SIGNAL='@t6g_mb_lib.t6g(sch_1):m_k_cpu0_sb_rsp(0)';
NODE_NAME     U25 BP6
 '@T6G_MB_LIB.T6G(SCH_1):PAGE20_I159@PURE_QUANTA.GENOA_SP5(CHIPS)':
 'MKB0_RSP_L': CDS_PINID='MKB0_RSP_L';
NODE_NAME     J20 87
 '@T6G_MB_LIB.T6G(SCH_1):PAGE95_I22@PURE_QUANTA.SCONN288_DDR506112002KQ(CHIPS)':
 'LBS||RSP_B_N': CDS_PINID='\lbs||rsp_b_n\';
NET_NAME
'M_K_CPU1_ALERT_N'
 '@T6G_MB_LIB.T6G(SCH_1):M_K_CPU1_ALERT_N':
 C_SIGNAL='@t6g_mb_lib.t6g(sch_1):m_k_cpu1_alert_n';
NODE_NAME     R510 1
 '@T6G_MB_LIB.T6G(SCH_1):PAGE47_I314@PURE_QUANTA.Q_RES(CHIPS)':
 'A': CDS_PINID='A';
NODE_NAME     J99 62
 '@T6G_MB_LIB.T6G(SCH_1):PAGE107_I22@PURE_QUANTA.SCONN288_DDR506112002KQ(CHIPS)':
 'ALERT_N': CDS_PINID='ALERT_N';
NET_NAME
'M_K_CPU1_ALERT_R_N'
 '@T6G_MB_LIB.T6G(SCH_1):M_K_CPU1_ALERT_R_N':
 C_SIGNAL='@t6g_mb_lib.t6g(sch_1):m_k_cpu1_alert_r_n';
NODE_NAME     U26 AT7
 '@T6G_MB_LIB.T6G(SCH_1):PAGE47_I159@PURE_QUANTA.GENOA_SP5(CHIPS)':
 'MK_ALERT_L': CDS_PINID='MK_ALERT_L';
NODE_NAME     R510 2
 '@T6G_MB_LIB.T6G(SCH_1):PAGE47_I314@PURE_QUANTA.Q_RES(CHIPS)':
 'B': CDS_PINID='B';
NET_NAME
'M_K_CPU1_CLK_DN<0>'
 '@T6G_MB_LIB.T6G(SCH_1):M_K_CPU1_CLK_DN'<0>:
 C_SIGNAL='@t6g_mb_lib.t6g(sch_1):m_k_cpu1_clk_dn(0)';
NODE_NAME     U26 BD6
 '@T6G_MB_LIB.T6G(SCH_1):PAGE47_I159@PURE_QUANTA.GENOA_SP5(CHIPS)':
 'MK0_CLK_L': CDS_PINID='MK0_CLK_L';
NODE_NAME     J99 218
 '@T6G_MB_LIB.T6G(SCH_1):PAGE107_I22@PURE_QUANTA.SCONN288_DDR506112002KQ(CHIPS)':
 'CK_C': CDS_PINID='CK_C';
NET_NAME
'M_K_CPU1_CLK_DP<0>'
 '@T6G_MB_LIB.T6G(SCH_1):M_K_CPU1_CLK_DP'<0>:
 C_SIGNAL='@t6g_mb_lib.t6g(sch_1):m_k_cpu1_clk_dp(0)';
NODE_NAME     U26 BC5
 '@T6G_MB_LIB.T6G(SCH_1):PAGE47_I159@PURE_QUANTA.GENOA_SP5(CHIPS)':
 'MK0_CLK_H': CDS_PINID='MK0_CLK_H';
NODE_NAME     J99 217
 '@T6G_MB_LIB.T6G(SCH_1):PAGE107_I22@PURE_QUANTA.SCONN288_DDR506112002KQ(CHIPS)':
 'CK_T': CDS_PINID='CK_T';
NET_NAME
'M_K_CPU1_RESET_N'
 '@T6G_MB_LIB.T6G(SCH_1):M_K_CPU1_RESET_N':
 C_SIGNAL='@t6g_mb_lib.t6g(sch_1):m_k_cpu1_reset_n';
NODE_NAME     U26 AU7
 '@T6G_MB_LIB.T6G(SCH_1):PAGE47_I159@PURE_QUANTA.GENOA_SP5(CHIPS)':
 'MK_RESET_L': CDS_PINID='MK_RESET_L';
NODE_NAME     J99 207
 '@T6G_MB_LIB.T6G(SCH_1):PAGE107_I22@PURE_QUANTA.SCONN288_DDR506112002KQ(CHIPS)':
 'RESET_N': CDS_PINID='RESET_N';
NET_NAME
'M_K_CPU1_SA_CA<0>'
 '@T6G_MB_LIB.T6G(SCH_1):M_K_CPU1_SA_CA'<0>:
 C_SIGNAL='@t6g_mb_lib.t6g(sch_1):m_k_cpu1_sa_ca(0)';
NODE_NAME     U26 AW5
 '@T6G_MB_LIB.T6G(SCH_1):PAGE47_I159@PURE_QUANTA.GENOA_SP5(CHIPS)':
 'MKA_CA0': CDS_PINID='MKA_CA0';
NODE_NAME     J99 66
 '@T6G_MB_LIB.T6G(SCH_1):PAGE107_I22@PURE_QUANTA.SCONN288_DDR506112002KQ(CHIPS)':
 'CA0_A': CDS_PINID='CA0_A';
NET_NAME
'M_K_CPU1_SA_CA<1>'
 '@T6G_MB_LIB.T6G(SCH_1):M_K_CPU1_SA_CA'<1>:
 C_SIGNAL='@t6g_mb_lib.t6g(sch_1):m_k_cpu1_sa_ca(1)';
NODE_NAME     U26 AY6
 '@T6G_MB_LIB.T6G(SCH_1):PAGE47_I159@PURE_QUANTA.GENOA_SP5(CHIPS)':
 'MKA_CA1': CDS_PINID='MKA_CA1';
NODE_NAME     J99 211
 '@T6G_MB_LIB.T6G(SCH_1):PAGE107_I22@PURE_QUANTA.SCONN288_DDR506112002KQ(CHIPS)':
 'CA1_A': CDS_PINID='CA1_A';
NET_NAME
'M_K_CPU1_SA_CA<2>'
 '@T6G_MB_LIB.T6G(SCH_1):M_K_CPU1_SA_CA'<2>:
 C_SIGNAL='@t6g_mb_lib.t6g(sch_1):m_k_cpu1_sa_ca(2)';
NODE_NAME     U26 AY7
 '@T6G_MB_LIB.T6G(SCH_1):PAGE47_I159@PURE_QUANTA.GENOA_SP5(CHIPS)':
 'MKA_CA2': CDS_PINID='MKA_CA2';
NODE_NAME     J99 68
 '@T6G_MB_LIB.T6G(SCH_1):PAGE107_I22@PURE_QUANTA.SCONN288_DDR506112002KQ(CHIPS)':
 'CA2_A': CDS_PINID='CA2_A';
NET_NAME
'M_K_CPU1_SA_CA<3>'
 '@T6G_MB_LIB.T6G(SCH_1):M_K_CPU1_SA_CA'<3>:
 C_SIGNAL='@t6g_mb_lib.t6g(sch_1):m_k_cpu1_sa_ca(3)';
NODE_NAME     U26 BA7
 '@T6G_MB_LIB.T6G(SCH_1):PAGE47_I159@PURE_QUANTA.GENOA_SP5(CHIPS)':
 'MKA_CA3': CDS_PINID='MKA_CA3';
NODE_NAME     J99 213
 '@T6G_MB_LIB.T6G(SCH_1):PAGE107_I22@PURE_QUANTA.SCONN288_DDR506112002KQ(CHIPS)':
 'CA3_A': CDS_PINID='CA3_A';
NET_NAME
'M_K_CPU1_SA_CA<4>'
 '@T6G_MB_LIB.T6G(SCH_1):M_K_CPU1_SA_CA'<4>:
 C_SIGNAL='@t6g_mb_lib.t6g(sch_1):m_k_cpu1_sa_ca(4)';
NODE_NAME     U26 BA5
 '@T6G_MB_LIB.T6G(SCH_1):PAGE47_I159@PURE_QUANTA.GENOA_SP5(CHIPS)':
 'MKA_CA4': CDS_PINID='MKA_CA4';
NODE_NAME     J99 70
 '@T6G_MB_LIB.T6G(SCH_1):PAGE107_I22@PURE_QUANTA.SCONN288_DDR506112002KQ(CHIPS)':
 'CA4_A': CDS_PINID='CA4_A';
NET_NAME
'M_K_CPU1_SA_CA<5>'
 '@T6G_MB_LIB.T6G(SCH_1):M_K_CPU1_SA_CA'<5>:
 C_SIGNAL='@t6g_mb_lib.t6g(sch_1):m_k_cpu1_sa_ca(5)';
NODE_NAME     U26 BB6
 '@T6G_MB_LIB.T6G(SCH_1):PAGE47_I159@PURE_QUANTA.GENOA_SP5(CHIPS)':
 'MKA_CA5': CDS_PINID='MKA_CA5';
NODE_NAME     J99 215
 '@T6G_MB_LIB.T6G(SCH_1):PAGE107_I22@PURE_QUANTA.SCONN288_DDR506112002KQ(CHIPS)':
 'CA5_A': CDS_PINID='CA5_A';
NET_NAME
'M_K_CPU1_SA_CA<6>'
 '@T6G_MB_LIB.T6G(SCH_1):M_K_CPU1_SA_CA'<6>:
 C_SIGNAL='@t6g_mb_lib.t6g(sch_1):m_k_cpu1_sa_ca(6)';
NODE_NAME     U26 BB7
 '@T6G_MB_LIB.T6G(SCH_1):PAGE47_I159@PURE_QUANTA.GENOA_SP5(CHIPS)':
 'MKA_CA6': CDS_PINID='MKA_CA6';
NODE_NAME     J99 72
 '@T6G_MB_LIB.T6G(SCH_1):PAGE107_I22@PURE_QUANTA.SCONN288_DDR506112002KQ(CHIPS)':
 'CA6_A': CDS_PINID='CA6_A';
NET_NAME
'M_K_CPU1_SA_CB<0>'
 '@T6G_MB_LIB.T6G(SCH_1):M_K_CPU1_SA_CB'<0>:
 C_SIGNAL='@t6g_mb_lib.t6g(sch_1):m_k_cpu1_sa_cb(0)';
NODE_NAME     U26 AJ5
 '@T6G_MB_LIB.T6G(SCH_1):PAGE47_I159@PURE_QUANTA.GENOA_SP5(CHIPS)':
 'MKA_CHECK0': CDS_PINID='MKA_CHECK0';
NODE_NAME     J99 51
 '@T6G_MB_LIB.T6G(SCH_1):PAGE107_I22@PURE_QUANTA.SCONN288_DDR506112002KQ(CHIPS)':
 'CB0_A': CDS_PINID='CB0_A';
NET_NAME
'M_K_CPU1_SA_CB<1>'
 '@T6G_MB_LIB.T6G(SCH_1):M_K_CPU1_SA_CB'<1>:
 C_SIGNAL='@t6g_mb_lib.t6g(sch_1):m_k_cpu1_sa_cb(1)';
NODE_NAME     U26 AK7
 '@T6G_MB_LIB.T6G(SCH_1):PAGE47_I159@PURE_QUANTA.GENOA_SP5(CHIPS)':
 'MKA_CHECK1': CDS_PINID='MKA_CHECK1';
NODE_NAME     J99 53
 '@T6G_MB_LIB.T6G(SCH_1):PAGE107_I22@PURE_QUANTA.SCONN288_DDR506112002KQ(CHIPS)':
 'CB1_A': CDS_PINID='CB1_A';
NET_NAME
'M_K_CPU1_SA_CB<2>'
 '@T6G_MB_LIB.T6G(SCH_1):M_K_CPU1_SA_CB'<2>:
 C_SIGNAL='@t6g_mb_lib.t6g(sch_1):m_k_cpu1_sa_cb(2)';
NODE_NAME     U26 AK6
 '@T6G_MB_LIB.T6G(SCH_1):PAGE47_I159@PURE_QUANTA.GENOA_SP5(CHIPS)':
 'MKA_CHECK2': CDS_PINID='MKA_CHECK2';
NODE_NAME     J99 196
 '@T6G_MB_LIB.T6G(SCH_1):PAGE107_I22@PURE_QUANTA.SCONN288_DDR506112002KQ(CHIPS)':
 'CB2_A': CDS_PINID='CB2_A';
NET_NAME
'M_K_CPU1_SA_CB<3>'
 '@T6G_MB_LIB.T6G(SCH_1):M_K_CPU1_SA_CB'<3>:
 C_SIGNAL='@t6g_mb_lib.t6g(sch_1):m_k_cpu1_sa_cb(3)';
NODE_NAME     U26 AL7
 '@T6G_MB_LIB.T6G(SCH_1):PAGE47_I159@PURE_QUANTA.GENOA_SP5(CHIPS)':
 'MKA_CHECK3': CDS_PINID='MKA_CHECK3';
NODE_NAME     J99 198
 '@T6G_MB_LIB.T6G(SCH_1):PAGE107_I22@PURE_QUANTA.SCONN288_DDR506112002KQ(CHIPS)':
 'CB3_A': CDS_PINID='CB3_A';
NET_NAME
'M_K_CPU1_SA_CB<4>'
 '@T6G_MB_LIB.T6G(SCH_1):M_K_CPU1_SA_CB'<4>:
 C_SIGNAL='@t6g_mb_lib.t6g(sch_1):m_k_cpu1_sa_cb(4)';
NODE_NAME     U26 AN5
 '@T6G_MB_LIB.T6G(SCH_1):PAGE47_I159@PURE_QUANTA.GENOA_SP5(CHIPS)':
 'MKA_CHECK4': CDS_PINID='MKA_CHECK4';
NODE_NAME     J99 58
 '@T6G_MB_LIB.T6G(SCH_1):PAGE107_I22@PURE_QUANTA.SCONN288_DDR506112002KQ(CHIPS)':
 'CB4_A': CDS_PINID='CB4_A';
NET_NAME
'M_K_CPU1_SA_CB<5>'
 '@T6G_MB_LIB.T6G(SCH_1):M_K_CPU1_SA_CB'<5>:
 C_SIGNAL='@t6g_mb_lib.t6g(sch_1):m_k_cpu1_sa_cb(5)';
NODE_NAME     U26 AP7
 '@T6G_MB_LIB.T6G(SCH_1):PAGE47_I159@PURE_QUANTA.GENOA_SP5(CHIPS)':
 'MKA_CHECK5': CDS_PINID='MKA_CHECK5';
NODE_NAME     J99 60
 '@T6G_MB_LIB.T6G(SCH_1):PAGE107_I22@PURE_QUANTA.SCONN288_DDR506112002KQ(CHIPS)':
 'CB5_A': CDS_PINID='CB5_A';
NET_NAME
'M_K_CPU1_SA_CB<6>'
 '@T6G_MB_LIB.T6G(SCH_1):M_K_CPU1_SA_CB'<6>:
 C_SIGNAL='@t6g_mb_lib.t6g(sch_1):m_k_cpu1_sa_cb(6)';
NODE_NAME     U26 AP6
 '@T6G_MB_LIB.T6G(SCH_1):PAGE47_I159@PURE_QUANTA.GENOA_SP5(CHIPS)':
 'MKA_CHECK6': CDS_PINID='MKA_CHECK6';
NODE_NAME     J99 203
 '@T6G_MB_LIB.T6G(SCH_1):PAGE107_I22@PURE_QUANTA.SCONN288_DDR506112002KQ(CHIPS)':
 'CB6_A': CDS_PINID='CB6_A';
NET_NAME
'M_K_CPU1_SA_CB<7>'
 '@T6G_MB_LIB.T6G(SCH_1):M_K_CPU1_SA_CB'<7>:
 C_SIGNAL='@t6g_mb_lib.t6g(sch_1):m_k_cpu1_sa_cb(7)';
NODE_NAME     U26 AR7
 '@T6G_MB_LIB.T6G(SCH_1):PAGE47_I159@PURE_QUANTA.GENOA_SP5(CHIPS)':
 'MKA_CHECK7': CDS_PINID='MKA_CHECK7';
NODE_NAME     J99 205
 '@T6G_MB_LIB.T6G(SCH_1):PAGE107_I22@PURE_QUANTA.SCONN288_DDR506112002KQ(CHIPS)':
 'CB7_A': CDS_PINID='CB7_A';
NET_NAME
'M_K_CPU1_SA_CS_N<0>'
 '@T6G_MB_LIB.T6G(SCH_1):M_K_CPU1_SA_CS_N'<0>:
 C_SIGNAL='@t6g_mb_lib.t6g(sch_1):m_k_cpu1_sa_cs_n(0)';
NODE_NAME     U26 AU5
 '@T6G_MB_LIB.T6G(SCH_1):PAGE47_I159@PURE_QUANTA.GENOA_SP5(CHIPS)':
 'MKA0_CS_L0': CDS_PINID='MKA0_CS_L0';
NODE_NAME     J99 64
 '@T6G_MB_LIB.T6G(SCH_1):PAGE107_I22@PURE_QUANTA.SCONN288_DDR506112002KQ(CHIPS)':
 'CS0_A_N': CDS_PINID='CS0_A_N';
NET_NAME
'M_K_CPU1_SA_CS_N<1>'
 '@T6G_MB_LIB.T6G(SCH_1):M_K_CPU1_SA_CS_N'<1>:
 C_SIGNAL='@t6g_mb_lib.t6g(sch_1):m_k_cpu1_sa_cs_n(1)';
NODE_NAME     U26 AV7
 '@T6G_MB_LIB.T6G(SCH_1):PAGE47_I159@PURE_QUANTA.GENOA_SP5(CHIPS)':
 'MKA0_CS_L1': CDS_PINID='MKA0_CS_L1';
NODE_NAME     J99 209
 '@T6G_MB_LIB.T6G(SCH_1):PAGE107_I22@PURE_QUANTA.SCONN288_DDR506112002KQ(CHIPS)':
 'CS1_A_N': CDS_PINID='CS1_A_N';
NET_NAME
'M_K_CPU1_SA_DQ<0>'
 '@T6G_MB_LIB.T6G(SCH_1):M_K_CPU1_SA_DQ'<0>:
 C_SIGNAL='@t6g_mb_lib.t6g(sch_1):m_k_cpu1_sa_dq(0)';
NODE_NAME     U26 E5
 '@T6G_MB_LIB.T6G(SCH_1):PAGE47_I159@PURE_QUANTA.GENOA_SP5(CHIPS)':
 'MKA_DATA0': CDS_PINID='MKA_DATA0';
NODE_NAME     J99 7
 '@T6G_MB_LIB.T6G(SCH_1):PAGE107_I22@PURE_QUANTA.SCONN288_DDR506112002KQ(CHIPS)':
 'DQ0_A': CDS_PINID='DQ0_A';
NET_NAME
'M_K_CPU1_SA_DQ<10>'
 '@T6G_MB_LIB.T6G(SCH_1):M_K_CPU1_SA_DQ'<10>:
 C_SIGNAL='@t6g_mb_lib.t6g(sch_1):m_k_cpu1_sa_dq(10)';
NODE_NAME     U26 M6
 '@T6G_MB_LIB.T6G(SCH_1):PAGE47_I159@PURE_QUANTA.GENOA_SP5(CHIPS)':
 'MKA_DATA10': CDS_PINID='MKA_DATA10';
NODE_NAME     J99 163
 '@T6G_MB_LIB.T6G(SCH_1):PAGE107_I22@PURE_QUANTA.SCONN288_DDR506112002KQ(CHIPS)':
 'DQ10_A': CDS_PINID='DQ10_A';
NET_NAME
'M_K_CPU1_SA_DQ<11>'
 '@T6G_MB_LIB.T6G(SCH_1):M_K_CPU1_SA_DQ'<11>:
 C_SIGNAL='@t6g_mb_lib.t6g(sch_1):m_k_cpu1_sa_dq(11)';
NODE_NAME     U26 N7
 '@T6G_MB_LIB.T6G(SCH_1):PAGE47_I159@PURE_QUANTA.GENOA_SP5(CHIPS)':
 'MKA_DATA11': CDS_PINID='MKA_DATA11';
NODE_NAME     J99 165
 '@T6G_MB_LIB.T6G(SCH_1):PAGE107_I22@PURE_QUANTA.SCONN288_DDR506112002KQ(CHIPS)':
 'DQ11_A': CDS_PINID='DQ11_A';
NET_NAME
'M_K_CPU1_SA_DQ<12>'
 '@T6G_MB_LIB.T6G(SCH_1):M_K_CPU1_SA_DQ'<12>:
 C_SIGNAL='@t6g_mb_lib.t6g(sch_1):m_k_cpu1_sa_dq(12)';
NODE_NAME     U26 R5
 '@T6G_MB_LIB.T6G(SCH_1):PAGE47_I159@PURE_QUANTA.GENOA_SP5(CHIPS)':
 'MKA_DATA12': CDS_PINID='MKA_DATA12';
NODE_NAME     J99 25
 '@T6G_MB_LIB.T6G(SCH_1):PAGE107_I22@PURE_QUANTA.SCONN288_DDR506112002KQ(CHIPS)':
 'DQ12_A': CDS_PINID='DQ12_A';
NET_NAME
'M_K_CPU1_SA_DQ<13>'
 '@T6G_MB_LIB.T6G(SCH_1):M_K_CPU1_SA_DQ'<13>:
 C_SIGNAL='@t6g_mb_lib.t6g(sch_1):m_k_cpu1_sa_dq(13)';
NODE_NAME     U26 T7
 '@T6G_MB_LIB.T6G(SCH_1):PAGE47_I159@PURE_QUANTA.GENOA_SP5(CHIPS)':
 'MKA_DATA13': CDS_PINID='MKA_DATA13';
NODE_NAME     J99 27
 '@T6G_MB_LIB.T6G(SCH_1):PAGE107_I22@PURE_QUANTA.SCONN288_DDR506112002KQ(CHIPS)':
 'DQ13_A': CDS_PINID='DQ13_A';
NET_NAME
'M_K_CPU1_SA_DQ<14>'
 '@T6G_MB_LIB.T6G(SCH_1):M_K_CPU1_SA_DQ'<14>:
 C_SIGNAL='@t6g_mb_lib.t6g(sch_1):m_k_cpu1_sa_dq(14)';
NODE_NAME     U26 T6
 '@T6G_MB_LIB.T6G(SCH_1):PAGE47_I159@PURE_QUANTA.GENOA_SP5(CHIPS)':
 'MKA_DATA14': CDS_PINID='MKA_DATA14';
NODE_NAME     J99 170
 '@T6G_MB_LIB.T6G(SCH_1):PAGE107_I22@PURE_QUANTA.SCONN288_DDR506112002KQ(CHIPS)':
 'DQ14_A': CDS_PINID='DQ14_A';
NET_NAME
'M_K_CPU1_SA_DQ<15>'
 '@T6G_MB_LIB.T6G(SCH_1):M_K_CPU1_SA_DQ'<15>:
 C_SIGNAL='@t6g_mb_lib.t6g(sch_1):m_k_cpu1_sa_dq(15)';
NODE_NAME     U26 U7
 '@T6G_MB_LIB.T6G(SCH_1):PAGE47_I159@PURE_QUANTA.GENOA_SP5(CHIPS)':
 'MKA_DATA15': CDS_PINID='MKA_DATA15';
NODE_NAME     J99 172
 '@T6G_MB_LIB.T6G(SCH_1):PAGE107_I22@PURE_QUANTA.SCONN288_DDR506112002KQ(CHIPS)':
 'DQ15_A': CDS_PINID='DQ15_A';
NET_NAME
'M_K_CPU1_SA_DQ<16>'
 '@T6G_MB_LIB.T6G(SCH_1):M_K_CPU1_SA_DQ'<16>:
 C_SIGNAL='@t6g_mb_lib.t6g(sch_1):m_k_cpu1_sa_dq(16)';
NODE_NAME     U26 U5
 '@T6G_MB_LIB.T6G(SCH_1):PAGE47_I159@PURE_QUANTA.GENOA_SP5(CHIPS)':
 'MKA_DATA16': CDS_PINID='MKA_DATA16';
NODE_NAME     J99 29
 '@T6G_MB_LIB.T6G(SCH_1):PAGE107_I22@PURE_QUANTA.SCONN288_DDR506112002KQ(CHIPS)':
 'DQ16_A': CDS_PINID='DQ16_A';
NET_NAME
'M_K_CPU1_SA_DQ<17>'
 '@T6G_MB_LIB.T6G(SCH_1):M_K_CPU1_SA_DQ'<17>:
 C_SIGNAL='@t6g_mb_lib.t6g(sch_1):m_k_cpu1_sa_dq(17)';
NODE_NAME     U26 V7
 '@T6G_MB_LIB.T6G(SCH_1):PAGE47_I159@PURE_QUANTA.GENOA_SP5(CHIPS)':
 'MKA_DATA17': CDS_PINID='MKA_DATA17';
NODE_NAME     J99 31
 '@T6G_MB_LIB.T6G(SCH_1):PAGE107_I22@PURE_QUANTA.SCONN288_DDR506112002KQ(CHIPS)':
 'DQ17_A': CDS_PINID='DQ17_A';
NET_NAME
'M_K_CPU1_SA_DQ<18>'
 '@T6G_MB_LIB.T6G(SCH_1):M_K_CPU1_SA_DQ'<18>:
 C_SIGNAL='@t6g_mb_lib.t6g(sch_1):m_k_cpu1_sa_dq(18)';
NODE_NAME     U26 V6
 '@T6G_MB_LIB.T6G(SCH_1):PAGE47_I159@PURE_QUANTA.GENOA_SP5(CHIPS)':
 'MKA_DATA18': CDS_PINID='MKA_DATA18';
NODE_NAME     J99 174
 '@T6G_MB_LIB.T6G(SCH_1):PAGE107_I22@PURE_QUANTA.SCONN288_DDR506112002KQ(CHIPS)':
 'DQ18_A': CDS_PINID='DQ18_A';
NET_NAME
'M_K_CPU1_SA_DQ<19>'
 '@T6G_MB_LIB.T6G(SCH_1):M_K_CPU1_SA_DQ'<19>:
 C_SIGNAL='@t6g_mb_lib.t6g(sch_1):m_k_cpu1_sa_dq(19)';
NODE_NAME     U26 W7
 '@T6G_MB_LIB.T6G(SCH_1):PAGE47_I159@PURE_QUANTA.GENOA_SP5(CHIPS)':
 'MKA_DATA19': CDS_PINID='MKA_DATA19';
NODE_NAME     J99 176
 '@T6G_MB_LIB.T6G(SCH_1):PAGE107_I22@PURE_QUANTA.SCONN288_DDR506112002KQ(CHIPS)':
 'DQ19_A': CDS_PINID='DQ19_A';
NET_NAME
'M_K_CPU1_SA_DQ<1>'
 '@T6G_MB_LIB.T6G(SCH_1):M_K_CPU1_SA_DQ'<1>:
 C_SIGNAL='@t6g_mb_lib.t6g(sch_1):m_k_cpu1_sa_dq(1)';
NODE_NAME     U26 F7
 '@T6G_MB_LIB.T6G(SCH_1):PAGE47_I159@PURE_QUANTA.GENOA_SP5(CHIPS)':
 'MKA_DATA1': CDS_PINID='MKA_DATA1';
NODE_NAME     J99 9
 '@T6G_MB_LIB.T6G(SCH_1):PAGE107_I22@PURE_QUANTA.SCONN288_DDR506112002KQ(CHIPS)':
 'DQ1_A': CDS_PINID='DQ1_A';
NET_NAME
'M_K_CPU1_SA_DQ<20>'
 '@T6G_MB_LIB.T6G(SCH_1):M_K_CPU1_SA_DQ'<20>:
 C_SIGNAL='@t6g_mb_lib.t6g(sch_1):m_k_cpu1_sa_dq(20)';
NODE_NAME     U26 AA5
 '@T6G_MB_LIB.T6G(SCH_1):PAGE47_I159@PURE_QUANTA.GENOA_SP5(CHIPS)':
 'MKA_DATA20': CDS_PINID='MKA_DATA20';
NODE_NAME     J99 36
 '@T6G_MB_LIB.T6G(SCH_1):PAGE107_I22@PURE_QUANTA.SCONN288_DDR506112002KQ(CHIPS)':
 'DQ20_A': CDS_PINID='DQ20_A';
NET_NAME
'M_K_CPU1_SA_DQ<21>'
 '@T6G_MB_LIB.T6G(SCH_1):M_K_CPU1_SA_DQ'<21>:
 C_SIGNAL='@t6g_mb_lib.t6g(sch_1):m_k_cpu1_sa_dq(21)';
NODE_NAME     U26 AB7
 '@T6G_MB_LIB.T6G(SCH_1):PAGE47_I159@PURE_QUANTA.GENOA_SP5(CHIPS)':
 'MKA_DATA21': CDS_PINID='MKA_DATA21';
NODE_NAME     J99 38
 '@T6G_MB_LIB.T6G(SCH_1):PAGE107_I22@PURE_QUANTA.SCONN288_DDR506112002KQ(CHIPS)':
 'DQ21_A': CDS_PINID='DQ21_A';
NET_NAME
'M_K_CPU1_SA_DQ<22>'
 '@T6G_MB_LIB.T6G(SCH_1):M_K_CPU1_SA_DQ'<22>:
 C_SIGNAL='@t6g_mb_lib.t6g(sch_1):m_k_cpu1_sa_dq(22)';
NODE_NAME     U26 AB6
 '@T6G_MB_LIB.T6G(SCH_1):PAGE47_I159@PURE_QUANTA.GENOA_SP5(CHIPS)':
 'MKA_DATA22': CDS_PINID='MKA_DATA22';
NODE_NAME     J99 181
 '@T6G_MB_LIB.T6G(SCH_1):PAGE107_I22@PURE_QUANTA.SCONN288_DDR506112002KQ(CHIPS)':
 'DQ22_A': CDS_PINID='DQ22_A';
NET_NAME
'M_K_CPU1_SA_DQ<23>'
 '@T6G_MB_LIB.T6G(SCH_1):M_K_CPU1_SA_DQ'<23>:
 C_SIGNAL='@t6g_mb_lib.t6g(sch_1):m_k_cpu1_sa_dq(23)';
NODE_NAME     U26 AC7
 '@T6G_MB_LIB.T6G(SCH_1):PAGE47_I159@PURE_QUANTA.GENOA_SP5(CHIPS)':
 'MKA_DATA23': CDS_PINID='MKA_DATA23';
NODE_NAME     J99 183
 '@T6G_MB_LIB.T6G(SCH_1):PAGE107_I22@PURE_QUANTA.SCONN288_DDR506112002KQ(CHIPS)':
 'DQ23_A': CDS_PINID='DQ23_A';
NET_NAME
'M_K_CPU1_SA_DQ<24>'
 '@T6G_MB_LIB.T6G(SCH_1):M_K_CPU1_SA_DQ'<24>:
 C_SIGNAL='@t6g_mb_lib.t6g(sch_1):m_k_cpu1_sa_dq(24)';
NODE_NAME     U26 AC5
 '@T6G_MB_LIB.T6G(SCH_1):PAGE47_I159@PURE_QUANTA.GENOA_SP5(CHIPS)':
 'MKA_DATA24': CDS_PINID='MKA_DATA24';
NODE_NAME     J99 40
 '@T6G_MB_LIB.T6G(SCH_1):PAGE107_I22@PURE_QUANTA.SCONN288_DDR506112002KQ(CHIPS)':
 'DQ24_A': CDS_PINID='DQ24_A';
NET_NAME
'M_K_CPU1_SA_DQ<25>'
 '@T6G_MB_LIB.T6G(SCH_1):M_K_CPU1_SA_DQ'<25>:
 C_SIGNAL='@t6g_mb_lib.t6g(sch_1):m_k_cpu1_sa_dq(25)';
NODE_NAME     U26 AD7
 '@T6G_MB_LIB.T6G(SCH_1):PAGE47_I159@PURE_QUANTA.GENOA_SP5(CHIPS)':
 'MKA_DATA25': CDS_PINID='MKA_DATA25';
NODE_NAME     J99 42
 '@T6G_MB_LIB.T6G(SCH_1):PAGE107_I22@PURE_QUANTA.SCONN288_DDR506112002KQ(CHIPS)':
 'DQ25_A': CDS_PINID='DQ25_A';
NET_NAME
'M_K_CPU1_SA_DQ<26>'
 '@T6G_MB_LIB.T6G(SCH_1):M_K_CPU1_SA_DQ'<26>:
 C_SIGNAL='@t6g_mb_lib.t6g(sch_1):m_k_cpu1_sa_dq(26)';
NODE_NAME     U26 AD6
 '@T6G_MB_LIB.T6G(SCH_1):PAGE47_I159@PURE_QUANTA.GENOA_SP5(CHIPS)':
 'MKA_DATA26': CDS_PINID='MKA_DATA26';
NODE_NAME     J99 185
 '@T6G_MB_LIB.T6G(SCH_1):PAGE107_I22@PURE_QUANTA.SCONN288_DDR506112002KQ(CHIPS)':
 'DQ26_A': CDS_PINID='DQ26_A';
NET_NAME
'M_K_CPU1_SA_DQ<27>'
 '@T6G_MB_LIB.T6G(SCH_1):M_K_CPU1_SA_DQ'<27>:
 C_SIGNAL='@t6g_mb_lib.t6g(sch_1):m_k_cpu1_sa_dq(27)';
NODE_NAME     U26 AE7
 '@T6G_MB_LIB.T6G(SCH_1):PAGE47_I159@PURE_QUANTA.GENOA_SP5(CHIPS)':
 'MKA_DATA27': CDS_PINID='MKA_DATA27';
NODE_NAME     J99 187
 '@T6G_MB_LIB.T6G(SCH_1):PAGE107_I22@PURE_QUANTA.SCONN288_DDR506112002KQ(CHIPS)':
 'DQ27_A': CDS_PINID='DQ27_A';
NET_NAME
'M_K_CPU1_SA_DQ<28>'
 '@T6G_MB_LIB.T6G(SCH_1):M_K_CPU1_SA_DQ'<28>:
 C_SIGNAL='@t6g_mb_lib.t6g(sch_1):m_k_cpu1_sa_dq(28)';
NODE_NAME     U26 AG5
 '@T6G_MB_LIB.T6G(SCH_1):PAGE47_I159@PURE_QUANTA.GENOA_SP5(CHIPS)':
 'MKA_DATA28': CDS_PINID='MKA_DATA28';
NODE_NAME     J99 47
 '@T6G_MB_LIB.T6G(SCH_1):PAGE107_I22@PURE_QUANTA.SCONN288_DDR506112002KQ(CHIPS)':
 'DQ28_A': CDS_PINID='DQ28_A';
NET_NAME
'M_K_CPU1_SA_DQ<29>'
 '@T6G_MB_LIB.T6G(SCH_1):M_K_CPU1_SA_DQ'<29>:
 C_SIGNAL='@t6g_mb_lib.t6g(sch_1):m_k_cpu1_sa_dq(29)';
NODE_NAME     U26 AH7
 '@T6G_MB_LIB.T6G(SCH_1):PAGE47_I159@PURE_QUANTA.GENOA_SP5(CHIPS)':
 'MKA_DATA29': CDS_PINID='MKA_DATA29';
NODE_NAME     J99 49
 '@T6G_MB_LIB.T6G(SCH_1):PAGE107_I22@PURE_QUANTA.SCONN288_DDR506112002KQ(CHIPS)':
 'DQ29_A': CDS_PINID='DQ29_A';
NET_NAME
'M_K_CPU1_SA_DQ<2>'
 '@T6G_MB_LIB.T6G(SCH_1):M_K_CPU1_SA_DQ'<2>:
 C_SIGNAL='@t6g_mb_lib.t6g(sch_1):m_k_cpu1_sa_dq(2)';
NODE_NAME     U26 F6
 '@T6G_MB_LIB.T6G(SCH_1):PAGE47_I159@PURE_QUANTA.GENOA_SP5(CHIPS)':
 'MKA_DATA2': CDS_PINID='MKA_DATA2';
NODE_NAME     J99 152
 '@T6G_MB_LIB.T6G(SCH_1):PAGE107_I22@PURE_QUANTA.SCONN288_DDR506112002KQ(CHIPS)':
 'DQ2_A': CDS_PINID='DQ2_A';
NET_NAME
'M_K_CPU1_SA_DQ<30>'
 '@T6G_MB_LIB.T6G(SCH_1):M_K_CPU1_SA_DQ'<30>:
 C_SIGNAL='@t6g_mb_lib.t6g(sch_1):m_k_cpu1_sa_dq(30)';
NODE_NAME     U26 AH6
 '@T6G_MB_LIB.T6G(SCH_1):PAGE47_I159@PURE_QUANTA.GENOA_SP5(CHIPS)':
 'MKA_DATA30': CDS_PINID='MKA_DATA30';
NODE_NAME     J99 192
 '@T6G_MB_LIB.T6G(SCH_1):PAGE107_I22@PURE_QUANTA.SCONN288_DDR506112002KQ(CHIPS)':
 'DQ30_A': CDS_PINID='DQ30_A';
NET_NAME
'M_K_CPU1_SA_DQ<31>'
 '@T6G_MB_LIB.T6G(SCH_1):M_K_CPU1_SA_DQ'<31>:
 C_SIGNAL='@t6g_mb_lib.t6g(sch_1):m_k_cpu1_sa_dq(31)';
NODE_NAME     U26 AJ7
 '@T6G_MB_LIB.T6G(SCH_1):PAGE47_I159@PURE_QUANTA.GENOA_SP5(CHIPS)':
 'MKA_DATA31': CDS_PINID='MKA_DATA31';
NODE_NAME     J99 194
 '@T6G_MB_LIB.T6G(SCH_1):PAGE107_I22@PURE_QUANTA.SCONN288_DDR506112002KQ(CHIPS)':
 'DQ31_A': CDS_PINID='DQ31_A';
NET_NAME
'M_K_CPU1_SA_DQ<3>'
 '@T6G_MB_LIB.T6G(SCH_1):M_K_CPU1_SA_DQ'<3>:
 C_SIGNAL='@t6g_mb_lib.t6g(sch_1):m_k_cpu1_sa_dq(3)';
NODE_NAME     U26 G7
 '@T6G_MB_LIB.T6G(SCH_1):PAGE47_I159@PURE_QUANTA.GENOA_SP5(CHIPS)':
 'MKA_DATA3': CDS_PINID='MKA_DATA3';
NODE_NAME     J99 154
 '@T6G_MB_LIB.T6G(SCH_1):PAGE107_I22@PURE_QUANTA.SCONN288_DDR506112002KQ(CHIPS)':
 'DQ3_A': CDS_PINID='DQ3_A';
NET_NAME
'M_K_CPU1_SA_DQ<4>'
 '@T6G_MB_LIB.T6G(SCH_1):M_K_CPU1_SA_DQ'<4>:
 C_SIGNAL='@t6g_mb_lib.t6g(sch_1):m_k_cpu1_sa_dq(4)';
NODE_NAME     U26 J5
 '@T6G_MB_LIB.T6G(SCH_1):PAGE47_I159@PURE_QUANTA.GENOA_SP5(CHIPS)':
 'MKA_DATA4': CDS_PINID='MKA_DATA4';
NODE_NAME     J99 14
 '@T6G_MB_LIB.T6G(SCH_1):PAGE107_I22@PURE_QUANTA.SCONN288_DDR506112002KQ(CHIPS)':
 'DQ4_A': CDS_PINID='DQ4_A';
NET_NAME
'M_K_CPU1_SA_DQ<5>'
 '@T6G_MB_LIB.T6G(SCH_1):M_K_CPU1_SA_DQ'<5>:
 C_SIGNAL='@t6g_mb_lib.t6g(sch_1):m_k_cpu1_sa_dq(5)';
NODE_NAME     U26 K7
 '@T6G_MB_LIB.T6G(SCH_1):PAGE47_I159@PURE_QUANTA.GENOA_SP5(CHIPS)':
 'MKA_DATA5': CDS_PINID='MKA_DATA5';
NODE_NAME     J99 16
 '@T6G_MB_LIB.T6G(SCH_1):PAGE107_I22@PURE_QUANTA.SCONN288_DDR506112002KQ(CHIPS)':
 'DQ5_A': CDS_PINID='DQ5_A';
NET_NAME
'M_K_CPU1_SA_DQ<6>'
 '@T6G_MB_LIB.T6G(SCH_1):M_K_CPU1_SA_DQ'<6>:
 C_SIGNAL='@t6g_mb_lib.t6g(sch_1):m_k_cpu1_sa_dq(6)';
NODE_NAME     U26 K6
 '@T6G_MB_LIB.T6G(SCH_1):PAGE47_I159@PURE_QUANTA.GENOA_SP5(CHIPS)':
 'MKA_DATA6': CDS_PINID='MKA_DATA6';
NODE_NAME     J99 159
 '@T6G_MB_LIB.T6G(SCH_1):PAGE107_I22@PURE_QUANTA.SCONN288_DDR506112002KQ(CHIPS)':
 'DQ6_A': CDS_PINID='DQ6_A';
NET_NAME
'M_K_CPU1_SA_DQ<7>'
 '@T6G_MB_LIB.T6G(SCH_1):M_K_CPU1_SA_DQ'<7>:
 C_SIGNAL='@t6g_mb_lib.t6g(sch_1):m_k_cpu1_sa_dq(7)';
NODE_NAME     U26 L7
 '@T6G_MB_LIB.T6G(SCH_1):PAGE47_I159@PURE_QUANTA.GENOA_SP5(CHIPS)':
 'MKA_DATA7': CDS_PINID='MKA_DATA7';
NODE_NAME     J99 161
 '@T6G_MB_LIB.T6G(SCH_1):PAGE107_I22@PURE_QUANTA.SCONN288_DDR506112002KQ(CHIPS)':
 'DQ7_A': CDS_PINID='DQ7_A';
NET_NAME
'M_K_CPU1_SA_DQ<8>'
 '@T6G_MB_LIB.T6G(SCH_1):M_K_CPU1_SA_DQ'<8>:
 C_SIGNAL='@t6g_mb_lib.t6g(sch_1):m_k_cpu1_sa_dq(8)';
NODE_NAME     U26 L5
 '@T6G_MB_LIB.T6G(SCH_1):PAGE47_I159@PURE_QUANTA.GENOA_SP5(CHIPS)':
 'MKA_DATA8': CDS_PINID='MKA_DATA8';
NODE_NAME     J99 18
 '@T6G_MB_LIB.T6G(SCH_1):PAGE107_I22@PURE_QUANTA.SCONN288_DDR506112002KQ(CHIPS)':
 'DQ8_A': CDS_PINID='DQ8_A';
NET_NAME
'M_K_CPU1_SA_DQ<9>'
 '@T6G_MB_LIB.T6G(SCH_1):M_K_CPU1_SA_DQ'<9>:
 C_SIGNAL='@t6g_mb_lib.t6g(sch_1):m_k_cpu1_sa_dq(9)';
NODE_NAME     U26 M7
 '@T6G_MB_LIB.T6G(SCH_1):PAGE47_I159@PURE_QUANTA.GENOA_SP5(CHIPS)':
 'MKA_DATA9': CDS_PINID='MKA_DATA9';
NODE_NAME     J99 20
 '@T6G_MB_LIB.T6G(SCH_1):PAGE107_I22@PURE_QUANTA.SCONN288_DDR506112002KQ(CHIPS)':
 'DQ9_A': CDS_PINID='DQ9_A';
NET_NAME
'M_K_CPU1_SA_DQS_DN<0>'
 '@T6G_MB_LIB.T6G(SCH_1):M_K_CPU1_SA_DQS_DN'<0>:
 C_SIGNAL='@t6g_mb_lib.t6g(sch_1):m_k_cpu1_sa_dqs_dn(0)';
NODE_NAME     U26 H6
 '@T6G_MB_LIB.T6G(SCH_1):PAGE47_I159@PURE_QUANTA.GENOA_SP5(CHIPS)':
 'MKA_DQS_L0': CDS_PINID='MKA_DQS_L0';
NODE_NAME     J99 12
 '@T6G_MB_LIB.T6G(SCH_1):PAGE107_I235@PURE_QUANTA.SCONN288_DDR506112002KQ(CHIPS)':
 'DQS0_A_C': CDS_PINID='DQS0_A_C';
NET_NAME
'M_K_CPU1_SA_DQS_DN<1>'
 '@T6G_MB_LIB.T6G(SCH_1):M_K_CPU1_SA_DQS_DN'<1>:
 C_SIGNAL='@t6g_mb_lib.t6g(sch_1):m_k_cpu1_sa_dqs_dn(1)';
NODE_NAME     U26 P6
 '@T6G_MB_LIB.T6G(SCH_1):PAGE47_I159@PURE_QUANTA.GENOA_SP5(CHIPS)':
 'MKA_DQS_L1': CDS_PINID='MKA_DQS_L1';
NODE_NAME     J99 23
 '@T6G_MB_LIB.T6G(SCH_1):PAGE107_I235@PURE_QUANTA.SCONN288_DDR506112002KQ(CHIPS)':
 'DQS1_A_C': CDS_PINID='DQS1_A_C';
NET_NAME
'M_K_CPU1_SA_DQS_DN<2>'
 '@T6G_MB_LIB.T6G(SCH_1):M_K_CPU1_SA_DQS_DN'<2>:
 C_SIGNAL='@t6g_mb_lib.t6g(sch_1):m_k_cpu1_sa_dqs_dn(2)';
NODE_NAME     U26 Y6
 '@T6G_MB_LIB.T6G(SCH_1):PAGE47_I159@PURE_QUANTA.GENOA_SP5(CHIPS)':
 'MKA_DQS_L2': CDS_PINID='MKA_DQS_L2';
NODE_NAME     J99 34
 '@T6G_MB_LIB.T6G(SCH_1):PAGE107_I235@PURE_QUANTA.SCONN288_DDR506112002KQ(CHIPS)':
 'DQS2_A_C': CDS_PINID='DQS2_A_C';
NET_NAME
'M_K_CPU1_SA_DQS_DN<3>'
 '@T6G_MB_LIB.T6G(SCH_1):M_K_CPU1_SA_DQS_DN'<3>:
 C_SIGNAL='@t6g_mb_lib.t6g(sch_1):m_k_cpu1_sa_dqs_dn(3)';
NODE_NAME     U26 AF6
 '@T6G_MB_LIB.T6G(SCH_1):PAGE47_I159@PURE_QUANTA.GENOA_SP5(CHIPS)':
 'MKA_DQS_L3': CDS_PINID='MKA_DQS_L3';
NODE_NAME     J99 45
 '@T6G_MB_LIB.T6G(SCH_1):PAGE107_I235@PURE_QUANTA.SCONN288_DDR506112002KQ(CHIPS)':
 'DQS3_A_C': CDS_PINID='DQS3_A_C';
NET_NAME
'M_K_CPU1_SA_DQS_DN<4>'
 '@T6G_MB_LIB.T6G(SCH_1):M_K_CPU1_SA_DQS_DN'<4>:
 C_SIGNAL='@t6g_mb_lib.t6g(sch_1):m_k_cpu1_sa_dqs_dn(4)';
NODE_NAME     U26 AM6
 '@T6G_MB_LIB.T6G(SCH_1):PAGE47_I159@PURE_QUANTA.GENOA_SP5(CHIPS)':
 'MKA_DQS_L4': CDS_PINID='MKA_DQS_L4';
NODE_NAME     J99 56
 '@T6G_MB_LIB.T6G(SCH_1):PAGE107_I235@PURE_QUANTA.SCONN288_DDR506112002KQ(CHIPS)':
 'DQS4_A_C': CDS_PINID='DQS4_A_C';
NET_NAME
'M_K_CPU1_SA_DQS_DN<5>'
 '@T6G_MB_LIB.T6G(SCH_1):M_K_CPU1_SA_DQS_DN'<5>:
 C_SIGNAL='@t6g_mb_lib.t6g(sch_1):m_k_cpu1_sa_dqs_dn(5)';
NODE_NAME     U26 H7
 '@T6G_MB_LIB.T6G(SCH_1):PAGE47_I159@PURE_QUANTA.GENOA_SP5(CHIPS)':
 'MKA_DQS_L5': CDS_PINID='MKA_DQS_L5';
NODE_NAME     J99 156
 '@T6G_MB_LIB.T6G(SCH_1):PAGE107_I235@PURE_QUANTA.SCONN288_DDR506112002KQ(CHIPS)':
 'DQS5_A_C||TDQS5_A_C||DQS5_A_T||TDQS5_A_T': CDS_PINID='\dqs5_a_c||tdqs5_a_c||dqs5_a_t||tdqs5_a_t\';
NET_NAME
'M_K_CPU1_SA_DQS_DN<6>'
 '@T6G_MB_LIB.T6G(SCH_1):M_K_CPU1_SA_DQS_DN'<6>:
 C_SIGNAL='@t6g_mb_lib.t6g(sch_1):m_k_cpu1_sa_dqs_dn(6)';
NODE_NAME     U26 P7
 '@T6G_MB_LIB.T6G(SCH_1):PAGE47_I159@PURE_QUANTA.GENOA_SP5(CHIPS)':
 'MKA_DQS_L6': CDS_PINID='MKA_DQS_L6';
NODE_NAME     J99 167
 '@T6G_MB_LIB.T6G(SCH_1):PAGE107_I235@PURE_QUANTA.SCONN288_DDR506112002KQ(CHIPS)':
 'DQS6_A_C||TDQS6_A_C||DQS6_A_T||TDQS6_A_T': CDS_PINID='\dqs6_a_c||tdqs6_a_c||dqs6_a_t||tdqs6_a_t\';
NET_NAME
'M_K_CPU1_SA_DQS_DN<7>'
 '@T6G_MB_LIB.T6G(SCH_1):M_K_CPU1_SA_DQS_DN'<7>:
 C_SIGNAL='@t6g_mb_lib.t6g(sch_1):m_k_cpu1_sa_dqs_dn(7)';
NODE_NAME     U26 Y7
 '@T6G_MB_LIB.T6G(SCH_1):PAGE47_I159@PURE_QUANTA.GENOA_SP5(CHIPS)':
 'MKA_DQS_L7': CDS_PINID='MKA_DQS_L7';
NODE_NAME     J99 178
 '@T6G_MB_LIB.T6G(SCH_1):PAGE107_I235@PURE_QUANTA.SCONN288_DDR506112002KQ(CHIPS)':
 'DQS7_A_C||TDQS7_A_C': CDS_PINID='\dqs7_a_c||tdqs7_a_c\';
NET_NAME
'M_K_CPU1_SA_DQS_DN<8>'
 '@T6G_MB_LIB.T6G(SCH_1):M_K_CPU1_SA_DQS_DN'<8>:
 C_SIGNAL='@t6g_mb_lib.t6g(sch_1):m_k_cpu1_sa_dqs_dn(8)';
NODE_NAME     U26 AF7
 '@T6G_MB_LIB.T6G(SCH_1):PAGE47_I159@PURE_QUANTA.GENOA_SP5(CHIPS)':
 'MKA_DQS_L8': CDS_PINID='MKA_DQS_L8';
NODE_NAME     J99 189
 '@T6G_MB_LIB.T6G(SCH_1):PAGE107_I235@PURE_QUANTA.SCONN288_DDR506112002KQ(CHIPS)':
 'DQS8_A_C||TDQS8_A_C': CDS_PINID='\dqs8_a_c||tdqs8_a_c\';
NET_NAME
'M_K_CPU1_SA_DQS_DN<9>'
 '@T6G_MB_LIB.T6G(SCH_1):M_K_CPU1_SA_DQS_DN'<9>:
 C_SIGNAL='@t6g_mb_lib.t6g(sch_1):m_k_cpu1_sa_dqs_dn(9)';
NODE_NAME     U26 AM7
 '@T6G_MB_LIB.T6G(SCH_1):PAGE47_I159@PURE_QUANTA.GENOA_SP5(CHIPS)':
 'MKA_DQS_L9': CDS_PINID='MKA_DQS_L9';
NODE_NAME     J99 200
 '@T6G_MB_LIB.T6G(SCH_1):PAGE107_I235@PURE_QUANTA.SCONN288_DDR506112002KQ(CHIPS)':
 'DQS9_A_C||TDQS9_A_C': CDS_PINID='\dqs9_a_c||tdqs9_a_c\';
NET_NAME
'M_K_CPU1_SA_DQS_DP<0>'
 '@T6G_MB_LIB.T6G(SCH_1):M_K_CPU1_SA_DQS_DP'<0>:
 C_SIGNAL='@t6g_mb_lib.t6g(sch_1):m_k_cpu1_sa_dqs_dp(0)';
NODE_NAME     U26 G5
 '@T6G_MB_LIB.T6G(SCH_1):PAGE47_I159@PURE_QUANTA.GENOA_SP5(CHIPS)':
 'MKA_DQS_H0': CDS_PINID='MKA_DQS_H0';
NODE_NAME     J99 11
 '@T6G_MB_LIB.T6G(SCH_1):PAGE107_I235@PURE_QUANTA.SCONN288_DDR506112002KQ(CHIPS)':
 'DQS0_A_T': CDS_PINID='DQS0_A_T';
NET_NAME
'M_K_CPU1_SA_DQS_DP<1>'
 '@T6G_MB_LIB.T6G(SCH_1):M_K_CPU1_SA_DQS_DP'<1>:
 C_SIGNAL='@t6g_mb_lib.t6g(sch_1):m_k_cpu1_sa_dqs_dp(1)';
NODE_NAME     U26 N5
 '@T6G_MB_LIB.T6G(SCH_1):PAGE47_I159@PURE_QUANTA.GENOA_SP5(CHIPS)':
 'MKA_DQS_H1': CDS_PINID='MKA_DQS_H1';
NODE_NAME     J99 22
 '@T6G_MB_LIB.T6G(SCH_1):PAGE107_I235@PURE_QUANTA.SCONN288_DDR506112002KQ(CHIPS)':
 'DQS1_A_T': CDS_PINID='DQS1_A_T';
NET_NAME
'M_K_CPU1_SA_DQS_DP<2>'
 '@T6G_MB_LIB.T6G(SCH_1):M_K_CPU1_SA_DQS_DP'<2>:
 C_SIGNAL='@t6g_mb_lib.t6g(sch_1):m_k_cpu1_sa_dqs_dp(2)';
NODE_NAME     U26 W5
 '@T6G_MB_LIB.T6G(SCH_1):PAGE47_I159@PURE_QUANTA.GENOA_SP5(CHIPS)':
 'MKA_DQS_H2': CDS_PINID='MKA_DQS_H2';
NODE_NAME     J99 33
 '@T6G_MB_LIB.T6G(SCH_1):PAGE107_I235@PURE_QUANTA.SCONN288_DDR506112002KQ(CHIPS)':
 'DQS2_A_T': CDS_PINID='DQS2_A_T';
NET_NAME
'M_K_CPU1_SA_DQS_DP<3>'
 '@T6G_MB_LIB.T6G(SCH_1):M_K_CPU1_SA_DQS_DP'<3>:
 C_SIGNAL='@t6g_mb_lib.t6g(sch_1):m_k_cpu1_sa_dqs_dp(3)';
NODE_NAME     U26 AE5
 '@T6G_MB_LIB.T6G(SCH_1):PAGE47_I159@PURE_QUANTA.GENOA_SP5(CHIPS)':
 'MKA_DQS_H3': CDS_PINID='MKA_DQS_H3';
NODE_NAME     J99 44
 '@T6G_MB_LIB.T6G(SCH_1):PAGE107_I235@PURE_QUANTA.SCONN288_DDR506112002KQ(CHIPS)':
 'DQS3_A_T': CDS_PINID='DQS3_A_T';
NET_NAME
'M_K_CPU1_SA_DQS_DP<4>'
 '@T6G_MB_LIB.T6G(SCH_1):M_K_CPU1_SA_DQS_DP'<4>:
 C_SIGNAL='@t6g_mb_lib.t6g(sch_1):m_k_cpu1_sa_dqs_dp(4)';
NODE_NAME     U26 AL5
 '@T6G_MB_LIB.T6G(SCH_1):PAGE47_I159@PURE_QUANTA.GENOA_SP5(CHIPS)':
 'MKA_DQS_H4': CDS_PINID='MKA_DQS_H4';
NODE_NAME     J99 55
 '@T6G_MB_LIB.T6G(SCH_1):PAGE107_I235@PURE_QUANTA.SCONN288_DDR506112002KQ(CHIPS)':
 'DQS4_A_T': CDS_PINID='DQS4_A_T';
NET_NAME
'M_K_CPU1_SA_DQS_DP<5>'
 '@T6G_MB_LIB.T6G(SCH_1):M_K_CPU1_SA_DQS_DP'<5>:
 C_SIGNAL='@t6g_mb_lib.t6g(sch_1):m_k_cpu1_sa_dqs_dp(5)';
NODE_NAME     U26 J7
 '@T6G_MB_LIB.T6G(SCH_1):PAGE47_I159@PURE_QUANTA.GENOA_SP5(CHIPS)':
 'MKA_DQS_H5': CDS_PINID='MKA_DQS_H5';
NODE_NAME     J99 157
 '@T6G_MB_LIB.T6G(SCH_1):PAGE107_I235@PURE_QUANTA.SCONN288_DDR506112002KQ(CHIPS)':
 'DQS5_A_T||TDQS5_A_T': CDS_PINID='\dqs5_a_t||tdqs5_a_t\';
NET_NAME
'M_K_CPU1_SA_DQS_DP<6>'
 '@T6G_MB_LIB.T6G(SCH_1):M_K_CPU1_SA_DQS_DP'<6>:
 C_SIGNAL='@t6g_mb_lib.t6g(sch_1):m_k_cpu1_sa_dqs_dp(6)';
NODE_NAME     U26 R7
 '@T6G_MB_LIB.T6G(SCH_1):PAGE47_I159@PURE_QUANTA.GENOA_SP5(CHIPS)':
 'MKA_DQS_H6': CDS_PINID='MKA_DQS_H6';
NODE_NAME     J99 168
 '@T6G_MB_LIB.T6G(SCH_1):PAGE107_I235@PURE_QUANTA.SCONN288_DDR506112002KQ(CHIPS)':
 'DQS6_A_T||TDQS6_A_T': CDS_PINID='\dqs6_a_t||tdqs6_a_t\';
NET_NAME
'M_K_CPU1_SA_DQS_DP<7>'
 '@T6G_MB_LIB.T6G(SCH_1):M_K_CPU1_SA_DQS_DP'<7>:
 C_SIGNAL='@t6g_mb_lib.t6g(sch_1):m_k_cpu1_sa_dqs_dp(7)';
NODE_NAME     U26 AA7
 '@T6G_MB_LIB.T6G(SCH_1):PAGE47_I159@PURE_QUANTA.GENOA_SP5(CHIPS)':
 'MKA_DQS_H7': CDS_PINID='MKA_DQS_H7';
NODE_NAME     J99 179
 '@T6G_MB_LIB.T6G(SCH_1):PAGE107_I235@PURE_QUANTA.SCONN288_DDR506112002KQ(CHIPS)':
 'DQS7_A_T||TDQS7_A_T': CDS_PINID='\dqs7_a_t||tdqs7_a_t\';
NET_NAME
'M_K_CPU1_SA_DQS_DP<8>'
 '@T6G_MB_LIB.T6G(SCH_1):M_K_CPU1_SA_DQS_DP'<8>:
 C_SIGNAL='@t6g_mb_lib.t6g(sch_1):m_k_cpu1_sa_dqs_dp(8)';
NODE_NAME     U26 AG7
 '@T6G_MB_LIB.T6G(SCH_1):PAGE47_I159@PURE_QUANTA.GENOA_SP5(CHIPS)':
 'MKA_DQS_H8': CDS_PINID='MKA_DQS_H8';
NODE_NAME     J99 190
 '@T6G_MB_LIB.T6G(SCH_1):PAGE107_I235@PURE_QUANTA.SCONN288_DDR506112002KQ(CHIPS)':
 'DQS8_A_T||TDQS8_A_T': CDS_PINID='\dqs8_a_t||tdqs8_a_t\';
NET_NAME
'M_K_CPU1_SA_DQS_DP<9>'
 '@T6G_MB_LIB.T6G(SCH_1):M_K_CPU1_SA_DQS_DP'<9>:
 C_SIGNAL='@t6g_mb_lib.t6g(sch_1):m_k_cpu1_sa_dqs_dp(9)';
NODE_NAME     U26 AN7
 '@T6G_MB_LIB.T6G(SCH_1):PAGE47_I159@PURE_QUANTA.GENOA_SP5(CHIPS)':
 'MKA_DQS_H9': CDS_PINID='MKA_DQS_H9';
NODE_NAME     J99 201
 '@T6G_MB_LIB.T6G(SCH_1):PAGE107_I235@PURE_QUANTA.SCONN288_DDR506112002KQ(CHIPS)':
 'DQS9_A_T||TDQS9_A_T': CDS_PINID='\dqs9_a_t||tdqs9_a_t\';
NET_NAME
'M_K_CPU1_SA_PAR'
 '@T6G_MB_LIB.T6G(SCH_1):M_K_CPU1_SA_PAR':
 C_SIGNAL='@t6g_mb_lib.t6g(sch_1):m_k_cpu1_sa_par';
NODE_NAME     U26 BC7
 '@T6G_MB_LIB.T6G(SCH_1):PAGE47_I159@PURE_QUANTA.GENOA_SP5(CHIPS)':
 'MKA_PAR': CDS_PINID='MKA_PAR';
NODE_NAME     J99 74
 '@T6G_MB_LIB.T6G(SCH_1):PAGE107_I22@PURE_QUANTA.SCONN288_DDR506112002KQ(CHIPS)':
 'PAR_A': CDS_PINID='PAR_A';
NET_NAME
'M_K_CPU1_SA_RSP<0>'
 '@T6G_MB_LIB.T6G(SCH_1):M_K_CPU1_SA_RSP'<0>:
 C_SIGNAL='@t6g_mb_lib.t6g(sch_1):m_k_cpu1_sa_rsp(0)';
NODE_NAME     U26 BN7
 '@T6G_MB_LIB.T6G(SCH_1):PAGE47_I159@PURE_QUANTA.GENOA_SP5(CHIPS)':
 'MKA0_RSP_L': CDS_PINID='MKA0_RSP_L';
NODE_NAME     J99 86
 '@T6G_MB_LIB.T6G(SCH_1):PAGE107_I22@PURE_QUANTA.SCONN288_DDR506112002KQ(CHIPS)':
 'LBD||RSP_A_N': CDS_PINID='\lbd||rsp_a_n\';
NET_NAME
'M_K_CPU1_SB_CA<0>'
 '@T6G_MB_LIB.T6G(SCH_1):M_K_CPU1_SB_CA'<0>:
 C_SIGNAL='@t6g_mb_lib.t6g(sch_1):m_k_cpu1_sb_ca(0)';
NODE_NAME     U26 BG7
 '@T6G_MB_LIB.T6G(SCH_1):PAGE47_I159@PURE_QUANTA.GENOA_SP5(CHIPS)':
 'MKB_CA0': CDS_PINID='MKB_CA0';
NODE_NAME     J99 76
 '@T6G_MB_LIB.T6G(SCH_1):PAGE107_I22@PURE_QUANTA.SCONN288_DDR506112002KQ(CHIPS)':
 'CA0_B': CDS_PINID='CA0_B';
NET_NAME
'M_K_CPU1_SB_CA<1>'
 '@T6G_MB_LIB.T6G(SCH_1):M_K_CPU1_SB_CA'<1>:
 C_SIGNAL='@t6g_mb_lib.t6g(sch_1):m_k_cpu1_sb_ca(1)';
NODE_NAME     U26 BH7
 '@T6G_MB_LIB.T6G(SCH_1):PAGE47_I159@PURE_QUANTA.GENOA_SP5(CHIPS)':
 'MKB_CA1': CDS_PINID='MKB_CA1';
NODE_NAME     J99 221
 '@T6G_MB_LIB.T6G(SCH_1):PAGE107_I22@PURE_QUANTA.SCONN288_DDR506112002KQ(CHIPS)':
 'CA1_B': CDS_PINID='CA1_B';
NET_NAME
'M_K_CPU1_SB_CA<2>'
 '@T6G_MB_LIB.T6G(SCH_1):M_K_CPU1_SB_CA'<2>:
 C_SIGNAL='@t6g_mb_lib.t6g(sch_1):m_k_cpu1_sb_ca(2)';
NODE_NAME     U26 BH6
 '@T6G_MB_LIB.T6G(SCH_1):PAGE47_I159@PURE_QUANTA.GENOA_SP5(CHIPS)':
 'MKB_CA2': CDS_PINID='MKB_CA2';
NODE_NAME     J99 78
 '@T6G_MB_LIB.T6G(SCH_1):PAGE107_I22@PURE_QUANTA.SCONN288_DDR506112002KQ(CHIPS)':
 'CA2_B': CDS_PINID='CA2_B';
NET_NAME
'M_K_CPU1_SB_CA<3>'
 '@T6G_MB_LIB.T6G(SCH_1):M_K_CPU1_SB_CA'<3>:
 C_SIGNAL='@t6g_mb_lib.t6g(sch_1):m_k_cpu1_sb_ca(3)';
NODE_NAME     U26 BJ5
 '@T6G_MB_LIB.T6G(SCH_1):PAGE47_I159@PURE_QUANTA.GENOA_SP5(CHIPS)':
 'MKB_CA3': CDS_PINID='MKB_CA3';
NODE_NAME     J99 223
 '@T6G_MB_LIB.T6G(SCH_1):PAGE107_I22@PURE_QUANTA.SCONN288_DDR506112002KQ(CHIPS)':
 'CA3_B': CDS_PINID='CA3_B';
NET_NAME
'M_K_CPU1_SB_CA<4>'
 '@T6G_MB_LIB.T6G(SCH_1):M_K_CPU1_SB_CA'<4>:
 C_SIGNAL='@t6g_mb_lib.t6g(sch_1):m_k_cpu1_sb_ca(4)';
NODE_NAME     U26 BJ7
 '@T6G_MB_LIB.T6G(SCH_1):PAGE47_I159@PURE_QUANTA.GENOA_SP5(CHIPS)':
 'MKB_CA4': CDS_PINID='MKB_CA4';
NODE_NAME     J99 80
 '@T6G_MB_LIB.T6G(SCH_1):PAGE107_I22@PURE_QUANTA.SCONN288_DDR506112002KQ(CHIPS)':
 'CA4_B': CDS_PINID='CA4_B';
NET_NAME
'M_K_CPU1_SB_CA<5>'
 '@T6G_MB_LIB.T6G(SCH_1):M_K_CPU1_SB_CA'<5>:
 C_SIGNAL='@t6g_mb_lib.t6g(sch_1):m_k_cpu1_sb_ca(5)';
NODE_NAME     U26 BK7
 '@T6G_MB_LIB.T6G(SCH_1):PAGE47_I159@PURE_QUANTA.GENOA_SP5(CHIPS)':
 'MKB_CA5': CDS_PINID='MKB_CA5';
NODE_NAME     J99 225
 '@T6G_MB_LIB.T6G(SCH_1):PAGE107_I22@PURE_QUANTA.SCONN288_DDR506112002KQ(CHIPS)':
 'CA5_B': CDS_PINID='CA5_B';
NET_NAME
'M_K_CPU1_SB_CA<6>'
 '@T6G_MB_LIB.T6G(SCH_1):M_K_CPU1_SB_CA'<6>:
 C_SIGNAL='@t6g_mb_lib.t6g(sch_1):m_k_cpu1_sb_ca(6)';
NODE_NAME     U26 BK6
 '@T6G_MB_LIB.T6G(SCH_1):PAGE47_I159@PURE_QUANTA.GENOA_SP5(CHIPS)':
 'MKB_CA6': CDS_PINID='MKB_CA6';
NODE_NAME     J99 82
 '@T6G_MB_LIB.T6G(SCH_1):PAGE107_I22@PURE_QUANTA.SCONN288_DDR506112002KQ(CHIPS)':
 'CA6_B': CDS_PINID='CA6_B';
NET_NAME
'M_K_CPU1_SB_CB<0>'
 '@T6G_MB_LIB.T6G(SCH_1):M_K_CPU1_SB_CB'<0>:
 C_SIGNAL='@t6g_mb_lib.t6g(sch_1):m_k_cpu1_sb_cb(0)';
NODE_NAME     U26 BY6
 '@T6G_MB_LIB.T6G(SCH_1):PAGE47_I159@PURE_QUANTA.GENOA_SP5(CHIPS)':
 'MKB_CHECK0': CDS_PINID='MKB_CHECK0';
NODE_NAME     J99 96
 '@T6G_MB_LIB.T6G(SCH_1):PAGE107_I22@PURE_QUANTA.SCONN288_DDR506112002KQ(CHIPS)':
 'CB0_B': CDS_PINID='CB0_B';
NET_NAME
'M_K_CPU1_SB_CB<1>'
 '@T6G_MB_LIB.T6G(SCH_1):M_K_CPU1_SB_CB'<1>:
 C_SIGNAL='@t6g_mb_lib.t6g(sch_1):m_k_cpu1_sb_cb(1)';
NODE_NAME     U26 CA7
 '@T6G_MB_LIB.T6G(SCH_1):PAGE47_I159@PURE_QUANTA.GENOA_SP5(CHIPS)':
 'MKB_CHECK1': CDS_PINID='MKB_CHECK1';
NODE_NAME     J99 98
 '@T6G_MB_LIB.T6G(SCH_1):PAGE107_I22@PURE_QUANTA.SCONN288_DDR506112002KQ(CHIPS)':
 'CB1_B': CDS_PINID='CB1_B';
NET_NAME
'M_K_CPU1_SB_CB<2>'
 '@T6G_MB_LIB.T6G(SCH_1):M_K_CPU1_SB_CB'<2>:
 C_SIGNAL='@t6g_mb_lib.t6g(sch_1):m_k_cpu1_sb_cb(2)';
NODE_NAME     U26 CA5
 '@T6G_MB_LIB.T6G(SCH_1):PAGE47_I159@PURE_QUANTA.GENOA_SP5(CHIPS)':
 'MKB_CHECK2': CDS_PINID='MKB_CHECK2';
NODE_NAME     J99 241
 '@T6G_MB_LIB.T6G(SCH_1):PAGE107_I22@PURE_QUANTA.SCONN288_DDR506112002KQ(CHIPS)':
 'CB2_B': CDS_PINID='CB2_B';
NET_NAME
'M_K_CPU1_SB_CB<3>'
 '@T6G_MB_LIB.T6G(SCH_1):M_K_CPU1_SB_CB'<3>:
 C_SIGNAL='@t6g_mb_lib.t6g(sch_1):m_k_cpu1_sb_cb(3)';
NODE_NAME     U26 CB7
 '@T6G_MB_LIB.T6G(SCH_1):PAGE47_I159@PURE_QUANTA.GENOA_SP5(CHIPS)':
 'MKB_CHECK3': CDS_PINID='MKB_CHECK3';
NODE_NAME     J99 243
 '@T6G_MB_LIB.T6G(SCH_1):PAGE107_I22@PURE_QUANTA.SCONN288_DDR506112002KQ(CHIPS)':
 'CB3_B': CDS_PINID='CB3_B';
NET_NAME
'M_K_CPU1_SB_CB<4>'
 '@T6G_MB_LIB.T6G(SCH_1):M_K_CPU1_SB_CB'<4>:
 C_SIGNAL='@t6g_mb_lib.t6g(sch_1):m_k_cpu1_sb_cb(4)';
NODE_NAME     U26 BT6
 '@T6G_MB_LIB.T6G(SCH_1):PAGE47_I159@PURE_QUANTA.GENOA_SP5(CHIPS)':
 'MKB_CHECK4': CDS_PINID='MKB_CHECK4';
NODE_NAME     J99 89
 '@T6G_MB_LIB.T6G(SCH_1):PAGE107_I22@PURE_QUANTA.SCONN288_DDR506112002KQ(CHIPS)':
 'CB4_B': CDS_PINID='CB4_B';
NET_NAME
'M_K_CPU1_SB_CB<5>'
 '@T6G_MB_LIB.T6G(SCH_1):M_K_CPU1_SB_CB'<5>:
 C_SIGNAL='@t6g_mb_lib.t6g(sch_1):m_k_cpu1_sb_cb(5)';
NODE_NAME     U26 BU7
 '@T6G_MB_LIB.T6G(SCH_1):PAGE47_I159@PURE_QUANTA.GENOA_SP5(CHIPS)':
 'MKB_CHECK5': CDS_PINID='MKB_CHECK5';
NODE_NAME     J99 91
 '@T6G_MB_LIB.T6G(SCH_1):PAGE107_I22@PURE_QUANTA.SCONN288_DDR506112002KQ(CHIPS)':
 'CB5_B': CDS_PINID='CB5_B';
NET_NAME
'M_K_CPU1_SB_CB<6>'
 '@T6G_MB_LIB.T6G(SCH_1):M_K_CPU1_SB_CB'<6>:
 C_SIGNAL='@t6g_mb_lib.t6g(sch_1):m_k_cpu1_sb_cb(6)';
NODE_NAME     U26 BU5
 '@T6G_MB_LIB.T6G(SCH_1):PAGE47_I159@PURE_QUANTA.GENOA_SP5(CHIPS)':
 'MKB_CHECK6': CDS_PINID='MKB_CHECK6';
NODE_NAME     J99 234
 '@T6G_MB_LIB.T6G(SCH_1):PAGE107_I22@PURE_QUANTA.SCONN288_DDR506112002KQ(CHIPS)':
 'CB6_B': CDS_PINID='CB6_B';
NET_NAME
'M_K_CPU1_SB_CB<7>'
 '@T6G_MB_LIB.T6G(SCH_1):M_K_CPU1_SB_CB'<7>:
 C_SIGNAL='@t6g_mb_lib.t6g(sch_1):m_k_cpu1_sb_cb(7)';
NODE_NAME     U26 BV7
 '@T6G_MB_LIB.T6G(SCH_1):PAGE47_I159@PURE_QUANTA.GENOA_SP5(CHIPS)':
 'MKB_CHECK7': CDS_PINID='MKB_CHECK7';
NODE_NAME     J99 236
 '@T6G_MB_LIB.T6G(SCH_1):PAGE107_I22@PURE_QUANTA.SCONN288_DDR506112002KQ(CHIPS)':
 'CB7_B': CDS_PINID='CB7_B';
NET_NAME
'M_K_CPU1_SB_CS_N<0>'
 '@T6G_MB_LIB.T6G(SCH_1):M_K_CPU1_SB_CS_N'<0>:
 C_SIGNAL='@t6g_mb_lib.t6g(sch_1):m_k_cpu1_sb_cs_n(0)';
NODE_NAME     U26 BM7
 '@T6G_MB_LIB.T6G(SCH_1):PAGE47_I159@PURE_QUANTA.GENOA_SP5(CHIPS)':
 'MKB0_CS_L0': CDS_PINID='MKB0_CS_L0';
NODE_NAME     J99 84
 '@T6G_MB_LIB.T6G(SCH_1):PAGE107_I22@PURE_QUANTA.SCONN288_DDR506112002KQ(CHIPS)':
 'CS0_B_N': CDS_PINID='CS0_B_N';
NET_NAME
'M_K_CPU1_SB_CS_N<1>'
 '@T6G_MB_LIB.T6G(SCH_1):M_K_CPU1_SB_CS_N'<1>:
 C_SIGNAL='@t6g_mb_lib.t6g(sch_1):m_k_cpu1_sb_cs_n(1)';
NODE_NAME     U26 BN5
 '@T6G_MB_LIB.T6G(SCH_1):PAGE47_I159@PURE_QUANTA.GENOA_SP5(CHIPS)':
 'MKB0_CS_L1': CDS_PINID='MKB0_CS_L1';
NODE_NAME     J99 229
 '@T6G_MB_LIB.T6G(SCH_1):PAGE107_I22@PURE_QUANTA.SCONN288_DDR506112002KQ(CHIPS)':
 'CS1_B_N': CDS_PINID='CS1_B_N';
NET_NAME
'M_K_CPU1_SB_DQ<0>'
 '@T6G_MB_LIB.T6G(SCH_1):M_K_CPU1_SB_DQ'<0>:
 C_SIGNAL='@t6g_mb_lib.t6g(sch_1):m_k_cpu1_sb_dq(0)';
NODE_NAME     U26 CB6
 '@T6G_MB_LIB.T6G(SCH_1):PAGE47_I159@PURE_QUANTA.GENOA_SP5(CHIPS)':
 'MKB_DATA0': CDS_PINID='MKB_DATA0';
NODE_NAME     J99 100
 '@T6G_MB_LIB.T6G(SCH_1):PAGE107_I22@PURE_QUANTA.SCONN288_DDR506112002KQ(CHIPS)':
 'DQ0_B': CDS_PINID='DQ0_B';
NET_NAME
'M_K_CPU1_SB_DQ<10>'
 '@T6G_MB_LIB.T6G(SCH_1):M_K_CPU1_SB_DQ'<10>:
 C_SIGNAL='@t6g_mb_lib.t6g(sch_1):m_k_cpu1_sb_dq(10)';
NODE_NAME     U26 CJ5
 '@T6G_MB_LIB.T6G(SCH_1):PAGE47_I159@PURE_QUANTA.GENOA_SP5(CHIPS)':
 'MKB_DATA10': CDS_PINID='MKB_DATA10';
NODE_NAME     J99 256
 '@T6G_MB_LIB.T6G(SCH_1):PAGE107_I22@PURE_QUANTA.SCONN288_DDR506112002KQ(CHIPS)':
 'DQ10_B': CDS_PINID='DQ10_B';
NET_NAME
'M_K_CPU1_SB_DQ<11>'
 '@T6G_MB_LIB.T6G(SCH_1):M_K_CPU1_SB_DQ'<11>:
 C_SIGNAL='@t6g_mb_lib.t6g(sch_1):m_k_cpu1_sb_dq(11)';
NODE_NAME     U26 CK7
 '@T6G_MB_LIB.T6G(SCH_1):PAGE47_I159@PURE_QUANTA.GENOA_SP5(CHIPS)':
 'MKB_DATA11': CDS_PINID='MKB_DATA11';
NODE_NAME     J99 258
 '@T6G_MB_LIB.T6G(SCH_1):PAGE107_I22@PURE_QUANTA.SCONN288_DDR506112002KQ(CHIPS)':
 'DQ11_B': CDS_PINID='DQ11_B';
NET_NAME
'M_K_CPU1_SB_DQ<12>'
 '@T6G_MB_LIB.T6G(SCH_1):M_K_CPU1_SB_DQ'<12>:
 C_SIGNAL='@t6g_mb_lib.t6g(sch_1):m_k_cpu1_sb_dq(12)';
NODE_NAME     U26 CM6
 '@T6G_MB_LIB.T6G(SCH_1):PAGE47_I159@PURE_QUANTA.GENOA_SP5(CHIPS)':
 'MKB_DATA12': CDS_PINID='MKB_DATA12';
NODE_NAME     J99 118
 '@T6G_MB_LIB.T6G(SCH_1):PAGE107_I22@PURE_QUANTA.SCONN288_DDR506112002KQ(CHIPS)':
 'DQ12_B': CDS_PINID='DQ12_B';
NET_NAME
'M_K_CPU1_SB_DQ<13>'
 '@T6G_MB_LIB.T6G(SCH_1):M_K_CPU1_SB_DQ'<13>:
 C_SIGNAL='@t6g_mb_lib.t6g(sch_1):m_k_cpu1_sb_dq(13)';
NODE_NAME     U26 CN7
 '@T6G_MB_LIB.T6G(SCH_1):PAGE47_I159@PURE_QUANTA.GENOA_SP5(CHIPS)':
 'MKB_DATA13': CDS_PINID='MKB_DATA13';
NODE_NAME     J99 120
 '@T6G_MB_LIB.T6G(SCH_1):PAGE107_I22@PURE_QUANTA.SCONN288_DDR506112002KQ(CHIPS)':
 'DQ13_B': CDS_PINID='DQ13_B';
NET_NAME
'M_K_CPU1_SB_DQ<14>'
 '@T6G_MB_LIB.T6G(SCH_1):M_K_CPU1_SB_DQ'<14>:
 C_SIGNAL='@t6g_mb_lib.t6g(sch_1):m_k_cpu1_sb_dq(14)';
NODE_NAME     U26 CN5
 '@T6G_MB_LIB.T6G(SCH_1):PAGE47_I159@PURE_QUANTA.GENOA_SP5(CHIPS)':
 'MKB_DATA14': CDS_PINID='MKB_DATA14';
NODE_NAME     J99 263
 '@T6G_MB_LIB.T6G(SCH_1):PAGE107_I22@PURE_QUANTA.SCONN288_DDR506112002KQ(CHIPS)':
 'DQ14_B': CDS_PINID='DQ14_B';
NET_NAME
'M_K_CPU1_SB_DQ<15>'
 '@T6G_MB_LIB.T6G(SCH_1):M_K_CPU1_SB_DQ'<15>:
 C_SIGNAL='@t6g_mb_lib.t6g(sch_1):m_k_cpu1_sb_dq(15)';
NODE_NAME     U26 CP7
 '@T6G_MB_LIB.T6G(SCH_1):PAGE47_I159@PURE_QUANTA.GENOA_SP5(CHIPS)':
 'MKB_DATA15': CDS_PINID='MKB_DATA15';
NODE_NAME     J99 265
 '@T6G_MB_LIB.T6G(SCH_1):PAGE107_I22@PURE_QUANTA.SCONN288_DDR506112002KQ(CHIPS)':
 'DQ15_B': CDS_PINID='DQ15_B';
NET_NAME
'M_K_CPU1_SB_DQ<16>'
 '@T6G_MB_LIB.T6G(SCH_1):M_K_CPU1_SB_DQ'<16>:
 C_SIGNAL='@t6g_mb_lib.t6g(sch_1):m_k_cpu1_sb_dq(16)';
NODE_NAME     U26 CP6
 '@T6G_MB_LIB.T6G(SCH_1):PAGE47_I159@PURE_QUANTA.GENOA_SP5(CHIPS)':
 'MKB_DATA16': CDS_PINID='MKB_DATA16';
NODE_NAME     J99 122
 '@T6G_MB_LIB.T6G(SCH_1):PAGE107_I22@PURE_QUANTA.SCONN288_DDR506112002KQ(CHIPS)':
 'DQ16_B': CDS_PINID='DQ16_B';
NET_NAME
'M_K_CPU1_SB_DQ<17>'
 '@T6G_MB_LIB.T6G(SCH_1):M_K_CPU1_SB_DQ'<17>:
 C_SIGNAL='@t6g_mb_lib.t6g(sch_1):m_k_cpu1_sb_dq(17)';
NODE_NAME     U26 CR7
 '@T6G_MB_LIB.T6G(SCH_1):PAGE47_I159@PURE_QUANTA.GENOA_SP5(CHIPS)':
 'MKB_DATA17': CDS_PINID='MKB_DATA17';
NODE_NAME     J99 124
 '@T6G_MB_LIB.T6G(SCH_1):PAGE107_I22@PURE_QUANTA.SCONN288_DDR506112002KQ(CHIPS)':
 'DQ17_B': CDS_PINID='DQ17_B';
NET_NAME
'M_K_CPU1_SB_DQ<18>'
 '@T6G_MB_LIB.T6G(SCH_1):M_K_CPU1_SB_DQ'<18>:
 C_SIGNAL='@t6g_mb_lib.t6g(sch_1):m_k_cpu1_sb_dq(18)';
NODE_NAME     U26 CR5
 '@T6G_MB_LIB.T6G(SCH_1):PAGE47_I159@PURE_QUANTA.GENOA_SP5(CHIPS)':
 'MKB_DATA18': CDS_PINID='MKB_DATA18';
NODE_NAME     J99 267
 '@T6G_MB_LIB.T6G(SCH_1):PAGE107_I22@PURE_QUANTA.SCONN288_DDR506112002KQ(CHIPS)':
 'DQ18_B': CDS_PINID='DQ18_B';
NET_NAME
'M_K_CPU1_SB_DQ<19>'
 '@T6G_MB_LIB.T6G(SCH_1):M_K_CPU1_SB_DQ'<19>:
 C_SIGNAL='@t6g_mb_lib.t6g(sch_1):m_k_cpu1_sb_dq(19)';
NODE_NAME     U26 CT7
 '@T6G_MB_LIB.T6G(SCH_1):PAGE47_I159@PURE_QUANTA.GENOA_SP5(CHIPS)':
 'MKB_DATA19': CDS_PINID='MKB_DATA19';
NODE_NAME     J99 269
 '@T6G_MB_LIB.T6G(SCH_1):PAGE107_I22@PURE_QUANTA.SCONN288_DDR506112002KQ(CHIPS)':
 'DQ19_B': CDS_PINID='DQ19_B';
NET_NAME
'M_K_CPU1_SB_DQ<1>'
 '@T6G_MB_LIB.T6G(SCH_1):M_K_CPU1_SB_DQ'<1>:
 C_SIGNAL='@t6g_mb_lib.t6g(sch_1):m_k_cpu1_sb_dq(1)';
NODE_NAME     U26 CC7
 '@T6G_MB_LIB.T6G(SCH_1):PAGE47_I159@PURE_QUANTA.GENOA_SP5(CHIPS)':
 'MKB_DATA1': CDS_PINID='MKB_DATA1';
NODE_NAME     J99 102
 '@T6G_MB_LIB.T6G(SCH_1):PAGE107_I22@PURE_QUANTA.SCONN288_DDR506112002KQ(CHIPS)':
 'DQ1_B': CDS_PINID='DQ1_B';
NET_NAME
'M_K_CPU1_SB_DQ<20>'
 '@T6G_MB_LIB.T6G(SCH_1):M_K_CPU1_SB_DQ'<20>:
 C_SIGNAL='@t6g_mb_lib.t6g(sch_1):m_k_cpu1_sb_dq(20)';
NODE_NAME     U26 CV6
 '@T6G_MB_LIB.T6G(SCH_1):PAGE47_I159@PURE_QUANTA.GENOA_SP5(CHIPS)':
 'MKB_DATA20': CDS_PINID='MKB_DATA20';
NODE_NAME     J99 129
 '@T6G_MB_LIB.T6G(SCH_1):PAGE107_I22@PURE_QUANTA.SCONN288_DDR506112002KQ(CHIPS)':
 'DQ20_B': CDS_PINID='DQ20_B';
NET_NAME
'M_K_CPU1_SB_DQ<21>'
 '@T6G_MB_LIB.T6G(SCH_1):M_K_CPU1_SB_DQ'<21>:
 C_SIGNAL='@t6g_mb_lib.t6g(sch_1):m_k_cpu1_sb_dq(21)';
NODE_NAME     U26 CW7
 '@T6G_MB_LIB.T6G(SCH_1):PAGE47_I159@PURE_QUANTA.GENOA_SP5(CHIPS)':
 'MKB_DATA21': CDS_PINID='MKB_DATA21';
NODE_NAME     J99 131
 '@T6G_MB_LIB.T6G(SCH_1):PAGE107_I22@PURE_QUANTA.SCONN288_DDR506112002KQ(CHIPS)':
 'DQ21_B': CDS_PINID='DQ21_B';
NET_NAME
'M_K_CPU1_SB_DQ<22>'
 '@T6G_MB_LIB.T6G(SCH_1):M_K_CPU1_SB_DQ'<22>:
 C_SIGNAL='@t6g_mb_lib.t6g(sch_1):m_k_cpu1_sb_dq(22)';
NODE_NAME     U26 CW5
 '@T6G_MB_LIB.T6G(SCH_1):PAGE47_I159@PURE_QUANTA.GENOA_SP5(CHIPS)':
 'MKB_DATA22': CDS_PINID='MKB_DATA22';
NODE_NAME     J99 274
 '@T6G_MB_LIB.T6G(SCH_1):PAGE107_I22@PURE_QUANTA.SCONN288_DDR506112002KQ(CHIPS)':
 'DQ22_B': CDS_PINID='DQ22_B';
NET_NAME
'M_K_CPU1_SB_DQ<23>'
 '@T6G_MB_LIB.T6G(SCH_1):M_K_CPU1_SB_DQ'<23>:
 C_SIGNAL='@t6g_mb_lib.t6g(sch_1):m_k_cpu1_sb_dq(23)';
NODE_NAME     U26 CY7
 '@T6G_MB_LIB.T6G(SCH_1):PAGE47_I159@PURE_QUANTA.GENOA_SP5(CHIPS)':
 'MKB_DATA23': CDS_PINID='MKB_DATA23';
NODE_NAME     J99 276
 '@T6G_MB_LIB.T6G(SCH_1):PAGE107_I22@PURE_QUANTA.SCONN288_DDR506112002KQ(CHIPS)':
 'DQ23_B': CDS_PINID='DQ23_B';
NET_NAME
'M_K_CPU1_SB_DQ<24>'
 '@T6G_MB_LIB.T6G(SCH_1):M_K_CPU1_SB_DQ'<24>:
 C_SIGNAL='@t6g_mb_lib.t6g(sch_1):m_k_cpu1_sb_dq(24)';
NODE_NAME     U26 CY6
 '@T6G_MB_LIB.T6G(SCH_1):PAGE47_I159@PURE_QUANTA.GENOA_SP5(CHIPS)':
 'MKB_DATA24': CDS_PINID='MKB_DATA24';
NODE_NAME     J99 133
 '@T6G_MB_LIB.T6G(SCH_1):PAGE107_I22@PURE_QUANTA.SCONN288_DDR506112002KQ(CHIPS)':
 'DQ24_B': CDS_PINID='DQ24_B';
NET_NAME
'M_K_CPU1_SB_DQ<25>'
 '@T6G_MB_LIB.T6G(SCH_1):M_K_CPU1_SB_DQ'<25>:
 C_SIGNAL='@t6g_mb_lib.t6g(sch_1):m_k_cpu1_sb_dq(25)';
NODE_NAME     U26 DA7
 '@T6G_MB_LIB.T6G(SCH_1):PAGE47_I159@PURE_QUANTA.GENOA_SP5(CHIPS)':
 'MKB_DATA25': CDS_PINID='MKB_DATA25';
NODE_NAME     J99 135
 '@T6G_MB_LIB.T6G(SCH_1):PAGE107_I22@PURE_QUANTA.SCONN288_DDR506112002KQ(CHIPS)':
 'DQ25_B': CDS_PINID='DQ25_B';
NET_NAME
'M_K_CPU1_SB_DQ<26>'
 '@T6G_MB_LIB.T6G(SCH_1):M_K_CPU1_SB_DQ'<26>:
 C_SIGNAL='@t6g_mb_lib.t6g(sch_1):m_k_cpu1_sb_dq(26)';
NODE_NAME     U26 DA5
 '@T6G_MB_LIB.T6G(SCH_1):PAGE47_I159@PURE_QUANTA.GENOA_SP5(CHIPS)':
 'MKB_DATA26': CDS_PINID='MKB_DATA26';
NODE_NAME     J99 278
 '@T6G_MB_LIB.T6G(SCH_1):PAGE107_I22@PURE_QUANTA.SCONN288_DDR506112002KQ(CHIPS)':
 'DQ26_B': CDS_PINID='DQ26_B';
NET_NAME
'M_K_CPU1_SB_DQ<27>'
 '@T6G_MB_LIB.T6G(SCH_1):M_K_CPU1_SB_DQ'<27>:
 C_SIGNAL='@t6g_mb_lib.t6g(sch_1):m_k_cpu1_sb_dq(27)';
NODE_NAME     U26 DB7
 '@T6G_MB_LIB.T6G(SCH_1):PAGE47_I159@PURE_QUANTA.GENOA_SP5(CHIPS)':
 'MKB_DATA27': CDS_PINID='MKB_DATA27';
NODE_NAME     J99 280
 '@T6G_MB_LIB.T6G(SCH_1):PAGE107_I22@PURE_QUANTA.SCONN288_DDR506112002KQ(CHIPS)':
 'DQ27_B': CDS_PINID='DQ27_B';
NET_NAME
'M_K_CPU1_SB_DQ<28>'
 '@T6G_MB_LIB.T6G(SCH_1):M_K_CPU1_SB_DQ'<28>:
 C_SIGNAL='@t6g_mb_lib.t6g(sch_1):m_k_cpu1_sb_dq(28)';
NODE_NAME     U26 DD6
 '@T6G_MB_LIB.T6G(SCH_1):PAGE47_I159@PURE_QUANTA.GENOA_SP5(CHIPS)':
 'MKB_DATA28': CDS_PINID='MKB_DATA28';
NODE_NAME     J99 140
 '@T6G_MB_LIB.T6G(SCH_1):PAGE107_I22@PURE_QUANTA.SCONN288_DDR506112002KQ(CHIPS)':
 'DQ28_B': CDS_PINID='DQ28_B';
NET_NAME
'M_K_CPU1_SB_DQ<29>'
 '@T6G_MB_LIB.T6G(SCH_1):M_K_CPU1_SB_DQ'<29>:
 C_SIGNAL='@t6g_mb_lib.t6g(sch_1):m_k_cpu1_sb_dq(29)';
NODE_NAME     U26 DE7
 '@T6G_MB_LIB.T6G(SCH_1):PAGE47_I159@PURE_QUANTA.GENOA_SP5(CHIPS)':
 'MKB_DATA29': CDS_PINID='MKB_DATA29';
NODE_NAME     J99 142
 '@T6G_MB_LIB.T6G(SCH_1):PAGE107_I22@PURE_QUANTA.SCONN288_DDR506112002KQ(CHIPS)':
 'DQ29_B': CDS_PINID='DQ29_B';
NET_NAME
'M_K_CPU1_SB_DQ<2>'
 '@T6G_MB_LIB.T6G(SCH_1):M_K_CPU1_SB_DQ'<2>:
 C_SIGNAL='@t6g_mb_lib.t6g(sch_1):m_k_cpu1_sb_dq(2)';
NODE_NAME     U26 CC5
 '@T6G_MB_LIB.T6G(SCH_1):PAGE47_I159@PURE_QUANTA.GENOA_SP5(CHIPS)':
 'MKB_DATA2': CDS_PINID='MKB_DATA2';
NODE_NAME     J99 245
 '@T6G_MB_LIB.T6G(SCH_1):PAGE107_I22@PURE_QUANTA.SCONN288_DDR506112002KQ(CHIPS)':
 'DQ2_B': CDS_PINID='DQ2_B';
NET_NAME
'M_K_CPU1_SB_DQ<30>'
 '@T6G_MB_LIB.T6G(SCH_1):M_K_CPU1_SB_DQ'<30>:
 C_SIGNAL='@t6g_mb_lib.t6g(sch_1):m_k_cpu1_sb_dq(30)';
NODE_NAME     U26 DE5
 '@T6G_MB_LIB.T6G(SCH_1):PAGE47_I159@PURE_QUANTA.GENOA_SP5(CHIPS)':
 'MKB_DATA30': CDS_PINID='MKB_DATA30';
NODE_NAME     J99 285
 '@T6G_MB_LIB.T6G(SCH_1):PAGE107_I22@PURE_QUANTA.SCONN288_DDR506112002KQ(CHIPS)':
 'DQ30_B': CDS_PINID='DQ30_B';
NET_NAME
'M_K_CPU1_SB_DQ<31>'
 '@T6G_MB_LIB.T6G(SCH_1):M_K_CPU1_SB_DQ'<31>:
 C_SIGNAL='@t6g_mb_lib.t6g(sch_1):m_k_cpu1_sb_dq(31)';
NODE_NAME     U26 DF7
 '@T6G_MB_LIB.T6G(SCH_1):PAGE47_I159@PURE_QUANTA.GENOA_SP5(CHIPS)':
 'MKB_DATA31': CDS_PINID='MKB_DATA31';
NODE_NAME     J99 287
 '@T6G_MB_LIB.T6G(SCH_1):PAGE107_I22@PURE_QUANTA.SCONN288_DDR506112002KQ(CHIPS)':
 'DQ31_B': CDS_PINID='DQ31_B';
NET_NAME
'M_K_CPU1_SB_DQ<3>'
 '@T6G_MB_LIB.T6G(SCH_1):M_K_CPU1_SB_DQ'<3>:
 C_SIGNAL='@t6g_mb_lib.t6g(sch_1):m_k_cpu1_sb_dq(3)';
NODE_NAME     U26 CD7
 '@T6G_MB_LIB.T6G(SCH_1):PAGE47_I159@PURE_QUANTA.GENOA_SP5(CHIPS)':
 'MKB_DATA3': CDS_PINID='MKB_DATA3';
NODE_NAME     J99 247
 '@T6G_MB_LIB.T6G(SCH_1):PAGE107_I22@PURE_QUANTA.SCONN288_DDR506112002KQ(CHIPS)':
 'DQ3_B': CDS_PINID='DQ3_B';
NET_NAME
'M_K_CPU1_SB_DQ<4>'
 '@T6G_MB_LIB.T6G(SCH_1):M_K_CPU1_SB_DQ'<4>:
 C_SIGNAL='@t6g_mb_lib.t6g(sch_1):m_k_cpu1_sb_dq(4)';
NODE_NAME     U26 CF6
 '@T6G_MB_LIB.T6G(SCH_1):PAGE47_I159@PURE_QUANTA.GENOA_SP5(CHIPS)':
 'MKB_DATA4': CDS_PINID='MKB_DATA4';
NODE_NAME     J99 107
 '@T6G_MB_LIB.T6G(SCH_1):PAGE107_I22@PURE_QUANTA.SCONN288_DDR506112002KQ(CHIPS)':
 'DQ4_B': CDS_PINID='DQ4_B';
NET_NAME
'M_K_CPU1_SB_DQ<5>'
 '@T6G_MB_LIB.T6G(SCH_1):M_K_CPU1_SB_DQ'<5>:
 C_SIGNAL='@t6g_mb_lib.t6g(sch_1):m_k_cpu1_sb_dq(5)';
NODE_NAME     U26 CG7
 '@T6G_MB_LIB.T6G(SCH_1):PAGE47_I159@PURE_QUANTA.GENOA_SP5(CHIPS)':
 'MKB_DATA5': CDS_PINID='MKB_DATA5';
NODE_NAME     J99 109
 '@T6G_MB_LIB.T6G(SCH_1):PAGE107_I22@PURE_QUANTA.SCONN288_DDR506112002KQ(CHIPS)':
 'DQ5_B': CDS_PINID='DQ5_B';
NET_NAME
'M_K_CPU1_SB_DQ<6>'
 '@T6G_MB_LIB.T6G(SCH_1):M_K_CPU1_SB_DQ'<6>:
 C_SIGNAL='@t6g_mb_lib.t6g(sch_1):m_k_cpu1_sb_dq(6)';
NODE_NAME     U26 CG5
 '@T6G_MB_LIB.T6G(SCH_1):PAGE47_I159@PURE_QUANTA.GENOA_SP5(CHIPS)':
 'MKB_DATA6': CDS_PINID='MKB_DATA6';
NODE_NAME     J99 252
 '@T6G_MB_LIB.T6G(SCH_1):PAGE107_I22@PURE_QUANTA.SCONN288_DDR506112002KQ(CHIPS)':
 'DQ6_B': CDS_PINID='DQ6_B';
NET_NAME
'M_K_CPU1_SB_DQ<7>'
 '@T6G_MB_LIB.T6G(SCH_1):M_K_CPU1_SB_DQ'<7>:
 C_SIGNAL='@t6g_mb_lib.t6g(sch_1):m_k_cpu1_sb_dq(7)';
NODE_NAME     U26 CH7
 '@T6G_MB_LIB.T6G(SCH_1):PAGE47_I159@PURE_QUANTA.GENOA_SP5(CHIPS)':
 'MKB_DATA7': CDS_PINID='MKB_DATA7';
NODE_NAME     J99 254
 '@T6G_MB_LIB.T6G(SCH_1):PAGE107_I22@PURE_QUANTA.SCONN288_DDR506112002KQ(CHIPS)':
 'DQ7_B': CDS_PINID='DQ7_B';
NET_NAME
'M_K_CPU1_SB_DQ<8>'
 '@T6G_MB_LIB.T6G(SCH_1):M_K_CPU1_SB_DQ'<8>:
 C_SIGNAL='@t6g_mb_lib.t6g(sch_1):m_k_cpu1_sb_dq(8)';
NODE_NAME     U26 CH6
 '@T6G_MB_LIB.T6G(SCH_1):PAGE47_I159@PURE_QUANTA.GENOA_SP5(CHIPS)':
 'MKB_DATA8': CDS_PINID='MKB_DATA8';
NODE_NAME     J99 111
 '@T6G_MB_LIB.T6G(SCH_1):PAGE107_I22@PURE_QUANTA.SCONN288_DDR506112002KQ(CHIPS)':
 'DQ8_B': CDS_PINID='DQ8_B';
NET_NAME
'M_K_CPU1_SB_DQ<9>'
 '@T6G_MB_LIB.T6G(SCH_1):M_K_CPU1_SB_DQ'<9>:
 C_SIGNAL='@t6g_mb_lib.t6g(sch_1):m_k_cpu1_sb_dq(9)';
NODE_NAME     U26 CJ7
 '@T6G_MB_LIB.T6G(SCH_1):PAGE47_I159@PURE_QUANTA.GENOA_SP5(CHIPS)':
 'MKB_DATA9': CDS_PINID='MKB_DATA9';
NODE_NAME     J99 113
 '@T6G_MB_LIB.T6G(SCH_1):PAGE107_I22@PURE_QUANTA.SCONN288_DDR506112002KQ(CHIPS)':
 'DQ9_B': CDS_PINID='DQ9_B';
NET_NAME
'M_K_CPU1_SB_DQS_DN<0>'
 '@T6G_MB_LIB.T6G(SCH_1):M_K_CPU1_SB_DQS_DN'<0>:
 C_SIGNAL='@t6g_mb_lib.t6g(sch_1):m_k_cpu1_sb_dqs_dn(0)';
NODE_NAME     U26 CE5
 '@T6G_MB_LIB.T6G(SCH_1):PAGE47_I159@PURE_QUANTA.GENOA_SP5(CHIPS)':
 'MKB_DQS_L0': CDS_PINID='MKB_DQS_L0';
NODE_NAME     J99 105
 '@T6G_MB_LIB.T6G(SCH_1):PAGE107_I235@PURE_QUANTA.SCONN288_DDR506112002KQ(CHIPS)':
 'DQS0_B_C': CDS_PINID='DQS0_B_C';
NET_NAME
'M_K_CPU1_SB_DQS_DN<1>'
 '@T6G_MB_LIB.T6G(SCH_1):M_K_CPU1_SB_DQS_DN'<1>:
 C_SIGNAL='@t6g_mb_lib.t6g(sch_1):m_k_cpu1_sb_dqs_dn(1)';
NODE_NAME     U26 CL5
 '@T6G_MB_LIB.T6G(SCH_1):PAGE47_I159@PURE_QUANTA.GENOA_SP5(CHIPS)':
 'MKB_DQS_L1': CDS_PINID='MKB_DQS_L1';
NODE_NAME     J99 116
 '@T6G_MB_LIB.T6G(SCH_1):PAGE107_I235@PURE_QUANTA.SCONN288_DDR506112002KQ(CHIPS)':
 'DQS1_B_C': CDS_PINID='DQS1_B_C';
NET_NAME
'M_K_CPU1_SB_DQS_DN<2>'
 '@T6G_MB_LIB.T6G(SCH_1):M_K_CPU1_SB_DQS_DN'<2>:
 C_SIGNAL='@t6g_mb_lib.t6g(sch_1):m_k_cpu1_sb_dqs_dn(2)';
NODE_NAME     U26 CU5
 '@T6G_MB_LIB.T6G(SCH_1):PAGE47_I159@PURE_QUANTA.GENOA_SP5(CHIPS)':
 'MKB_DQS_L2': CDS_PINID='MKB_DQS_L2';
NODE_NAME     J99 127
 '@T6G_MB_LIB.T6G(SCH_1):PAGE107_I235@PURE_QUANTA.SCONN288_DDR506112002KQ(CHIPS)':
 'DQS2_B_C': CDS_PINID='DQS2_B_C';
NET_NAME
'M_K_CPU1_SB_DQS_DN<3>'
 '@T6G_MB_LIB.T6G(SCH_1):M_K_CPU1_SB_DQS_DN'<3>:
 C_SIGNAL='@t6g_mb_lib.t6g(sch_1):m_k_cpu1_sb_dqs_dn(3)';
NODE_NAME     U26 DC5
 '@T6G_MB_LIB.T6G(SCH_1):PAGE47_I159@PURE_QUANTA.GENOA_SP5(CHIPS)':
 'MKB_DQS_L3': CDS_PINID='MKB_DQS_L3';
NODE_NAME     J99 138
 '@T6G_MB_LIB.T6G(SCH_1):PAGE107_I235@PURE_QUANTA.SCONN288_DDR506112002KQ(CHIPS)':
 'DQS3_B_C': CDS_PINID='DQS3_B_C';
NET_NAME
'M_K_CPU1_SB_DQS_DN<4>'
 '@T6G_MB_LIB.T6G(SCH_1):M_K_CPU1_SB_DQS_DN'<4>:
 C_SIGNAL='@t6g_mb_lib.t6g(sch_1):m_k_cpu1_sb_dqs_dn(4)';
NODE_NAME     U26 BW7
 '@T6G_MB_LIB.T6G(SCH_1):PAGE47_I159@PURE_QUANTA.GENOA_SP5(CHIPS)':
 'MKB_DQS_L4': CDS_PINID='MKB_DQS_L4';
NODE_NAME     J99 238
 '@T6G_MB_LIB.T6G(SCH_1):PAGE107_I235@PURE_QUANTA.SCONN288_DDR506112002KQ(CHIPS)':
 'DQS4_B_C': CDS_PINID='DQS4_B_C';
NET_NAME
'M_K_CPU1_SB_DQS_DN<5>'
 '@T6G_MB_LIB.T6G(SCH_1):M_K_CPU1_SB_DQS_DN'<5>:
 C_SIGNAL='@t6g_mb_lib.t6g(sch_1):m_k_cpu1_sb_dqs_dn(5)';
NODE_NAME     U26 CE7
 '@T6G_MB_LIB.T6G(SCH_1):PAGE47_I159@PURE_QUANTA.GENOA_SP5(CHIPS)':
 'MKB_DQS_L5': CDS_PINID='MKB_DQS_L5';
NODE_NAME     J99 249
 '@T6G_MB_LIB.T6G(SCH_1):PAGE107_I235@PURE_QUANTA.SCONN288_DDR506112002KQ(CHIPS)':
 'DQS5_B_C||TDQS5_B_C': CDS_PINID='\dqs5_b_c||tdqs5_b_c\';
NET_NAME
'M_K_CPU1_SB_DQS_DN<6>'
 '@T6G_MB_LIB.T6G(SCH_1):M_K_CPU1_SB_DQS_DN'<6>:
 C_SIGNAL='@t6g_mb_lib.t6g(sch_1):m_k_cpu1_sb_dqs_dn(6)';
NODE_NAME     U26 CL7
 '@T6G_MB_LIB.T6G(SCH_1):PAGE47_I159@PURE_QUANTA.GENOA_SP5(CHIPS)':
 'MKB_DQS_L6': CDS_PINID='MKB_DQS_L6';
NODE_NAME     J99 260
 '@T6G_MB_LIB.T6G(SCH_1):PAGE107_I235@PURE_QUANTA.SCONN288_DDR506112002KQ(CHIPS)':
 'DQS6_B_C||TDQS6_B_C': CDS_PINID='\dqs6_b_c||tdqs6_b_c\';
NET_NAME
'M_K_CPU1_SB_DQS_DN<7>'
 '@T6G_MB_LIB.T6G(SCH_1):M_K_CPU1_SB_DQS_DN'<7>:
 C_SIGNAL='@t6g_mb_lib.t6g(sch_1):m_k_cpu1_sb_dqs_dn(7)';
NODE_NAME     U26 CU7
 '@T6G_MB_LIB.T6G(SCH_1):PAGE47_I159@PURE_QUANTA.GENOA_SP5(CHIPS)':
 'MKB_DQS_L7': CDS_PINID='MKB_DQS_L7';
NODE_NAME     J99 271
 '@T6G_MB_LIB.T6G(SCH_1):PAGE107_I235@PURE_QUANTA.SCONN288_DDR506112002KQ(CHIPS)':
 'DQS7_B_C||TDQS7_B_C': CDS_PINID='\dqs7_b_c||tdqs7_b_c\';
NET_NAME
'M_K_CPU1_SB_DQS_DN<8>'
 '@T6G_MB_LIB.T6G(SCH_1):M_K_CPU1_SB_DQS_DN'<8>:
 C_SIGNAL='@t6g_mb_lib.t6g(sch_1):m_k_cpu1_sb_dqs_dn(8)';
NODE_NAME     U26 DC7
 '@T6G_MB_LIB.T6G(SCH_1):PAGE47_I159@PURE_QUANTA.GENOA_SP5(CHIPS)':
 'MKB_DQS_L8': CDS_PINID='MKB_DQS_L8';
NODE_NAME     J99 282
 '@T6G_MB_LIB.T6G(SCH_1):PAGE107_I235@PURE_QUANTA.SCONN288_DDR506112002KQ(CHIPS)':
 'DQS8_B_C||TDQS8_B_C': CDS_PINID='\dqs8_b_c||tdqs8_b_c\';
NET_NAME
'M_K_CPU1_SB_DQS_DN<9>'
 '@T6G_MB_LIB.T6G(SCH_1):M_K_CPU1_SB_DQS_DN'<9>:
 C_SIGNAL='@t6g_mb_lib.t6g(sch_1):m_k_cpu1_sb_dqs_dn(9)';
NODE_NAME     U26 BW5
 '@T6G_MB_LIB.T6G(SCH_1):PAGE47_I159@PURE_QUANTA.GENOA_SP5(CHIPS)':
 'MKB_DQS_L9': CDS_PINID='MKB_DQS_L9';
NODE_NAME     J99 94
 '@T6G_MB_LIB.T6G(SCH_1):PAGE107_I235@PURE_QUANTA.SCONN288_DDR506112002KQ(CHIPS)':
 'DQS9_B_C||TDQS9_B_C': CDS_PINID='\dqs9_b_c||tdqs9_b_c\';
NET_NAME
'M_K_CPU1_SB_DQS_DP<0>'
 '@T6G_MB_LIB.T6G(SCH_1):M_K_CPU1_SB_DQS_DP'<0>:
 C_SIGNAL='@t6g_mb_lib.t6g(sch_1):m_k_cpu1_sb_dqs_dp(0)';
NODE_NAME     U26 CD6
 '@T6G_MB_LIB.T6G(SCH_1):PAGE47_I159@PURE_QUANTA.GENOA_SP5(CHIPS)':
 'MKB_DQS_H0': CDS_PINID='MKB_DQS_H0';
NODE_NAME     J99 104
 '@T6G_MB_LIB.T6G(SCH_1):PAGE107_I235@PURE_QUANTA.SCONN288_DDR506112002KQ(CHIPS)':
 'DQS0_B_T': CDS_PINID='DQS0_B_T';
NET_NAME
'M_K_CPU1_SB_DQS_DP<1>'
 '@T6G_MB_LIB.T6G(SCH_1):M_K_CPU1_SB_DQS_DP'<1>:
 C_SIGNAL='@t6g_mb_lib.t6g(sch_1):m_k_cpu1_sb_dqs_dp(1)';
NODE_NAME     U26 CK6
 '@T6G_MB_LIB.T6G(SCH_1):PAGE47_I159@PURE_QUANTA.GENOA_SP5(CHIPS)':
 'MKB_DQS_H1': CDS_PINID='MKB_DQS_H1';
NODE_NAME     J99 115
 '@T6G_MB_LIB.T6G(SCH_1):PAGE107_I235@PURE_QUANTA.SCONN288_DDR506112002KQ(CHIPS)':
 'DQS1_B_T': CDS_PINID='DQS1_B_T';
NET_NAME
'M_K_CPU1_SB_DQS_DP<2>'
 '@T6G_MB_LIB.T6G(SCH_1):M_K_CPU1_SB_DQS_DP'<2>:
 C_SIGNAL='@t6g_mb_lib.t6g(sch_1):m_k_cpu1_sb_dqs_dp(2)';
NODE_NAME     U26 CT6
 '@T6G_MB_LIB.T6G(SCH_1):PAGE47_I159@PURE_QUANTA.GENOA_SP5(CHIPS)':
 'MKB_DQS_H2': CDS_PINID='MKB_DQS_H2';
NODE_NAME     J99 126
 '@T6G_MB_LIB.T6G(SCH_1):PAGE107_I235@PURE_QUANTA.SCONN288_DDR506112002KQ(CHIPS)':
 'DQS2_B_T': CDS_PINID='DQS2_B_T';
NET_NAME
'M_K_CPU1_SB_DQS_DP<3>'
 '@T6G_MB_LIB.T6G(SCH_1):M_K_CPU1_SB_DQS_DP'<3>:
 C_SIGNAL='@t6g_mb_lib.t6g(sch_1):m_k_cpu1_sb_dqs_dp(3)';
NODE_NAME     U26 DB6
 '@T6G_MB_LIB.T6G(SCH_1):PAGE47_I159@PURE_QUANTA.GENOA_SP5(CHIPS)':
 'MKB_DQS_H3': CDS_PINID='MKB_DQS_H3';
NODE_NAME     J99 137
 '@T6G_MB_LIB.T6G(SCH_1):PAGE107_I235@PURE_QUANTA.SCONN288_DDR506112002KQ(CHIPS)':
 'DQS3_B_T': CDS_PINID='DQS3_B_T';
NET_NAME
'M_K_CPU1_SB_DQS_DP<4>'
 '@T6G_MB_LIB.T6G(SCH_1):M_K_CPU1_SB_DQS_DP'<4>:
 C_SIGNAL='@t6g_mb_lib.t6g(sch_1):m_k_cpu1_sb_dqs_dp(4)';
NODE_NAME     U26 BY7
 '@T6G_MB_LIB.T6G(SCH_1):PAGE47_I159@PURE_QUANTA.GENOA_SP5(CHIPS)':
 'MKB_DQS_H4': CDS_PINID='MKB_DQS_H4';
NODE_NAME     J99 239
 '@T6G_MB_LIB.T6G(SCH_1):PAGE107_I235@PURE_QUANTA.SCONN288_DDR506112002KQ(CHIPS)':
 'DQS4_B_T': CDS_PINID='DQS4_B_T';
NET_NAME
'M_K_CPU1_SB_DQS_DP<5>'
 '@T6G_MB_LIB.T6G(SCH_1):M_K_CPU1_SB_DQS_DP'<5>:
 C_SIGNAL='@t6g_mb_lib.t6g(sch_1):m_k_cpu1_sb_dqs_dp(5)';
NODE_NAME     U26 CF7
 '@T6G_MB_LIB.T6G(SCH_1):PAGE47_I159@PURE_QUANTA.GENOA_SP5(CHIPS)':
 'MKB_DQS_H5': CDS_PINID='MKB_DQS_H5';
NODE_NAME     J99 250
 '@T6G_MB_LIB.T6G(SCH_1):PAGE107_I235@PURE_QUANTA.SCONN288_DDR506112002KQ(CHIPS)':
 'DQS5_B_T||TDQS5_B_T': CDS_PINID='\dqs5_b_t||tdqs5_b_t\';
NET_NAME
'M_K_CPU1_SB_DQS_DP<6>'
 '@T6G_MB_LIB.T6G(SCH_1):M_K_CPU1_SB_DQS_DP'<6>:
 C_SIGNAL='@t6g_mb_lib.t6g(sch_1):m_k_cpu1_sb_dqs_dp(6)';
NODE_NAME     U26 CM7
 '@T6G_MB_LIB.T6G(SCH_1):PAGE47_I159@PURE_QUANTA.GENOA_SP5(CHIPS)':
 'MKB_DQS_H6': CDS_PINID='MKB_DQS_H6';
NODE_NAME     J99 261
 '@T6G_MB_LIB.T6G(SCH_1):PAGE107_I235@PURE_QUANTA.SCONN288_DDR506112002KQ(CHIPS)':
 'DQS6_B_T||TDQS6_B_T': CDS_PINID='\dqs6_b_t||tdqs6_b_t\';
NET_NAME
'M_K_CPU1_SB_DQS_DP<7>'
 '@T6G_MB_LIB.T6G(SCH_1):M_K_CPU1_SB_DQS_DP'<7>:
 C_SIGNAL='@t6g_mb_lib.t6g(sch_1):m_k_cpu1_sb_dqs_dp(7)';
NODE_NAME     U26 CV7
 '@T6G_MB_LIB.T6G(SCH_1):PAGE47_I159@PURE_QUANTA.GENOA_SP5(CHIPS)':
 'MKB_DQS_H7': CDS_PINID='MKB_DQS_H7';
NODE_NAME     J99 272
 '@T6G_MB_LIB.T6G(SCH_1):PAGE107_I235@PURE_QUANTA.SCONN288_DDR506112002KQ(CHIPS)':
 'DQS7_B_T||TDQS7_B_T': CDS_PINID='\dqs7_b_t||tdqs7_b_t\';
NET_NAME
'M_K_CPU1_SB_DQS_DP<8>'
 '@T6G_MB_LIB.T6G(SCH_1):M_K_CPU1_SB_DQS_DP'<8>:
 C_SIGNAL='@t6g_mb_lib.t6g(sch_1):m_k_cpu1_sb_dqs_dp(8)';
NODE_NAME     U26 DD7
 '@T6G_MB_LIB.T6G(SCH_1):PAGE47_I159@PURE_QUANTA.GENOA_SP5(CHIPS)':
 'MKB_DQS_H8': CDS_PINID='MKB_DQS_H8';
NODE_NAME     J99 283
 '@T6G_MB_LIB.T6G(SCH_1):PAGE107_I235@PURE_QUANTA.SCONN288_DDR506112002KQ(CHIPS)':
 'DQS8_B_T||TDQS8_B_T': CDS_PINID='\dqs8_b_t||tdqs8_b_t\';
NET_NAME
'M_K_CPU1_SB_DQS_DP<9>'
 '@T6G_MB_LIB.T6G(SCH_1):M_K_CPU1_SB_DQS_DP'<9>:
 C_SIGNAL='@t6g_mb_lib.t6g(sch_1):m_k_cpu1_sb_dqs_dp(9)';
NODE_NAME     U26 BV6
 '@T6G_MB_LIB.T6G(SCH_1):PAGE47_I159@PURE_QUANTA.GENOA_SP5(CHIPS)':
 'MKB_DQS_H9': CDS_PINID='MKB_DQS_H9';
NODE_NAME     J99 93
 '@T6G_MB_LIB.T6G(SCH_1):PAGE107_I235@PURE_QUANTA.SCONN288_DDR506112002KQ(CHIPS)':
 'DQS9_B_T||TDQS9_B_T||DBI4_B_N': CDS_PINID='\dqs9_b_t||tdqs9_b_t||dbi4_b_n\';
NET_NAME
'M_K_CPU1_SB_PAR'
 '@T6G_MB_LIB.T6G(SCH_1):M_K_CPU1_SB_PAR':
 C_SIGNAL='@t6g_mb_lib.t6g(sch_1):m_k_cpu1_sb_par';
NODE_NAME     U26 BL7
 '@T6G_MB_LIB.T6G(SCH_1):PAGE47_I159@PURE_QUANTA.GENOA_SP5(CHIPS)':
 'MKB_PAR': CDS_PINID='MKB_PAR';
NODE_NAME     J99 227
 '@T6G_MB_LIB.T6G(SCH_1):PAGE107_I22@PURE_QUANTA.SCONN288_DDR506112002KQ(CHIPS)':
 'PAR_B': CDS_PINID='PAR_B';
NET_NAME
'M_K_CPU1_SB_RSP<0>'
 '@T6G_MB_LIB.T6G(SCH_1):M_K_CPU1_SB_RSP'<0>:
 C_SIGNAL='@t6g_mb_lib.t6g(sch_1):m_k_cpu1_sb_rsp(0)';
NODE_NAME     U26 BP6
 '@T6G_MB_LIB.T6G(SCH_1):PAGE47_I159@PURE_QUANTA.GENOA_SP5(CHIPS)':
 'MKB0_RSP_L': CDS_PINID='MKB0_RSP_L';
NODE_NAME     J99 87
 '@T6G_MB_LIB.T6G(SCH_1):PAGE107_I22@PURE_QUANTA.SCONN288_DDR506112002KQ(CHIPS)':
 'LBS||RSP_B_N': CDS_PINID='\lbs||rsp_b_n\';
NET_NAME
'M_L_CPU0_ALERT_N'
 '@T6G_MB_LIB.T6G(SCH_1):M_L_CPU0_ALERT_N':
 C_SIGNAL='@t6g_mb_lib.t6g(sch_1):m_l_cpu0_alert_n';
NODE_NAME     R386 1
 '@T6G_MB_LIB.T6G(SCH_1):PAGE21_I314@PURE_QUANTA.Q_RES(CHIPS)':
 'A': CDS_PINID='A';
NODE_NAME     J67 62
 '@T6G_MB_LIB.T6G(SCH_1):PAGE96_I22@PURE_QUANTA.SCONN288_DDR506112002KQ(CHIPS)':
 'ALERT_N': CDS_PINID='ALERT_N';
NET_NAME
'M_L_CPU0_ALERT_R_N'
 '@T6G_MB_LIB.T6G(SCH_1):M_L_CPU0_ALERT_R_N':
 C_SIGNAL='@t6g_mb_lib.t6g(sch_1):m_l_cpu0_alert_r_n';
NODE_NAME     U25 AT11
 '@T6G_MB_LIB.T6G(SCH_1):PAGE21_I159@PURE_QUANTA.GENOA_SP5(CHIPS)':
 'ML_ALERT_L': CDS_PINID='ML_ALERT_L';
NODE_NAME     R386 2
 '@T6G_MB_LIB.T6G(SCH_1):PAGE21_I314@PURE_QUANTA.Q_RES(CHIPS)':
 'B': CDS_PINID='B';
NET_NAME
'M_L_CPU0_CLK_DN<0>'
 '@T6G_MB_LIB.T6G(SCH_1):M_L_CPU0_CLK_DN'<0>:
 C_SIGNAL='@t6g_mb_lib.t6g(sch_1):m_l_cpu0_clk_dn(0)';
NODE_NAME     U25 BD9
 '@T6G_MB_LIB.T6G(SCH_1):PAGE21_I159@PURE_QUANTA.GENOA_SP5(CHIPS)':
 'ML0_CLK_L': CDS_PINID='ML0_CLK_L';
NODE_NAME     J67 218
 '@T6G_MB_LIB.T6G(SCH_1):PAGE96_I22@PURE_QUANTA.SCONN288_DDR506112002KQ(CHIPS)':
 'CK_C': CDS_PINID='CK_C';
NET_NAME
'M_L_CPU0_CLK_DP<0>'
 '@T6G_MB_LIB.T6G(SCH_1):M_L_CPU0_CLK_DP'<0>:
 C_SIGNAL='@t6g_mb_lib.t6g(sch_1):m_l_cpu0_clk_dp(0)';
NODE_NAME     U25 BC9
 '@T6G_MB_LIB.T6G(SCH_1):PAGE21_I159@PURE_QUANTA.GENOA_SP5(CHIPS)':
 'ML0_CLK_H': CDS_PINID='ML0_CLK_H';
NODE_NAME     J67 217
 '@T6G_MB_LIB.T6G(SCH_1):PAGE96_I22@PURE_QUANTA.SCONN288_DDR506112002KQ(CHIPS)':
 'CK_T': CDS_PINID='CK_T';
NET_NAME
'M_L_CPU0_RESET_N'
 '@T6G_MB_LIB.T6G(SCH_1):M_L_CPU0_RESET_N':
 C_SIGNAL='@t6g_mb_lib.t6g(sch_1):m_l_cpu0_reset_n';
NODE_NAME     U25 AU10
 '@T6G_MB_LIB.T6G(SCH_1):PAGE21_I159@PURE_QUANTA.GENOA_SP5(CHIPS)':
 'ML_RESET_L': CDS_PINID='ML_RESET_L';
NODE_NAME     J67 207
 '@T6G_MB_LIB.T6G(SCH_1):PAGE96_I22@PURE_QUANTA.SCONN288_DDR506112002KQ(CHIPS)':
 'RESET_N': CDS_PINID='RESET_N';
NET_NAME
'M_L_CPU0_SA_CA<0>'
 '@T6G_MB_LIB.T6G(SCH_1):M_L_CPU0_SA_CA'<0>:
 C_SIGNAL='@t6g_mb_lib.t6g(sch_1):m_l_cpu0_sa_ca(0)';
NODE_NAME     U25 AW9
 '@T6G_MB_LIB.T6G(SCH_1):PAGE21_I159@PURE_QUANTA.GENOA_SP5(CHIPS)':
 'MLA_CA0': CDS_PINID='MLA_CA0';
NODE_NAME     J67 66
 '@T6G_MB_LIB.T6G(SCH_1):PAGE96_I22@PURE_QUANTA.SCONN288_DDR506112002KQ(CHIPS)':
 'CA0_A': CDS_PINID='CA0_A';
NET_NAME
'M_L_CPU0_SA_CA<1>'
 '@T6G_MB_LIB.T6G(SCH_1):M_L_CPU0_SA_CA'<1>:
 C_SIGNAL='@t6g_mb_lib.t6g(sch_1):m_l_cpu0_sa_ca(1)';
NODE_NAME     U25 AY9
 '@T6G_MB_LIB.T6G(SCH_1):PAGE21_I159@PURE_QUANTA.GENOA_SP5(CHIPS)':
 'MLA_CA1': CDS_PINID='MLA_CA1';
NODE_NAME     J67 211
 '@T6G_MB_LIB.T6G(SCH_1):PAGE96_I22@PURE_QUANTA.SCONN288_DDR506112002KQ(CHIPS)':
 'CA1_A': CDS_PINID='CA1_A';
NET_NAME
'M_L_CPU0_SA_CA<2>'
 '@T6G_MB_LIB.T6G(SCH_1):M_L_CPU0_SA_CA'<2>:
 C_SIGNAL='@t6g_mb_lib.t6g(sch_1):m_l_cpu0_sa_ca(2)';
NODE_NAME     U25 AY11
 '@T6G_MB_LIB.T6G(SCH_1):PAGE21_I159@PURE_QUANTA.GENOA_SP5(CHIPS)':
 'MLA_CA2': CDS_PINID='MLA_CA2';
NODE_NAME     J67 68
 '@T6G_MB_LIB.T6G(SCH_1):PAGE96_I22@PURE_QUANTA.SCONN288_DDR506112002KQ(CHIPS)':
 'CA2_A': CDS_PINID='CA2_A';
NET_NAME
'M_L_CPU0_SA_CA<3>'
 '@T6G_MB_LIB.T6G(SCH_1):M_L_CPU0_SA_CA'<3>:
 C_SIGNAL='@t6g_mb_lib.t6g(sch_1):m_l_cpu0_sa_ca(3)';
NODE_NAME     U25 BA10
 '@T6G_MB_LIB.T6G(SCH_1):PAGE21_I159@PURE_QUANTA.GENOA_SP5(CHIPS)':
 'MLA_CA3': CDS_PINID='MLA_CA3';
NODE_NAME     J67 213
 '@T6G_MB_LIB.T6G(SCH_1):PAGE96_I22@PURE_QUANTA.SCONN288_DDR506112002KQ(CHIPS)':
 'CA3_A': CDS_PINID='CA3_A';
NET_NAME
'M_L_CPU0_SA_CA<4>'
 '@T6G_MB_LIB.T6G(SCH_1):M_L_CPU0_SA_CA'<4>:
 C_SIGNAL='@t6g_mb_lib.t6g(sch_1):m_l_cpu0_sa_ca(4)';
NODE_NAME     U25 BA9
 '@T6G_MB_LIB.T6G(SCH_1):PAGE21_I159@PURE_QUANTA.GENOA_SP5(CHIPS)':
 'MLA_CA4': CDS_PINID='MLA_CA4';
NODE_NAME     J67 70
 '@T6G_MB_LIB.T6G(SCH_1):PAGE96_I22@PURE_QUANTA.SCONN288_DDR506112002KQ(CHIPS)':
 'CA4_A': CDS_PINID='CA4_A';
NET_NAME
'M_L_CPU0_SA_CA<5>'
 '@T6G_MB_LIB.T6G(SCH_1):M_L_CPU0_SA_CA'<5>:
 C_SIGNAL='@t6g_mb_lib.t6g(sch_1):m_l_cpu0_sa_ca(5)';
NODE_NAME     U25 BB9
 '@T6G_MB_LIB.T6G(SCH_1):PAGE21_I159@PURE_QUANTA.GENOA_SP5(CHIPS)':
 'MLA_CA5': CDS_PINID='MLA_CA5';
NODE_NAME     J67 215
 '@T6G_MB_LIB.T6G(SCH_1):PAGE96_I22@PURE_QUANTA.SCONN288_DDR506112002KQ(CHIPS)':
 'CA5_A': CDS_PINID='CA5_A';
NET_NAME
'M_L_CPU0_SA_CA<6>'
 '@T6G_MB_LIB.T6G(SCH_1):M_L_CPU0_SA_CA'<6>:
 C_SIGNAL='@t6g_mb_lib.t6g(sch_1):m_l_cpu0_sa_ca(6)';
NODE_NAME     U25 BB11
 '@T6G_MB_LIB.T6G(SCH_1):PAGE21_I159@PURE_QUANTA.GENOA_SP5(CHIPS)':
 'MLA_CA6': CDS_PINID='MLA_CA6';
NODE_NAME     J67 72
 '@T6G_MB_LIB.T6G(SCH_1):PAGE96_I22@PURE_QUANTA.SCONN288_DDR506112002KQ(CHIPS)':
 'CA6_A': CDS_PINID='CA6_A';
NET_NAME
'M_L_CPU0_SA_CB<0>'
 '@T6G_MB_LIB.T6G(SCH_1):M_L_CPU0_SA_CB'<0>:
 C_SIGNAL='@t6g_mb_lib.t6g(sch_1):m_l_cpu0_sa_cb(0)';
NODE_NAME     U25 AJ9
 '@T6G_MB_LIB.T6G(SCH_1):PAGE21_I159@PURE_QUANTA.GENOA_SP5(CHIPS)':
 'MLA_CHECK0': CDS_PINID='MLA_CHECK0';
NODE_NAME     J67 51
 '@T6G_MB_LIB.T6G(SCH_1):PAGE96_I22@PURE_QUANTA.SCONN288_DDR506112002KQ(CHIPS)':
 'CB0_A': CDS_PINID='CB0_A';
NET_NAME
'M_L_CPU0_SA_CB<1>'
 '@T6G_MB_LIB.T6G(SCH_1):M_L_CPU0_SA_CB'<1>:
 C_SIGNAL='@t6g_mb_lib.t6g(sch_1):m_l_cpu0_sa_cb(1)';
NODE_NAME     U25 AK11
 '@T6G_MB_LIB.T6G(SCH_1):PAGE21_I159@PURE_QUANTA.GENOA_SP5(CHIPS)':
 'MLA_CHECK1': CDS_PINID='MLA_CHECK1';
NODE_NAME     J67 53
 '@T6G_MB_LIB.T6G(SCH_1):PAGE96_I22@PURE_QUANTA.SCONN288_DDR506112002KQ(CHIPS)':
 'CB1_A': CDS_PINID='CB1_A';
NET_NAME
'M_L_CPU0_SA_CB<2>'
 '@T6G_MB_LIB.T6G(SCH_1):M_L_CPU0_SA_CB'<2>:
 C_SIGNAL='@t6g_mb_lib.t6g(sch_1):m_l_cpu0_sa_cb(2)';
NODE_NAME     U25 AK9
 '@T6G_MB_LIB.T6G(SCH_1):PAGE21_I159@PURE_QUANTA.GENOA_SP5(CHIPS)':
 'MLA_CHECK2': CDS_PINID='MLA_CHECK2';
NODE_NAME     J67 196
 '@T6G_MB_LIB.T6G(SCH_1):PAGE96_I22@PURE_QUANTA.SCONN288_DDR506112002KQ(CHIPS)':
 'CB2_A': CDS_PINID='CB2_A';
NET_NAME
'M_L_CPU0_SA_CB<3>'
 '@T6G_MB_LIB.T6G(SCH_1):M_L_CPU0_SA_CB'<3>:
 C_SIGNAL='@t6g_mb_lib.t6g(sch_1):m_l_cpu0_sa_cb(3)';
NODE_NAME     U25 AL10
 '@T6G_MB_LIB.T6G(SCH_1):PAGE21_I159@PURE_QUANTA.GENOA_SP5(CHIPS)':
 'MLA_CHECK3': CDS_PINID='MLA_CHECK3';
NODE_NAME     J67 198
 '@T6G_MB_LIB.T6G(SCH_1):PAGE96_I22@PURE_QUANTA.SCONN288_DDR506112002KQ(CHIPS)':
 'CB3_A': CDS_PINID='CB3_A';
NET_NAME
'M_L_CPU0_SA_CB<4>'
 '@T6G_MB_LIB.T6G(SCH_1):M_L_CPU0_SA_CB'<4>:
 C_SIGNAL='@t6g_mb_lib.t6g(sch_1):m_l_cpu0_sa_cb(4)';
NODE_NAME     U25 AN9
 '@T6G_MB_LIB.T6G(SCH_1):PAGE21_I159@PURE_QUANTA.GENOA_SP5(CHIPS)':
 'MLA_CHECK4': CDS_PINID='MLA_CHECK4';
NODE_NAME     J67 58
 '@T6G_MB_LIB.T6G(SCH_1):PAGE96_I22@PURE_QUANTA.SCONN288_DDR506112002KQ(CHIPS)':
 'CB4_A': CDS_PINID='CB4_A';
NET_NAME
'M_L_CPU0_SA_CB<5>'
 '@T6G_MB_LIB.T6G(SCH_1):M_L_CPU0_SA_CB'<5>:
 C_SIGNAL='@t6g_mb_lib.t6g(sch_1):m_l_cpu0_sa_cb(5)';
NODE_NAME     U25 AP11
 '@T6G_MB_LIB.T6G(SCH_1):PAGE21_I159@PURE_QUANTA.GENOA_SP5(CHIPS)':
 'MLA_CHECK5': CDS_PINID='MLA_CHECK5';
NODE_NAME     J67 60
 '@T6G_MB_LIB.T6G(SCH_1):PAGE96_I22@PURE_QUANTA.SCONN288_DDR506112002KQ(CHIPS)':
 'CB5_A': CDS_PINID='CB5_A';
NET_NAME
'M_L_CPU0_SA_CB<6>'
 '@T6G_MB_LIB.T6G(SCH_1):M_L_CPU0_SA_CB'<6>:
 C_SIGNAL='@t6g_mb_lib.t6g(sch_1):m_l_cpu0_sa_cb(6)';
NODE_NAME     U25 AP9
 '@T6G_MB_LIB.T6G(SCH_1):PAGE21_I159@PURE_QUANTA.GENOA_SP5(CHIPS)':
 'MLA_CHECK6': CDS_PINID='MLA_CHECK6';
NODE_NAME     J67 203
 '@T6G_MB_LIB.T6G(SCH_1):PAGE96_I22@PURE_QUANTA.SCONN288_DDR506112002KQ(CHIPS)':
 'CB6_A': CDS_PINID='CB6_A';
NET_NAME
'M_L_CPU0_SA_CB<7>'
 '@T6G_MB_LIB.T6G(SCH_1):M_L_CPU0_SA_CB'<7>:
 C_SIGNAL='@t6g_mb_lib.t6g(sch_1):m_l_cpu0_sa_cb(7)';
NODE_NAME     U25 AR10
 '@T6G_MB_LIB.T6G(SCH_1):PAGE21_I159@PURE_QUANTA.GENOA_SP5(CHIPS)':
 'MLA_CHECK7': CDS_PINID='MLA_CHECK7';
NODE_NAME     J67 205
 '@T6G_MB_LIB.T6G(SCH_1):PAGE96_I22@PURE_QUANTA.SCONN288_DDR506112002KQ(CHIPS)':
 'CB7_A': CDS_PINID='CB7_A';
NET_NAME
'M_L_CPU0_SA_CS_N<0>'
 '@T6G_MB_LIB.T6G(SCH_1):M_L_CPU0_SA_CS_N'<0>:
 C_SIGNAL='@t6g_mb_lib.t6g(sch_1):m_l_cpu0_sa_cs_n(0)';
NODE_NAME     U25 AU9
 '@T6G_MB_LIB.T6G(SCH_1):PAGE21_I159@PURE_QUANTA.GENOA_SP5(CHIPS)':
 'MLA0_CS_L0': CDS_PINID='MLA0_CS_L0';
NODE_NAME     J67 64
 '@T6G_MB_LIB.T6G(SCH_1):PAGE96_I22@PURE_QUANTA.SCONN288_DDR506112002KQ(CHIPS)':
 'CS0_A_N': CDS_PINID='CS0_A_N';
NET_NAME
'M_L_CPU0_SA_CS_N<1>'
 '@T6G_MB_LIB.T6G(SCH_1):M_L_CPU0_SA_CS_N'<1>:
 C_SIGNAL='@t6g_mb_lib.t6g(sch_1):m_l_cpu0_sa_cs_n(1)';
NODE_NAME     U25 AV11
 '@T6G_MB_LIB.T6G(SCH_1):PAGE21_I159@PURE_QUANTA.GENOA_SP5(CHIPS)':
 'MLA0_CS_L1': CDS_PINID='MLA0_CS_L1';
NODE_NAME     J67 209
 '@T6G_MB_LIB.T6G(SCH_1):PAGE96_I22@PURE_QUANTA.SCONN288_DDR506112002KQ(CHIPS)':
 'CS1_A_N': CDS_PINID='CS1_A_N';
NET_NAME
'M_L_CPU0_SA_DQ<0>'
 '@T6G_MB_LIB.T6G(SCH_1):M_L_CPU0_SA_DQ'<0>:
 C_SIGNAL='@t6g_mb_lib.t6g(sch_1):m_l_cpu0_sa_dq(0)';
NODE_NAME     U25 E9
 '@T6G_MB_LIB.T6G(SCH_1):PAGE21_I159@PURE_QUANTA.GENOA_SP5(CHIPS)':
 'MLA_DATA0': CDS_PINID='MLA_DATA0';
NODE_NAME     J67 7
 '@T6G_MB_LIB.T6G(SCH_1):PAGE96_I22@PURE_QUANTA.SCONN288_DDR506112002KQ(CHIPS)':
 'DQ0_A': CDS_PINID='DQ0_A';
NET_NAME
'M_L_CPU0_SA_DQ<10>'
 '@T6G_MB_LIB.T6G(SCH_1):M_L_CPU0_SA_DQ'<10>:
 C_SIGNAL='@t6g_mb_lib.t6g(sch_1):m_l_cpu0_sa_dq(10)';
NODE_NAME     U25 M9
 '@T6G_MB_LIB.T6G(SCH_1):PAGE21_I159@PURE_QUANTA.GENOA_SP5(CHIPS)':
 'MLA_DATA10': CDS_PINID='MLA_DATA10';
NODE_NAME     J67 163
 '@T6G_MB_LIB.T6G(SCH_1):PAGE96_I22@PURE_QUANTA.SCONN288_DDR506112002KQ(CHIPS)':
 'DQ10_A': CDS_PINID='DQ10_A';
NET_NAME
'M_L_CPU0_SA_DQ<11>'
 '@T6G_MB_LIB.T6G(SCH_1):M_L_CPU0_SA_DQ'<11>:
 C_SIGNAL='@t6g_mb_lib.t6g(sch_1):m_l_cpu0_sa_dq(11)';
NODE_NAME     U25 N10
 '@T6G_MB_LIB.T6G(SCH_1):PAGE21_I159@PURE_QUANTA.GENOA_SP5(CHIPS)':
 'MLA_DATA11': CDS_PINID='MLA_DATA11';
NODE_NAME     J67 165
 '@T6G_MB_LIB.T6G(SCH_1):PAGE96_I22@PURE_QUANTA.SCONN288_DDR506112002KQ(CHIPS)':
 'DQ11_A': CDS_PINID='DQ11_A';
NET_NAME
'M_L_CPU0_SA_DQ<12>'
 '@T6G_MB_LIB.T6G(SCH_1):M_L_CPU0_SA_DQ'<12>:
 C_SIGNAL='@t6g_mb_lib.t6g(sch_1):m_l_cpu0_sa_dq(12)';
NODE_NAME     U25 R9
 '@T6G_MB_LIB.T6G(SCH_1):PAGE21_I159@PURE_QUANTA.GENOA_SP5(CHIPS)':
 'MLA_DATA12': CDS_PINID='MLA_DATA12';
NODE_NAME     J67 25
 '@T6G_MB_LIB.T6G(SCH_1):PAGE96_I22@PURE_QUANTA.SCONN288_DDR506112002KQ(CHIPS)':
 'DQ12_A': CDS_PINID='DQ12_A';
NET_NAME
'M_L_CPU0_SA_DQ<13>'
 '@T6G_MB_LIB.T6G(SCH_1):M_L_CPU0_SA_DQ'<13>:
 C_SIGNAL='@t6g_mb_lib.t6g(sch_1):m_l_cpu0_sa_dq(13)';
NODE_NAME     U25 T11
 '@T6G_MB_LIB.T6G(SCH_1):PAGE21_I159@PURE_QUANTA.GENOA_SP5(CHIPS)':
 'MLA_DATA13': CDS_PINID='MLA_DATA13';
NODE_NAME     J67 27
 '@T6G_MB_LIB.T6G(SCH_1):PAGE96_I22@PURE_QUANTA.SCONN288_DDR506112002KQ(CHIPS)':
 'DQ13_A': CDS_PINID='DQ13_A';
NET_NAME
'M_L_CPU0_SA_DQ<14>'
 '@T6G_MB_LIB.T6G(SCH_1):M_L_CPU0_SA_DQ'<14>:
 C_SIGNAL='@t6g_mb_lib.t6g(sch_1):m_l_cpu0_sa_dq(14)';
NODE_NAME     U25 T9
 '@T6G_MB_LIB.T6G(SCH_1):PAGE21_I159@PURE_QUANTA.GENOA_SP5(CHIPS)':
 'MLA_DATA14': CDS_PINID='MLA_DATA14';
NODE_NAME     J67 170
 '@T6G_MB_LIB.T6G(SCH_1):PAGE96_I22@PURE_QUANTA.SCONN288_DDR506112002KQ(CHIPS)':
 'DQ14_A': CDS_PINID='DQ14_A';
NET_NAME
'M_L_CPU0_SA_DQ<15>'
 '@T6G_MB_LIB.T6G(SCH_1):M_L_CPU0_SA_DQ'<15>:
 C_SIGNAL='@t6g_mb_lib.t6g(sch_1):m_l_cpu0_sa_dq(15)';
NODE_NAME     U25 U10
 '@T6G_MB_LIB.T6G(SCH_1):PAGE21_I159@PURE_QUANTA.GENOA_SP5(CHIPS)':
 'MLA_DATA15': CDS_PINID='MLA_DATA15';
NODE_NAME     J67 172
 '@T6G_MB_LIB.T6G(SCH_1):PAGE96_I22@PURE_QUANTA.SCONN288_DDR506112002KQ(CHIPS)':
 'DQ15_A': CDS_PINID='DQ15_A';
NET_NAME
'M_L_CPU0_SA_DQ<16>'
 '@T6G_MB_LIB.T6G(SCH_1):M_L_CPU0_SA_DQ'<16>:
 C_SIGNAL='@t6g_mb_lib.t6g(sch_1):m_l_cpu0_sa_dq(16)';
NODE_NAME     U25 U9
 '@T6G_MB_LIB.T6G(SCH_1):PAGE21_I159@PURE_QUANTA.GENOA_SP5(CHIPS)':
 'MLA_DATA16': CDS_PINID='MLA_DATA16';
NODE_NAME     J67 29
 '@T6G_MB_LIB.T6G(SCH_1):PAGE96_I22@PURE_QUANTA.SCONN288_DDR506112002KQ(CHIPS)':
 'DQ16_A': CDS_PINID='DQ16_A';
NET_NAME
'M_L_CPU0_SA_DQ<17>'
 '@T6G_MB_LIB.T6G(SCH_1):M_L_CPU0_SA_DQ'<17>:
 C_SIGNAL='@t6g_mb_lib.t6g(sch_1):m_l_cpu0_sa_dq(17)';
NODE_NAME     U25 V11
 '@T6G_MB_LIB.T6G(SCH_1):PAGE21_I159@PURE_QUANTA.GENOA_SP5(CHIPS)':
 'MLA_DATA17': CDS_PINID='MLA_DATA17';
NODE_NAME     J67 31
 '@T6G_MB_LIB.T6G(SCH_1):PAGE96_I22@PURE_QUANTA.SCONN288_DDR506112002KQ(CHIPS)':
 'DQ17_A': CDS_PINID='DQ17_A';
NET_NAME
'M_L_CPU0_SA_DQ<18>'
 '@T6G_MB_LIB.T6G(SCH_1):M_L_CPU0_SA_DQ'<18>:
 C_SIGNAL='@t6g_mb_lib.t6g(sch_1):m_l_cpu0_sa_dq(18)';
NODE_NAME     U25 V9
 '@T6G_MB_LIB.T6G(SCH_1):PAGE21_I159@PURE_QUANTA.GENOA_SP5(CHIPS)':
 'MLA_DATA18': CDS_PINID='MLA_DATA18';
NODE_NAME     J67 174
 '@T6G_MB_LIB.T6G(SCH_1):PAGE96_I22@PURE_QUANTA.SCONN288_DDR506112002KQ(CHIPS)':
 'DQ18_A': CDS_PINID='DQ18_A';
NET_NAME
'M_L_CPU0_SA_DQ<19>'
 '@T6G_MB_LIB.T6G(SCH_1):M_L_CPU0_SA_DQ'<19>:
 C_SIGNAL='@t6g_mb_lib.t6g(sch_1):m_l_cpu0_sa_dq(19)';
NODE_NAME     U25 W10
 '@T6G_MB_LIB.T6G(SCH_1):PAGE21_I159@PURE_QUANTA.GENOA_SP5(CHIPS)':
 'MLA_DATA19': CDS_PINID='MLA_DATA19';
NODE_NAME     J67 176
 '@T6G_MB_LIB.T6G(SCH_1):PAGE96_I22@PURE_QUANTA.SCONN288_DDR506112002KQ(CHIPS)':
 'DQ19_A': CDS_PINID='DQ19_A';
NET_NAME
'M_L_CPU0_SA_DQ<1>'
 '@T6G_MB_LIB.T6G(SCH_1):M_L_CPU0_SA_DQ'<1>:
 C_SIGNAL='@t6g_mb_lib.t6g(sch_1):m_l_cpu0_sa_dq(1)';
NODE_NAME     U25 F11
 '@T6G_MB_LIB.T6G(SCH_1):PAGE21_I159@PURE_QUANTA.GENOA_SP5(CHIPS)':
 'MLA_DATA1': CDS_PINID='MLA_DATA1';
NODE_NAME     J67 9
 '@T6G_MB_LIB.T6G(SCH_1):PAGE96_I22@PURE_QUANTA.SCONN288_DDR506112002KQ(CHIPS)':
 'DQ1_A': CDS_PINID='DQ1_A';
NET_NAME
'M_L_CPU0_SA_DQ<20>'
 '@T6G_MB_LIB.T6G(SCH_1):M_L_CPU0_SA_DQ'<20>:
 C_SIGNAL='@t6g_mb_lib.t6g(sch_1):m_l_cpu0_sa_dq(20)';
NODE_NAME     U25 AA9
 '@T6G_MB_LIB.T6G(SCH_1):PAGE21_I159@PURE_QUANTA.GENOA_SP5(CHIPS)':
 'MLA_DATA20': CDS_PINID='MLA_DATA20';
NODE_NAME     J67 36
 '@T6G_MB_LIB.T6G(SCH_1):PAGE96_I22@PURE_QUANTA.SCONN288_DDR506112002KQ(CHIPS)':
 'DQ20_A': CDS_PINID='DQ20_A';
NET_NAME
'M_L_CPU0_SA_DQ<21>'
 '@T6G_MB_LIB.T6G(SCH_1):M_L_CPU0_SA_DQ'<21>:
 C_SIGNAL='@t6g_mb_lib.t6g(sch_1):m_l_cpu0_sa_dq(21)';
NODE_NAME     U25 AB11
 '@T6G_MB_LIB.T6G(SCH_1):PAGE21_I159@PURE_QUANTA.GENOA_SP5(CHIPS)':
 'MLA_DATA21': CDS_PINID='MLA_DATA21';
NODE_NAME     J67 38
 '@T6G_MB_LIB.T6G(SCH_1):PAGE96_I22@PURE_QUANTA.SCONN288_DDR506112002KQ(CHIPS)':
 'DQ21_A': CDS_PINID='DQ21_A';
NET_NAME
'M_L_CPU0_SA_DQ<22>'
 '@T6G_MB_LIB.T6G(SCH_1):M_L_CPU0_SA_DQ'<22>:
 C_SIGNAL='@t6g_mb_lib.t6g(sch_1):m_l_cpu0_sa_dq(22)';
NODE_NAME     U25 AB9
 '@T6G_MB_LIB.T6G(SCH_1):PAGE21_I159@PURE_QUANTA.GENOA_SP5(CHIPS)':
 'MLA_DATA22': CDS_PINID='MLA_DATA22';
NODE_NAME     J67 181
 '@T6G_MB_LIB.T6G(SCH_1):PAGE96_I22@PURE_QUANTA.SCONN288_DDR506112002KQ(CHIPS)':
 'DQ22_A': CDS_PINID='DQ22_A';
NET_NAME
'M_L_CPU0_SA_DQ<23>'
 '@T6G_MB_LIB.T6G(SCH_1):M_L_CPU0_SA_DQ'<23>:
 C_SIGNAL='@t6g_mb_lib.t6g(sch_1):m_l_cpu0_sa_dq(23)';
NODE_NAME     U25 AC10
 '@T6G_MB_LIB.T6G(SCH_1):PAGE21_I159@PURE_QUANTA.GENOA_SP5(CHIPS)':
 'MLA_DATA23': CDS_PINID='MLA_DATA23';
NODE_NAME     J67 183
 '@T6G_MB_LIB.T6G(SCH_1):PAGE96_I22@PURE_QUANTA.SCONN288_DDR506112002KQ(CHIPS)':
 'DQ23_A': CDS_PINID='DQ23_A';
NET_NAME
'M_L_CPU0_SA_DQ<24>'
 '@T6G_MB_LIB.T6G(SCH_1):M_L_CPU0_SA_DQ'<24>:
 C_SIGNAL='@t6g_mb_lib.t6g(sch_1):m_l_cpu0_sa_dq(24)';
NODE_NAME     U25 AC9
 '@T6G_MB_LIB.T6G(SCH_1):PAGE21_I159@PURE_QUANTA.GENOA_SP5(CHIPS)':
 'MLA_DATA24': CDS_PINID='MLA_DATA24';
NODE_NAME     J67 40
 '@T6G_MB_LIB.T6G(SCH_1):PAGE96_I22@PURE_QUANTA.SCONN288_DDR506112002KQ(CHIPS)':
 'DQ24_A': CDS_PINID='DQ24_A';
NET_NAME
'M_L_CPU0_SA_DQ<25>'
 '@T6G_MB_LIB.T6G(SCH_1):M_L_CPU0_SA_DQ'<25>:
 C_SIGNAL='@t6g_mb_lib.t6g(sch_1):m_l_cpu0_sa_dq(25)';
NODE_NAME     U25 AD11
 '@T6G_MB_LIB.T6G(SCH_1):PAGE21_I159@PURE_QUANTA.GENOA_SP5(CHIPS)':
 'MLA_DATA25': CDS_PINID='MLA_DATA25';
NODE_NAME     J67 42
 '@T6G_MB_LIB.T6G(SCH_1):PAGE96_I22@PURE_QUANTA.SCONN288_DDR506112002KQ(CHIPS)':
 'DQ25_A': CDS_PINID='DQ25_A';
NET_NAME
'M_L_CPU0_SA_DQ<26>'
 '@T6G_MB_LIB.T6G(SCH_1):M_L_CPU0_SA_DQ'<26>:
 C_SIGNAL='@t6g_mb_lib.t6g(sch_1):m_l_cpu0_sa_dq(26)';
NODE_NAME     U25 AD9
 '@T6G_MB_LIB.T6G(SCH_1):PAGE21_I159@PURE_QUANTA.GENOA_SP5(CHIPS)':
 'MLA_DATA26': CDS_PINID='MLA_DATA26';
NODE_NAME     J67 185
 '@T6G_MB_LIB.T6G(SCH_1):PAGE96_I22@PURE_QUANTA.SCONN288_DDR506112002KQ(CHIPS)':
 'DQ26_A': CDS_PINID='DQ26_A';
NET_NAME
'M_L_CPU0_SA_DQ<27>'
 '@T6G_MB_LIB.T6G(SCH_1):M_L_CPU0_SA_DQ'<27>:
 C_SIGNAL='@t6g_mb_lib.t6g(sch_1):m_l_cpu0_sa_dq(27)';
NODE_NAME     U25 AE10
 '@T6G_MB_LIB.T6G(SCH_1):PAGE21_I159@PURE_QUANTA.GENOA_SP5(CHIPS)':
 'MLA_DATA27': CDS_PINID='MLA_DATA27';
NODE_NAME     J67 187
 '@T6G_MB_LIB.T6G(SCH_1):PAGE96_I22@PURE_QUANTA.SCONN288_DDR506112002KQ(CHIPS)':
 'DQ27_A': CDS_PINID='DQ27_A';
NET_NAME
'M_L_CPU0_SA_DQ<28>'
 '@T6G_MB_LIB.T6G(SCH_1):M_L_CPU0_SA_DQ'<28>:
 C_SIGNAL='@t6g_mb_lib.t6g(sch_1):m_l_cpu0_sa_dq(28)';
NODE_NAME     U25 AG9
 '@T6G_MB_LIB.T6G(SCH_1):PAGE21_I159@PURE_QUANTA.GENOA_SP5(CHIPS)':
 'MLA_DATA28': CDS_PINID='MLA_DATA28';
NODE_NAME     J67 47
 '@T6G_MB_LIB.T6G(SCH_1):PAGE96_I22@PURE_QUANTA.SCONN288_DDR506112002KQ(CHIPS)':
 'DQ28_A': CDS_PINID='DQ28_A';
NET_NAME
'M_L_CPU0_SA_DQ<29>'
 '@T6G_MB_LIB.T6G(SCH_1):M_L_CPU0_SA_DQ'<29>:
 C_SIGNAL='@t6g_mb_lib.t6g(sch_1):m_l_cpu0_sa_dq(29)';
NODE_NAME     U25 AH11
 '@T6G_MB_LIB.T6G(SCH_1):PAGE21_I159@PURE_QUANTA.GENOA_SP5(CHIPS)':
 'MLA_DATA29': CDS_PINID='MLA_DATA29';
NODE_NAME     J67 49
 '@T6G_MB_LIB.T6G(SCH_1):PAGE96_I22@PURE_QUANTA.SCONN288_DDR506112002KQ(CHIPS)':
 'DQ29_A': CDS_PINID='DQ29_A';
NET_NAME
'M_L_CPU0_SA_DQ<2>'
 '@T6G_MB_LIB.T6G(SCH_1):M_L_CPU0_SA_DQ'<2>:
 C_SIGNAL='@t6g_mb_lib.t6g(sch_1):m_l_cpu0_sa_dq(2)';
NODE_NAME     U25 F9
 '@T6G_MB_LIB.T6G(SCH_1):PAGE21_I159@PURE_QUANTA.GENOA_SP5(CHIPS)':
 'MLA_DATA2': CDS_PINID='MLA_DATA2';
NODE_NAME     J67 152
 '@T6G_MB_LIB.T6G(SCH_1):PAGE96_I22@PURE_QUANTA.SCONN288_DDR506112002KQ(CHIPS)':
 'DQ2_A': CDS_PINID='DQ2_A';
NET_NAME
'M_L_CPU0_SA_DQ<30>'
 '@T6G_MB_LIB.T6G(SCH_1):M_L_CPU0_SA_DQ'<30>:
 C_SIGNAL='@t6g_mb_lib.t6g(sch_1):m_l_cpu0_sa_dq(30)';
NODE_NAME     U25 AH9
 '@T6G_MB_LIB.T6G(SCH_1):PAGE21_I159@PURE_QUANTA.GENOA_SP5(CHIPS)':
 'MLA_DATA30': CDS_PINID='MLA_DATA30';
NODE_NAME     J67 192
 '@T6G_MB_LIB.T6G(SCH_1):PAGE96_I22@PURE_QUANTA.SCONN288_DDR506112002KQ(CHIPS)':
 'DQ30_A': CDS_PINID='DQ30_A';
NET_NAME
'M_L_CPU0_SA_DQ<31>'
 '@T6G_MB_LIB.T6G(SCH_1):M_L_CPU0_SA_DQ'<31>:
 C_SIGNAL='@t6g_mb_lib.t6g(sch_1):m_l_cpu0_sa_dq(31)';
NODE_NAME     U25 AJ10
 '@T6G_MB_LIB.T6G(SCH_1):PAGE21_I159@PURE_QUANTA.GENOA_SP5(CHIPS)':
 'MLA_DATA31': CDS_PINID='MLA_DATA31';
NODE_NAME     J67 194
 '@T6G_MB_LIB.T6G(SCH_1):PAGE96_I22@PURE_QUANTA.SCONN288_DDR506112002KQ(CHIPS)':
 'DQ31_A': CDS_PINID='DQ31_A';
NET_NAME
'M_L_CPU0_SA_DQ<3>'
 '@T6G_MB_LIB.T6G(SCH_1):M_L_CPU0_SA_DQ'<3>:
 C_SIGNAL='@t6g_mb_lib.t6g(sch_1):m_l_cpu0_sa_dq(3)';
NODE_NAME     U25 G10
 '@T6G_MB_LIB.T6G(SCH_1):PAGE21_I159@PURE_QUANTA.GENOA_SP5(CHIPS)':
 'MLA_DATA3': CDS_PINID='MLA_DATA3';
NODE_NAME     J67 154
 '@T6G_MB_LIB.T6G(SCH_1):PAGE96_I22@PURE_QUANTA.SCONN288_DDR506112002KQ(CHIPS)':
 'DQ3_A': CDS_PINID='DQ3_A';
NET_NAME
'M_L_CPU0_SA_DQ<4>'
 '@T6G_MB_LIB.T6G(SCH_1):M_L_CPU0_SA_DQ'<4>:
 C_SIGNAL='@t6g_mb_lib.t6g(sch_1):m_l_cpu0_sa_dq(4)';
NODE_NAME     U25 J9
 '@T6G_MB_LIB.T6G(SCH_1):PAGE21_I159@PURE_QUANTA.GENOA_SP5(CHIPS)':
 'MLA_DATA4': CDS_PINID='MLA_DATA4';
NODE_NAME     J67 14
 '@T6G_MB_LIB.T6G(SCH_1):PAGE96_I22@PURE_QUANTA.SCONN288_DDR506112002KQ(CHIPS)':
 'DQ4_A': CDS_PINID='DQ4_A';
NET_NAME
'M_L_CPU0_SA_DQ<5>'
 '@T6G_MB_LIB.T6G(SCH_1):M_L_CPU0_SA_DQ'<5>:
 C_SIGNAL='@t6g_mb_lib.t6g(sch_1):m_l_cpu0_sa_dq(5)';
NODE_NAME     U25 K11
 '@T6G_MB_LIB.T6G(SCH_1):PAGE21_I159@PURE_QUANTA.GENOA_SP5(CHIPS)':
 'MLA_DATA5': CDS_PINID='MLA_DATA5';
NODE_NAME     J67 16
 '@T6G_MB_LIB.T6G(SCH_1):PAGE96_I22@PURE_QUANTA.SCONN288_DDR506112002KQ(CHIPS)':
 'DQ5_A': CDS_PINID='DQ5_A';
NET_NAME
'M_L_CPU0_SA_DQ<6>'
 '@T6G_MB_LIB.T6G(SCH_1):M_L_CPU0_SA_DQ'<6>:
 C_SIGNAL='@t6g_mb_lib.t6g(sch_1):m_l_cpu0_sa_dq(6)';
NODE_NAME     U25 K9
 '@T6G_MB_LIB.T6G(SCH_1):PAGE21_I159@PURE_QUANTA.GENOA_SP5(CHIPS)':
 'MLA_DATA6': CDS_PINID='MLA_DATA6';
NODE_NAME     J67 159
 '@T6G_MB_LIB.T6G(SCH_1):PAGE96_I22@PURE_QUANTA.SCONN288_DDR506112002KQ(CHIPS)':
 'DQ6_A': CDS_PINID='DQ6_A';
NET_NAME
'M_L_CPU0_SA_DQ<7>'
 '@T6G_MB_LIB.T6G(SCH_1):M_L_CPU0_SA_DQ'<7>:
 C_SIGNAL='@t6g_mb_lib.t6g(sch_1):m_l_cpu0_sa_dq(7)';
NODE_NAME     U25 L10
 '@T6G_MB_LIB.T6G(SCH_1):PAGE21_I159@PURE_QUANTA.GENOA_SP5(CHIPS)':
 'MLA_DATA7': CDS_PINID='MLA_DATA7';
NODE_NAME     J67 161
 '@T6G_MB_LIB.T6G(SCH_1):PAGE96_I22@PURE_QUANTA.SCONN288_DDR506112002KQ(CHIPS)':
 'DQ7_A': CDS_PINID='DQ7_A';
NET_NAME
'M_L_CPU0_SA_DQ<8>'
 '@T6G_MB_LIB.T6G(SCH_1):M_L_CPU0_SA_DQ'<8>:
 C_SIGNAL='@t6g_mb_lib.t6g(sch_1):m_l_cpu0_sa_dq(8)';
NODE_NAME     U25 L9
 '@T6G_MB_LIB.T6G(SCH_1):PAGE21_I159@PURE_QUANTA.GENOA_SP5(CHIPS)':
 'MLA_DATA8': CDS_PINID='MLA_DATA8';
NODE_NAME     J67 18
 '@T6G_MB_LIB.T6G(SCH_1):PAGE96_I22@PURE_QUANTA.SCONN288_DDR506112002KQ(CHIPS)':
 'DQ8_A': CDS_PINID='DQ8_A';
NET_NAME
'M_L_CPU0_SA_DQ<9>'
 '@T6G_MB_LIB.T6G(SCH_1):M_L_CPU0_SA_DQ'<9>:
 C_SIGNAL='@t6g_mb_lib.t6g(sch_1):m_l_cpu0_sa_dq(9)';
NODE_NAME     U25 M11
 '@T6G_MB_LIB.T6G(SCH_1):PAGE21_I159@PURE_QUANTA.GENOA_SP5(CHIPS)':
 'MLA_DATA9': CDS_PINID='MLA_DATA9';
NODE_NAME     J67 20
 '@T6G_MB_LIB.T6G(SCH_1):PAGE96_I22@PURE_QUANTA.SCONN288_DDR506112002KQ(CHIPS)':
 'DQ9_A': CDS_PINID='DQ9_A';
NET_NAME
'M_L_CPU0_SA_DQS_DN<0>'
 '@T6G_MB_LIB.T6G(SCH_1):M_L_CPU0_SA_DQS_DN'<0>:
 C_SIGNAL='@t6g_mb_lib.t6g(sch_1):m_l_cpu0_sa_dqs_dn(0)';
NODE_NAME     U25 H9
 '@T6G_MB_LIB.T6G(SCH_1):PAGE21_I159@PURE_QUANTA.GENOA_SP5(CHIPS)':
 'MLA_DQS_L0': CDS_PINID='MLA_DQS_L0';
NODE_NAME     J67 12
 '@T6G_MB_LIB.T6G(SCH_1):PAGE96_I236@PURE_QUANTA.SCONN288_DDR506112002KQ(CHIPS)':
 'DQS0_A_C': CDS_PINID='DQS0_A_C';
NET_NAME
'M_L_CPU0_SA_DQS_DN<1>'
 '@T6G_MB_LIB.T6G(SCH_1):M_L_CPU0_SA_DQS_DN'<1>:
 C_SIGNAL='@t6g_mb_lib.t6g(sch_1):m_l_cpu0_sa_dqs_dn(1)';
NODE_NAME     U25 P9
 '@T6G_MB_LIB.T6G(SCH_1):PAGE21_I159@PURE_QUANTA.GENOA_SP5(CHIPS)':
 'MLA_DQS_L1': CDS_PINID='MLA_DQS_L1';
NODE_NAME     J67 23
 '@T6G_MB_LIB.T6G(SCH_1):PAGE96_I236@PURE_QUANTA.SCONN288_DDR506112002KQ(CHIPS)':
 'DQS1_A_C': CDS_PINID='DQS1_A_C';
NET_NAME
'M_L_CPU0_SA_DQS_DN<2>'
 '@T6G_MB_LIB.T6G(SCH_1):M_L_CPU0_SA_DQS_DN'<2>:
 C_SIGNAL='@t6g_mb_lib.t6g(sch_1):m_l_cpu0_sa_dqs_dn(2)';
NODE_NAME     U25 Y9
 '@T6G_MB_LIB.T6G(SCH_1):PAGE21_I159@PURE_QUANTA.GENOA_SP5(CHIPS)':
 'MLA_DQS_L2': CDS_PINID='MLA_DQS_L2';
NODE_NAME     J67 34
 '@T6G_MB_LIB.T6G(SCH_1):PAGE96_I236@PURE_QUANTA.SCONN288_DDR506112002KQ(CHIPS)':
 'DQS2_A_C': CDS_PINID='DQS2_A_C';
NET_NAME
'M_L_CPU0_SA_DQS_DN<3>'
 '@T6G_MB_LIB.T6G(SCH_1):M_L_CPU0_SA_DQS_DN'<3>:
 C_SIGNAL='@t6g_mb_lib.t6g(sch_1):m_l_cpu0_sa_dqs_dn(3)';
NODE_NAME     U25 AF9
 '@T6G_MB_LIB.T6G(SCH_1):PAGE21_I159@PURE_QUANTA.GENOA_SP5(CHIPS)':
 'MLA_DQS_L3': CDS_PINID='MLA_DQS_L3';
NODE_NAME     J67 45
 '@T6G_MB_LIB.T6G(SCH_1):PAGE96_I236@PURE_QUANTA.SCONN288_DDR506112002KQ(CHIPS)':
 'DQS3_A_C': CDS_PINID='DQS3_A_C';
NET_NAME
'M_L_CPU0_SA_DQS_DN<4>'
 '@T6G_MB_LIB.T6G(SCH_1):M_L_CPU0_SA_DQS_DN'<4>:
 C_SIGNAL='@t6g_mb_lib.t6g(sch_1):m_l_cpu0_sa_dqs_dn(4)';
NODE_NAME     U25 AM9
 '@T6G_MB_LIB.T6G(SCH_1):PAGE21_I159@PURE_QUANTA.GENOA_SP5(CHIPS)':
 'MLA_DQS_L4': CDS_PINID='MLA_DQS_L4';
NODE_NAME     J67 56
 '@T6G_MB_LIB.T6G(SCH_1):PAGE96_I236@PURE_QUANTA.SCONN288_DDR506112002KQ(CHIPS)':
 'DQS4_A_C': CDS_PINID='DQS4_A_C';
NET_NAME
'M_L_CPU0_SA_DQS_DN<5>'
 '@T6G_MB_LIB.T6G(SCH_1):M_L_CPU0_SA_DQS_DN'<5>:
 C_SIGNAL='@t6g_mb_lib.t6g(sch_1):m_l_cpu0_sa_dqs_dn(5)';
NODE_NAME     U25 H11
 '@T6G_MB_LIB.T6G(SCH_1):PAGE21_I159@PURE_QUANTA.GENOA_SP5(CHIPS)':
 'MLA_DQS_L5': CDS_PINID='MLA_DQS_L5';
NODE_NAME     J67 156
 '@T6G_MB_LIB.T6G(SCH_1):PAGE96_I236@PURE_QUANTA.SCONN288_DDR506112002KQ(CHIPS)':
 'DQS5_A_C||TDQS5_A_C||DQS5_A_T||TDQS5_A_T': CDS_PINID='\dqs5_a_c||tdqs5_a_c||dqs5_a_t||tdqs5_a_t\';
NET_NAME
'M_L_CPU0_SA_DQS_DN<6>'
 '@T6G_MB_LIB.T6G(SCH_1):M_L_CPU0_SA_DQS_DN'<6>:
 C_SIGNAL='@t6g_mb_lib.t6g(sch_1):m_l_cpu0_sa_dqs_dn(6)';
NODE_NAME     U25 P11
 '@T6G_MB_LIB.T6G(SCH_1):PAGE21_I159@PURE_QUANTA.GENOA_SP5(CHIPS)':
 'MLA_DQS_L6': CDS_PINID='MLA_DQS_L6';
NODE_NAME     J67 167
 '@T6G_MB_LIB.T6G(SCH_1):PAGE96_I236@PURE_QUANTA.SCONN288_DDR506112002KQ(CHIPS)':
 'DQS6_A_C||TDQS6_A_C||DQS6_A_T||TDQS6_A_T': CDS_PINID='\dqs6_a_c||tdqs6_a_c||dqs6_a_t||tdqs6_a_t\';
NET_NAME
'M_L_CPU0_SA_DQS_DN<7>'
 '@T6G_MB_LIB.T6G(SCH_1):M_L_CPU0_SA_DQS_DN'<7>:
 C_SIGNAL='@t6g_mb_lib.t6g(sch_1):m_l_cpu0_sa_dqs_dn(7)';
NODE_NAME     U25 Y11
 '@T6G_MB_LIB.T6G(SCH_1):PAGE21_I159@PURE_QUANTA.GENOA_SP5(CHIPS)':
 'MLA_DQS_L7': CDS_PINID='MLA_DQS_L7';
NODE_NAME     J67 178
 '@T6G_MB_LIB.T6G(SCH_1):PAGE96_I236@PURE_QUANTA.SCONN288_DDR506112002KQ(CHIPS)':
 'DQS7_A_C||TDQS7_A_C': CDS_PINID='\dqs7_a_c||tdqs7_a_c\';
NET_NAME
'M_L_CPU0_SA_DQS_DN<8>'
 '@T6G_MB_LIB.T6G(SCH_1):M_L_CPU0_SA_DQS_DN'<8>:
 C_SIGNAL='@t6g_mb_lib.t6g(sch_1):m_l_cpu0_sa_dqs_dn(8)';
NODE_NAME     U25 AF11
 '@T6G_MB_LIB.T6G(SCH_1):PAGE21_I159@PURE_QUANTA.GENOA_SP5(CHIPS)':
 'MLA_DQS_L8': CDS_PINID='MLA_DQS_L8';
NODE_NAME     J67 189
 '@T6G_MB_LIB.T6G(SCH_1):PAGE96_I236@PURE_QUANTA.SCONN288_DDR506112002KQ(CHIPS)':
 'DQS8_A_C||TDQS8_A_C': CDS_PINID='\dqs8_a_c||tdqs8_a_c\';
NET_NAME
'M_L_CPU0_SA_DQS_DN<9>'
 '@T6G_MB_LIB.T6G(SCH_1):M_L_CPU0_SA_DQS_DN'<9>:
 C_SIGNAL='@t6g_mb_lib.t6g(sch_1):m_l_cpu0_sa_dqs_dn(9)';
NODE_NAME     U25 AM11
 '@T6G_MB_LIB.T6G(SCH_1):PAGE21_I159@PURE_QUANTA.GENOA_SP5(CHIPS)':
 'MLA_DQS_L9': CDS_PINID='MLA_DQS_L9';
NODE_NAME     J67 200
 '@T6G_MB_LIB.T6G(SCH_1):PAGE96_I236@PURE_QUANTA.SCONN288_DDR506112002KQ(CHIPS)':
 'DQS9_A_C||TDQS9_A_C': CDS_PINID='\dqs9_a_c||tdqs9_a_c\';
NET_NAME
'M_L_CPU0_SA_DQS_DP<0>'
 '@T6G_MB_LIB.T6G(SCH_1):M_L_CPU0_SA_DQS_DP'<0>:
 C_SIGNAL='@t6g_mb_lib.t6g(sch_1):m_l_cpu0_sa_dqs_dp(0)';
NODE_NAME     U25 G9
 '@T6G_MB_LIB.T6G(SCH_1):PAGE21_I159@PURE_QUANTA.GENOA_SP5(CHIPS)':
 'MLA_DQS_H0': CDS_PINID='MLA_DQS_H0';
NODE_NAME     J67 11
 '@T6G_MB_LIB.T6G(SCH_1):PAGE96_I236@PURE_QUANTA.SCONN288_DDR506112002KQ(CHIPS)':
 'DQS0_A_T': CDS_PINID='DQS0_A_T';
NET_NAME
'M_L_CPU0_SA_DQS_DP<1>'
 '@T6G_MB_LIB.T6G(SCH_1):M_L_CPU0_SA_DQS_DP'<1>:
 C_SIGNAL='@t6g_mb_lib.t6g(sch_1):m_l_cpu0_sa_dqs_dp(1)';
NODE_NAME     U25 N9
 '@T6G_MB_LIB.T6G(SCH_1):PAGE21_I159@PURE_QUANTA.GENOA_SP5(CHIPS)':
 'MLA_DQS_H1': CDS_PINID='MLA_DQS_H1';
NODE_NAME     J67 22
 '@T6G_MB_LIB.T6G(SCH_1):PAGE96_I236@PURE_QUANTA.SCONN288_DDR506112002KQ(CHIPS)':
 'DQS1_A_T': CDS_PINID='DQS1_A_T';
NET_NAME
'M_L_CPU0_SA_DQS_DP<2>'
 '@T6G_MB_LIB.T6G(SCH_1):M_L_CPU0_SA_DQS_DP'<2>:
 C_SIGNAL='@t6g_mb_lib.t6g(sch_1):m_l_cpu0_sa_dqs_dp(2)';
NODE_NAME     U25 W9
 '@T6G_MB_LIB.T6G(SCH_1):PAGE21_I159@PURE_QUANTA.GENOA_SP5(CHIPS)':
 'MLA_DQS_H2': CDS_PINID='MLA_DQS_H2';
NODE_NAME     J67 33
 '@T6G_MB_LIB.T6G(SCH_1):PAGE96_I236@PURE_QUANTA.SCONN288_DDR506112002KQ(CHIPS)':
 'DQS2_A_T': CDS_PINID='DQS2_A_T';
NET_NAME
'M_L_CPU0_SA_DQS_DP<3>'
 '@T6G_MB_LIB.T6G(SCH_1):M_L_CPU0_SA_DQS_DP'<3>:
 C_SIGNAL='@t6g_mb_lib.t6g(sch_1):m_l_cpu0_sa_dqs_dp(3)';
NODE_NAME     U25 AE9
 '@T6G_MB_LIB.T6G(SCH_1):PAGE21_I159@PURE_QUANTA.GENOA_SP5(CHIPS)':
 'MLA_DQS_H3': CDS_PINID='MLA_DQS_H3';
NODE_NAME     J67 44
 '@T6G_MB_LIB.T6G(SCH_1):PAGE96_I236@PURE_QUANTA.SCONN288_DDR506112002KQ(CHIPS)':
 'DQS3_A_T': CDS_PINID='DQS3_A_T';
NET_NAME
'M_L_CPU0_SA_DQS_DP<4>'
 '@T6G_MB_LIB.T6G(SCH_1):M_L_CPU0_SA_DQS_DP'<4>:
 C_SIGNAL='@t6g_mb_lib.t6g(sch_1):m_l_cpu0_sa_dqs_dp(4)';
NODE_NAME     U25 AL9
 '@T6G_MB_LIB.T6G(SCH_1):PAGE21_I159@PURE_QUANTA.GENOA_SP5(CHIPS)':
 'MLA_DQS_H4': CDS_PINID='MLA_DQS_H4';
NODE_NAME     J67 55
 '@T6G_MB_LIB.T6G(SCH_1):PAGE96_I236@PURE_QUANTA.SCONN288_DDR506112002KQ(CHIPS)':
 'DQS4_A_T': CDS_PINID='DQS4_A_T';
NET_NAME
'M_L_CPU0_SA_DQS_DP<5>'
 '@T6G_MB_LIB.T6G(SCH_1):M_L_CPU0_SA_DQS_DP'<5>:
 C_SIGNAL='@t6g_mb_lib.t6g(sch_1):m_l_cpu0_sa_dqs_dp(5)';
NODE_NAME     U25 J10
 '@T6G_MB_LIB.T6G(SCH_1):PAGE21_I159@PURE_QUANTA.GENOA_SP5(CHIPS)':
 'MLA_DQS_H5': CDS_PINID='MLA_DQS_H5';
NODE_NAME     J67 157
 '@T6G_MB_LIB.T6G(SCH_1):PAGE96_I236@PURE_QUANTA.SCONN288_DDR506112002KQ(CHIPS)':
 'DQS5_A_T||TDQS5_A_T': CDS_PINID='\dqs5_a_t||tdqs5_a_t\';
NET_NAME
'M_L_CPU0_SA_DQS_DP<6>'
 '@T6G_MB_LIB.T6G(SCH_1):M_L_CPU0_SA_DQS_DP'<6>:
 C_SIGNAL='@t6g_mb_lib.t6g(sch_1):m_l_cpu0_sa_dqs_dp(6)';
NODE_NAME     U25 R10
 '@T6G_MB_LIB.T6G(SCH_1):PAGE21_I159@PURE_QUANTA.GENOA_SP5(CHIPS)':
 'MLA_DQS_H6': CDS_PINID='MLA_DQS_H6';
NODE_NAME     J67 168
 '@T6G_MB_LIB.T6G(SCH_1):PAGE96_I236@PURE_QUANTA.SCONN288_DDR506112002KQ(CHIPS)':
 'DQS6_A_T||TDQS6_A_T': CDS_PINID='\dqs6_a_t||tdqs6_a_t\';
NET_NAME
'M_L_CPU0_SA_DQS_DP<7>'
 '@T6G_MB_LIB.T6G(SCH_1):M_L_CPU0_SA_DQS_DP'<7>:
 C_SIGNAL='@t6g_mb_lib.t6g(sch_1):m_l_cpu0_sa_dqs_dp(7)';
NODE_NAME     U25 AA10
 '@T6G_MB_LIB.T6G(SCH_1):PAGE21_I159@PURE_QUANTA.GENOA_SP5(CHIPS)':
 'MLA_DQS_H7': CDS_PINID='MLA_DQS_H7';
NODE_NAME     J67 179
 '@T6G_MB_LIB.T6G(SCH_1):PAGE96_I236@PURE_QUANTA.SCONN288_DDR506112002KQ(CHIPS)':
 'DQS7_A_T||TDQS7_A_T': CDS_PINID='\dqs7_a_t||tdqs7_a_t\';
NET_NAME
'M_L_CPU0_SA_DQS_DP<8>'
 '@T6G_MB_LIB.T6G(SCH_1):M_L_CPU0_SA_DQS_DP'<8>:
 C_SIGNAL='@t6g_mb_lib.t6g(sch_1):m_l_cpu0_sa_dqs_dp(8)';
NODE_NAME     U25 AG10
 '@T6G_MB_LIB.T6G(SCH_1):PAGE21_I159@PURE_QUANTA.GENOA_SP5(CHIPS)':
 'MLA_DQS_H8': CDS_PINID='MLA_DQS_H8';
NODE_NAME     J67 190
 '@T6G_MB_LIB.T6G(SCH_1):PAGE96_I236@PURE_QUANTA.SCONN288_DDR506112002KQ(CHIPS)':
 'DQS8_A_T||TDQS8_A_T': CDS_PINID='\dqs8_a_t||tdqs8_a_t\';
NET_NAME
'M_L_CPU0_SA_DQS_DP<9>'
 '@T6G_MB_LIB.T6G(SCH_1):M_L_CPU0_SA_DQS_DP'<9>:
 C_SIGNAL='@t6g_mb_lib.t6g(sch_1):m_l_cpu0_sa_dqs_dp(9)';
NODE_NAME     U25 AN10
 '@T6G_MB_LIB.T6G(SCH_1):PAGE21_I159@PURE_QUANTA.GENOA_SP5(CHIPS)':
 'MLA_DQS_H9': CDS_PINID='MLA_DQS_H9';
NODE_NAME     J67 201
 '@T6G_MB_LIB.T6G(SCH_1):PAGE96_I236@PURE_QUANTA.SCONN288_DDR506112002KQ(CHIPS)':
 'DQS9_A_T||TDQS9_A_T': CDS_PINID='\dqs9_a_t||tdqs9_a_t\';
NET_NAME
'M_L_CPU0_SA_PAR'
 '@T6G_MB_LIB.T6G(SCH_1):M_L_CPU0_SA_PAR':
 C_SIGNAL='@t6g_mb_lib.t6g(sch_1):m_l_cpu0_sa_par';
NODE_NAME     U25 BC10
 '@T6G_MB_LIB.T6G(SCH_1):PAGE21_I159@PURE_QUANTA.GENOA_SP5(CHIPS)':
 'MLA_PAR': CDS_PINID='MLA_PAR';
NODE_NAME     J67 74
 '@T6G_MB_LIB.T6G(SCH_1):PAGE96_I22@PURE_QUANTA.SCONN288_DDR506112002KQ(CHIPS)':
 'PAR_A': CDS_PINID='PAR_A';
NET_NAME
'M_L_CPU0_SA_RSP<0>'
 '@T6G_MB_LIB.T6G(SCH_1):M_L_CPU0_SA_RSP'<0>:
 C_SIGNAL='@t6g_mb_lib.t6g(sch_1):m_l_cpu0_sa_rsp(0)';
NODE_NAME     U25 BN10
 '@T6G_MB_LIB.T6G(SCH_1):PAGE21_I159@PURE_QUANTA.GENOA_SP5(CHIPS)':
 'MLA0_RSP_L': CDS_PINID='MLA0_RSP_L';
NODE_NAME     J67 86
 '@T6G_MB_LIB.T6G(SCH_1):PAGE96_I22@PURE_QUANTA.SCONN288_DDR506112002KQ(CHIPS)':
 'LBD||RSP_A_N': CDS_PINID='\lbd||rsp_a_n\';
NET_NAME
'M_L_CPU0_SB_CA<0>'
 '@T6G_MB_LIB.T6G(SCH_1):M_L_CPU0_SB_CA'<0>:
 C_SIGNAL='@t6g_mb_lib.t6g(sch_1):m_l_cpu0_sb_ca(0)';
NODE_NAME     U25 BG10
 '@T6G_MB_LIB.T6G(SCH_1):PAGE21_I159@PURE_QUANTA.GENOA_SP5(CHIPS)':
 'MLB_CA0': CDS_PINID='MLB_CA0';
NODE_NAME     J67 76
 '@T6G_MB_LIB.T6G(SCH_1):PAGE96_I22@PURE_QUANTA.SCONN288_DDR506112002KQ(CHIPS)':
 'CA0_B': CDS_PINID='CA0_B';
NET_NAME
'M_L_CPU0_SB_CA<1>'
 '@T6G_MB_LIB.T6G(SCH_1):M_L_CPU0_SB_CA'<1>:
 C_SIGNAL='@t6g_mb_lib.t6g(sch_1):m_l_cpu0_sb_ca(1)';
NODE_NAME     U25 BH11
 '@T6G_MB_LIB.T6G(SCH_1):PAGE21_I159@PURE_QUANTA.GENOA_SP5(CHIPS)':
 'MLB_CA1': CDS_PINID='MLB_CA1';
NODE_NAME     J67 221
 '@T6G_MB_LIB.T6G(SCH_1):PAGE96_I22@PURE_QUANTA.SCONN288_DDR506112002KQ(CHIPS)':
 'CA1_B': CDS_PINID='CA1_B';
NET_NAME
'M_L_CPU0_SB_CA<2>'
 '@T6G_MB_LIB.T6G(SCH_1):M_L_CPU0_SB_CA'<2>:
 C_SIGNAL='@t6g_mb_lib.t6g(sch_1):m_l_cpu0_sb_ca(2)';
NODE_NAME     U25 BH9
 '@T6G_MB_LIB.T6G(SCH_1):PAGE21_I159@PURE_QUANTA.GENOA_SP5(CHIPS)':
 'MLB_CA2': CDS_PINID='MLB_CA2';
NODE_NAME     J67 78
 '@T6G_MB_LIB.T6G(SCH_1):PAGE96_I22@PURE_QUANTA.SCONN288_DDR506112002KQ(CHIPS)':
 'CA2_B': CDS_PINID='CA2_B';
NET_NAME
'M_L_CPU0_SB_CA<3>'
 '@T6G_MB_LIB.T6G(SCH_1):M_L_CPU0_SB_CA'<3>:
 C_SIGNAL='@t6g_mb_lib.t6g(sch_1):m_l_cpu0_sb_ca(3)';
NODE_NAME     U25 BJ9
 '@T6G_MB_LIB.T6G(SCH_1):PAGE21_I159@PURE_QUANTA.GENOA_SP5(CHIPS)':
 'MLB_CA3': CDS_PINID='MLB_CA3';
NODE_NAME     J67 223
 '@T6G_MB_LIB.T6G(SCH_1):PAGE96_I22@PURE_QUANTA.SCONN288_DDR506112002KQ(CHIPS)':
 'CA3_B': CDS_PINID='CA3_B';
NET_NAME
'M_L_CPU0_SB_CA<4>'
 '@T6G_MB_LIB.T6G(SCH_1):M_L_CPU0_SB_CA'<4>:
 C_SIGNAL='@t6g_mb_lib.t6g(sch_1):m_l_cpu0_sb_ca(4)';
NODE_NAME     U25 BJ10
 '@T6G_MB_LIB.T6G(SCH_1):PAGE21_I159@PURE_QUANTA.GENOA_SP5(CHIPS)':
 'MLB_CA4': CDS_PINID='MLB_CA4';
NODE_NAME     J67 80
 '@T6G_MB_LIB.T6G(SCH_1):PAGE96_I22@PURE_QUANTA.SCONN288_DDR506112002KQ(CHIPS)':
 'CA4_B': CDS_PINID='CA4_B';
NET_NAME
'M_L_CPU0_SB_CA<5>'
 '@T6G_MB_LIB.T6G(SCH_1):M_L_CPU0_SB_CA'<5>:
 C_SIGNAL='@t6g_mb_lib.t6g(sch_1):m_l_cpu0_sb_ca(5)';
NODE_NAME     U25 BK11
 '@T6G_MB_LIB.T6G(SCH_1):PAGE21_I159@PURE_QUANTA.GENOA_SP5(CHIPS)':
 'MLB_CA5': CDS_PINID='MLB_CA5';
NODE_NAME     J67 225
 '@T6G_MB_LIB.T6G(SCH_1):PAGE96_I22@PURE_QUANTA.SCONN288_DDR506112002KQ(CHIPS)':
 'CA5_B': CDS_PINID='CA5_B';
NET_NAME
'M_L_CPU0_SB_CA<6>'
 '@T6G_MB_LIB.T6G(SCH_1):M_L_CPU0_SB_CA'<6>:
 C_SIGNAL='@t6g_mb_lib.t6g(sch_1):m_l_cpu0_sb_ca(6)';
NODE_NAME     U25 BK9
 '@T6G_MB_LIB.T6G(SCH_1):PAGE21_I159@PURE_QUANTA.GENOA_SP5(CHIPS)':
 'MLB_CA6': CDS_PINID='MLB_CA6';
NODE_NAME     J67 82
 '@T6G_MB_LIB.T6G(SCH_1):PAGE96_I22@PURE_QUANTA.SCONN288_DDR506112002KQ(CHIPS)':
 'CA6_B': CDS_PINID='CA6_B';
NET_NAME
'M_L_CPU0_SB_CB<0>'
 '@T6G_MB_LIB.T6G(SCH_1):M_L_CPU0_SB_CB'<0>:
 C_SIGNAL='@t6g_mb_lib.t6g(sch_1):m_l_cpu0_sb_cb(0)';
NODE_NAME     U25 BY9
 '@T6G_MB_LIB.T6G(SCH_1):PAGE21_I159@PURE_QUANTA.GENOA_SP5(CHIPS)':
 'MLB_CHECK0': CDS_PINID='MLB_CHECK0';
NODE_NAME     J67 96
 '@T6G_MB_LIB.T6G(SCH_1):PAGE96_I22@PURE_QUANTA.SCONN288_DDR506112002KQ(CHIPS)':
 'CB0_B': CDS_PINID='CB0_B';
NET_NAME
'M_L_CPU0_SB_CB<1>'
 '@T6G_MB_LIB.T6G(SCH_1):M_L_CPU0_SB_CB'<1>:
 C_SIGNAL='@t6g_mb_lib.t6g(sch_1):m_l_cpu0_sb_cb(1)';
NODE_NAME     U25 CA10
 '@T6G_MB_LIB.T6G(SCH_1):PAGE21_I159@PURE_QUANTA.GENOA_SP5(CHIPS)':
 'MLB_CHECK1': CDS_PINID='MLB_CHECK1';
NODE_NAME     J67 98
 '@T6G_MB_LIB.T6G(SCH_1):PAGE96_I22@PURE_QUANTA.SCONN288_DDR506112002KQ(CHIPS)':
 'CB1_B': CDS_PINID='CB1_B';
NET_NAME
'M_L_CPU0_SB_CB<2>'
 '@T6G_MB_LIB.T6G(SCH_1):M_L_CPU0_SB_CB'<2>:
 C_SIGNAL='@t6g_mb_lib.t6g(sch_1):m_l_cpu0_sb_cb(2)';
NODE_NAME     U25 CA9
 '@T6G_MB_LIB.T6G(SCH_1):PAGE21_I159@PURE_QUANTA.GENOA_SP5(CHIPS)':
 'MLB_CHECK2': CDS_PINID='MLB_CHECK2';
NODE_NAME     J67 241
 '@T6G_MB_LIB.T6G(SCH_1):PAGE96_I22@PURE_QUANTA.SCONN288_DDR506112002KQ(CHIPS)':
 'CB2_B': CDS_PINID='CB2_B';
NET_NAME
'M_L_CPU0_SB_CB<3>'
 '@T6G_MB_LIB.T6G(SCH_1):M_L_CPU0_SB_CB'<3>:
 C_SIGNAL='@t6g_mb_lib.t6g(sch_1):m_l_cpu0_sb_cb(3)';
NODE_NAME     U25 CB11
 '@T6G_MB_LIB.T6G(SCH_1):PAGE21_I159@PURE_QUANTA.GENOA_SP5(CHIPS)':
 'MLB_CHECK3': CDS_PINID='MLB_CHECK3';
NODE_NAME     J67 243
 '@T6G_MB_LIB.T6G(SCH_1):PAGE96_I22@PURE_QUANTA.SCONN288_DDR506112002KQ(CHIPS)':
 'CB3_B': CDS_PINID='CB3_B';
NET_NAME
'M_L_CPU0_SB_CB<4>'
 '@T6G_MB_LIB.T6G(SCH_1):M_L_CPU0_SB_CB'<4>:
 C_SIGNAL='@t6g_mb_lib.t6g(sch_1):m_l_cpu0_sb_cb(4)';
NODE_NAME     U25 BT9
 '@T6G_MB_LIB.T6G(SCH_1):PAGE21_I159@PURE_QUANTA.GENOA_SP5(CHIPS)':
 'MLB_CHECK4': CDS_PINID='MLB_CHECK4';
NODE_NAME     J67 89
 '@T6G_MB_LIB.T6G(SCH_1):PAGE96_I22@PURE_QUANTA.SCONN288_DDR506112002KQ(CHIPS)':
 'CB4_B': CDS_PINID='CB4_B';
NET_NAME
'M_L_CPU0_SB_CB<5>'
 '@T6G_MB_LIB.T6G(SCH_1):M_L_CPU0_SB_CB'<5>:
 C_SIGNAL='@t6g_mb_lib.t6g(sch_1):m_l_cpu0_sb_cb(5)';
NODE_NAME     U25 BU10
 '@T6G_MB_LIB.T6G(SCH_1):PAGE21_I159@PURE_QUANTA.GENOA_SP5(CHIPS)':
 'MLB_CHECK5': CDS_PINID='MLB_CHECK5';
NODE_NAME     J67 91
 '@T6G_MB_LIB.T6G(SCH_1):PAGE96_I22@PURE_QUANTA.SCONN288_DDR506112002KQ(CHIPS)':
 'CB5_B': CDS_PINID='CB5_B';
NET_NAME
'M_L_CPU0_SB_CB<6>'
 '@T6G_MB_LIB.T6G(SCH_1):M_L_CPU0_SB_CB'<6>:
 C_SIGNAL='@t6g_mb_lib.t6g(sch_1):m_l_cpu0_sb_cb(6)';
NODE_NAME     U25 BU9
 '@T6G_MB_LIB.T6G(SCH_1):PAGE21_I159@PURE_QUANTA.GENOA_SP5(CHIPS)':
 'MLB_CHECK6': CDS_PINID='MLB_CHECK6';
NODE_NAME     J67 234
 '@T6G_MB_LIB.T6G(SCH_1):PAGE96_I22@PURE_QUANTA.SCONN288_DDR506112002KQ(CHIPS)':
 'CB6_B': CDS_PINID='CB6_B';
NET_NAME
'M_L_CPU0_SB_CB<7>'
 '@T6G_MB_LIB.T6G(SCH_1):M_L_CPU0_SB_CB'<7>:
 C_SIGNAL='@t6g_mb_lib.t6g(sch_1):m_l_cpu0_sb_cb(7)';
NODE_NAME     U25 BV11
 '@T6G_MB_LIB.T6G(SCH_1):PAGE21_I159@PURE_QUANTA.GENOA_SP5(CHIPS)':
 'MLB_CHECK7': CDS_PINID='MLB_CHECK7';
NODE_NAME     J67 236
 '@T6G_MB_LIB.T6G(SCH_1):PAGE96_I22@PURE_QUANTA.SCONN288_DDR506112002KQ(CHIPS)':
 'CB7_B': CDS_PINID='CB7_B';
NET_NAME
'M_L_CPU0_SB_CS_N<0>'
 '@T6G_MB_LIB.T6G(SCH_1):M_L_CPU0_SB_CS_N'<0>:
 C_SIGNAL='@t6g_mb_lib.t6g(sch_1):m_l_cpu0_sb_cs_n(0)';
NODE_NAME     U25 BM11
 '@T6G_MB_LIB.T6G(SCH_1):PAGE21_I159@PURE_QUANTA.GENOA_SP5(CHIPS)':
 'MLB0_CS_L0': CDS_PINID='MLB0_CS_L0';
NODE_NAME     J67 84
 '@T6G_MB_LIB.T6G(SCH_1):PAGE96_I22@PURE_QUANTA.SCONN288_DDR506112002KQ(CHIPS)':
 'CS0_B_N': CDS_PINID='CS0_B_N';
NET_NAME
'M_L_CPU0_SB_CS_N<1>'
 '@T6G_MB_LIB.T6G(SCH_1):M_L_CPU0_SB_CS_N'<1>:
 C_SIGNAL='@t6g_mb_lib.t6g(sch_1):m_l_cpu0_sb_cs_n(1)';
NODE_NAME     U25 BN9
 '@T6G_MB_LIB.T6G(SCH_1):PAGE21_I159@PURE_QUANTA.GENOA_SP5(CHIPS)':
 'MLB0_CS_L1': CDS_PINID='MLB0_CS_L1';
NODE_NAME     J67 229
 '@T6G_MB_LIB.T6G(SCH_1):PAGE96_I22@PURE_QUANTA.SCONN288_DDR506112002KQ(CHIPS)':
 'CS1_B_N': CDS_PINID='CS1_B_N';
NET_NAME
'M_L_CPU0_SB_DQ<0>'
 '@T6G_MB_LIB.T6G(SCH_1):M_L_CPU0_SB_DQ'<0>:
 C_SIGNAL='@t6g_mb_lib.t6g(sch_1):m_l_cpu0_sb_dq(0)';
NODE_NAME     U25 CB9
 '@T6G_MB_LIB.T6G(SCH_1):PAGE21_I159@PURE_QUANTA.GENOA_SP5(CHIPS)':
 'MLB_DATA0': CDS_PINID='MLB_DATA0';
NODE_NAME     J67 100
 '@T6G_MB_LIB.T6G(SCH_1):PAGE96_I22@PURE_QUANTA.SCONN288_DDR506112002KQ(CHIPS)':
 'DQ0_B': CDS_PINID='DQ0_B';
NET_NAME
'M_L_CPU0_SB_DQ<10>'
 '@T6G_MB_LIB.T6G(SCH_1):M_L_CPU0_SB_DQ'<10>:
 C_SIGNAL='@t6g_mb_lib.t6g(sch_1):m_l_cpu0_sb_dq(10)';
NODE_NAME     U25 CJ9
 '@T6G_MB_LIB.T6G(SCH_1):PAGE21_I159@PURE_QUANTA.GENOA_SP5(CHIPS)':
 'MLB_DATA10': CDS_PINID='MLB_DATA10';
NODE_NAME     J67 256
 '@T6G_MB_LIB.T6G(SCH_1):PAGE96_I22@PURE_QUANTA.SCONN288_DDR506112002KQ(CHIPS)':
 'DQ10_B': CDS_PINID='DQ10_B';
NET_NAME
'M_L_CPU0_SB_DQ<11>'
 '@T6G_MB_LIB.T6G(SCH_1):M_L_CPU0_SB_DQ'<11>:
 C_SIGNAL='@t6g_mb_lib.t6g(sch_1):m_l_cpu0_sb_dq(11)';
NODE_NAME     U25 CK11
 '@T6G_MB_LIB.T6G(SCH_1):PAGE21_I159@PURE_QUANTA.GENOA_SP5(CHIPS)':
 'MLB_DATA11': CDS_PINID='MLB_DATA11';
NODE_NAME     J67 258
 '@T6G_MB_LIB.T6G(SCH_1):PAGE96_I22@PURE_QUANTA.SCONN288_DDR506112002KQ(CHIPS)':
 'DQ11_B': CDS_PINID='DQ11_B';
NET_NAME
'M_L_CPU0_SB_DQ<12>'
 '@T6G_MB_LIB.T6G(SCH_1):M_L_CPU0_SB_DQ'<12>:
 C_SIGNAL='@t6g_mb_lib.t6g(sch_1):m_l_cpu0_sb_dq(12)';
NODE_NAME     U25 CM9
 '@T6G_MB_LIB.T6G(SCH_1):PAGE21_I159@PURE_QUANTA.GENOA_SP5(CHIPS)':
 'MLB_DATA12': CDS_PINID='MLB_DATA12';
NODE_NAME     J67 118
 '@T6G_MB_LIB.T6G(SCH_1):PAGE96_I22@PURE_QUANTA.SCONN288_DDR506112002KQ(CHIPS)':
 'DQ12_B': CDS_PINID='DQ12_B';
NET_NAME
'M_L_CPU0_SB_DQ<13>'
 '@T6G_MB_LIB.T6G(SCH_1):M_L_CPU0_SB_DQ'<13>:
 C_SIGNAL='@t6g_mb_lib.t6g(sch_1):m_l_cpu0_sb_dq(13)';
NODE_NAME     U25 CN10
 '@T6G_MB_LIB.T6G(SCH_1):PAGE21_I159@PURE_QUANTA.GENOA_SP5(CHIPS)':
 'MLB_DATA13': CDS_PINID='MLB_DATA13';
NODE_NAME     J67 120
 '@T6G_MB_LIB.T6G(SCH_1):PAGE96_I22@PURE_QUANTA.SCONN288_DDR506112002KQ(CHIPS)':
 'DQ13_B': CDS_PINID='DQ13_B';
NET_NAME
'M_L_CPU0_SB_DQ<14>'
 '@T6G_MB_LIB.T6G(SCH_1):M_L_CPU0_SB_DQ'<14>:
 C_SIGNAL='@t6g_mb_lib.t6g(sch_1):m_l_cpu0_sb_dq(14)';
NODE_NAME     U25 CN9
 '@T6G_MB_LIB.T6G(SCH_1):PAGE21_I159@PURE_QUANTA.GENOA_SP5(CHIPS)':
 'MLB_DATA14': CDS_PINID='MLB_DATA14';
NODE_NAME     J67 263
 '@T6G_MB_LIB.T6G(SCH_1):PAGE96_I22@PURE_QUANTA.SCONN288_DDR506112002KQ(CHIPS)':
 'DQ14_B': CDS_PINID='DQ14_B';
NET_NAME
'M_L_CPU0_SB_DQ<15>'
 '@T6G_MB_LIB.T6G(SCH_1):M_L_CPU0_SB_DQ'<15>:
 C_SIGNAL='@t6g_mb_lib.t6g(sch_1):m_l_cpu0_sb_dq(15)';
NODE_NAME     U25 CP11
 '@T6G_MB_LIB.T6G(SCH_1):PAGE21_I159@PURE_QUANTA.GENOA_SP5(CHIPS)':
 'MLB_DATA15': CDS_PINID='MLB_DATA15';
NODE_NAME     J67 265
 '@T6G_MB_LIB.T6G(SCH_1):PAGE96_I22@PURE_QUANTA.SCONN288_DDR506112002KQ(CHIPS)':
 'DQ15_B': CDS_PINID='DQ15_B';
NET_NAME
'M_L_CPU0_SB_DQ<16>'
 '@T6G_MB_LIB.T6G(SCH_1):M_L_CPU0_SB_DQ'<16>:
 C_SIGNAL='@t6g_mb_lib.t6g(sch_1):m_l_cpu0_sb_dq(16)';
NODE_NAME     U25 CP9
 '@T6G_MB_LIB.T6G(SCH_1):PAGE21_I159@PURE_QUANTA.GENOA_SP5(CHIPS)':
 'MLB_DATA16': CDS_PINID='MLB_DATA16';
NODE_NAME     J67 122
 '@T6G_MB_LIB.T6G(SCH_1):PAGE96_I22@PURE_QUANTA.SCONN288_DDR506112002KQ(CHIPS)':
 'DQ16_B': CDS_PINID='DQ16_B';
NET_NAME
'M_L_CPU0_SB_DQ<17>'
 '@T6G_MB_LIB.T6G(SCH_1):M_L_CPU0_SB_DQ'<17>:
 C_SIGNAL='@t6g_mb_lib.t6g(sch_1):m_l_cpu0_sb_dq(17)';
NODE_NAME     U25 CR10
 '@T6G_MB_LIB.T6G(SCH_1):PAGE21_I159@PURE_QUANTA.GENOA_SP5(CHIPS)':
 'MLB_DATA17': CDS_PINID='MLB_DATA17';
NODE_NAME     J67 124
 '@T6G_MB_LIB.T6G(SCH_1):PAGE96_I22@PURE_QUANTA.SCONN288_DDR506112002KQ(CHIPS)':
 'DQ17_B': CDS_PINID='DQ17_B';
NET_NAME
'M_L_CPU0_SB_DQ<18>'
 '@T6G_MB_LIB.T6G(SCH_1):M_L_CPU0_SB_DQ'<18>:
 C_SIGNAL='@t6g_mb_lib.t6g(sch_1):m_l_cpu0_sb_dq(18)';
NODE_NAME     U25 CR9
 '@T6G_MB_LIB.T6G(SCH_1):PAGE21_I159@PURE_QUANTA.GENOA_SP5(CHIPS)':
 'MLB_DATA18': CDS_PINID='MLB_DATA18';
NODE_NAME     J67 267
 '@T6G_MB_LIB.T6G(SCH_1):PAGE96_I22@PURE_QUANTA.SCONN288_DDR506112002KQ(CHIPS)':
 'DQ18_B': CDS_PINID='DQ18_B';
NET_NAME
'M_L_CPU0_SB_DQ<19>'
 '@T6G_MB_LIB.T6G(SCH_1):M_L_CPU0_SB_DQ'<19>:
 C_SIGNAL='@t6g_mb_lib.t6g(sch_1):m_l_cpu0_sb_dq(19)';
NODE_NAME     U25 CT11
 '@T6G_MB_LIB.T6G(SCH_1):PAGE21_I159@PURE_QUANTA.GENOA_SP5(CHIPS)':
 'MLB_DATA19': CDS_PINID='MLB_DATA19';
NODE_NAME     J67 269
 '@T6G_MB_LIB.T6G(SCH_1):PAGE96_I22@PURE_QUANTA.SCONN288_DDR506112002KQ(CHIPS)':
 'DQ19_B': CDS_PINID='DQ19_B';
NET_NAME
'M_L_CPU0_SB_DQ<1>'
 '@T6G_MB_LIB.T6G(SCH_1):M_L_CPU0_SB_DQ'<1>:
 C_SIGNAL='@t6g_mb_lib.t6g(sch_1):m_l_cpu0_sb_dq(1)';
NODE_NAME     U25 CC10
 '@T6G_MB_LIB.T6G(SCH_1):PAGE21_I159@PURE_QUANTA.GENOA_SP5(CHIPS)':
 'MLB_DATA1': CDS_PINID='MLB_DATA1';
NODE_NAME     J67 102
 '@T6G_MB_LIB.T6G(SCH_1):PAGE96_I22@PURE_QUANTA.SCONN288_DDR506112002KQ(CHIPS)':
 'DQ1_B': CDS_PINID='DQ1_B';
NET_NAME
'M_L_CPU0_SB_DQ<20>'
 '@T6G_MB_LIB.T6G(SCH_1):M_L_CPU0_SB_DQ'<20>:
 C_SIGNAL='@t6g_mb_lib.t6g(sch_1):m_l_cpu0_sb_dq(20)';
NODE_NAME     U25 CV9
 '@T6G_MB_LIB.T6G(SCH_1):PAGE21_I159@PURE_QUANTA.GENOA_SP5(CHIPS)':
 'MLB_DATA20': CDS_PINID='MLB_DATA20';
NODE_NAME     J67 129
 '@T6G_MB_LIB.T6G(SCH_1):PAGE96_I22@PURE_QUANTA.SCONN288_DDR506112002KQ(CHIPS)':
 'DQ20_B': CDS_PINID='DQ20_B';
NET_NAME
'M_L_CPU0_SB_DQ<21>'
 '@T6G_MB_LIB.T6G(SCH_1):M_L_CPU0_SB_DQ'<21>:
 C_SIGNAL='@t6g_mb_lib.t6g(sch_1):m_l_cpu0_sb_dq(21)';
NODE_NAME     U25 CW10
 '@T6G_MB_LIB.T6G(SCH_1):PAGE21_I159@PURE_QUANTA.GENOA_SP5(CHIPS)':
 'MLB_DATA21': CDS_PINID='MLB_DATA21';
NODE_NAME     J67 131
 '@T6G_MB_LIB.T6G(SCH_1):PAGE96_I22@PURE_QUANTA.SCONN288_DDR506112002KQ(CHIPS)':
 'DQ21_B': CDS_PINID='DQ21_B';
NET_NAME
'M_L_CPU0_SB_DQ<22>'
 '@T6G_MB_LIB.T6G(SCH_1):M_L_CPU0_SB_DQ'<22>:
 C_SIGNAL='@t6g_mb_lib.t6g(sch_1):m_l_cpu0_sb_dq(22)';
NODE_NAME     U25 CW9
 '@T6G_MB_LIB.T6G(SCH_1):PAGE21_I159@PURE_QUANTA.GENOA_SP5(CHIPS)':
 'MLB_DATA22': CDS_PINID='MLB_DATA22';
NODE_NAME     J67 274
 '@T6G_MB_LIB.T6G(SCH_1):PAGE96_I22@PURE_QUANTA.SCONN288_DDR506112002KQ(CHIPS)':
 'DQ22_B': CDS_PINID='DQ22_B';
NET_NAME
'M_L_CPU0_SB_DQ<23>'
 '@T6G_MB_LIB.T6G(SCH_1):M_L_CPU0_SB_DQ'<23>:
 C_SIGNAL='@t6g_mb_lib.t6g(sch_1):m_l_cpu0_sb_dq(23)';
NODE_NAME     U25 CY11
 '@T6G_MB_LIB.T6G(SCH_1):PAGE21_I159@PURE_QUANTA.GENOA_SP5(CHIPS)':
 'MLB_DATA23': CDS_PINID='MLB_DATA23';
NODE_NAME     J67 276
 '@T6G_MB_LIB.T6G(SCH_1):PAGE96_I22@PURE_QUANTA.SCONN288_DDR506112002KQ(CHIPS)':
 'DQ23_B': CDS_PINID='DQ23_B';
NET_NAME
'M_L_CPU0_SB_DQ<24>'
 '@T6G_MB_LIB.T6G(SCH_1):M_L_CPU0_SB_DQ'<24>:
 C_SIGNAL='@t6g_mb_lib.t6g(sch_1):m_l_cpu0_sb_dq(24)';
NODE_NAME     U25 CY9
 '@T6G_MB_LIB.T6G(SCH_1):PAGE21_I159@PURE_QUANTA.GENOA_SP5(CHIPS)':
 'MLB_DATA24': CDS_PINID='MLB_DATA24';
NODE_NAME     J67 133
 '@T6G_MB_LIB.T6G(SCH_1):PAGE96_I22@PURE_QUANTA.SCONN288_DDR506112002KQ(CHIPS)':
 'DQ24_B': CDS_PINID='DQ24_B';
NET_NAME
'M_L_CPU0_SB_DQ<25>'
 '@T6G_MB_LIB.T6G(SCH_1):M_L_CPU0_SB_DQ'<25>:
 C_SIGNAL='@t6g_mb_lib.t6g(sch_1):m_l_cpu0_sb_dq(25)';
NODE_NAME     U25 DA10
 '@T6G_MB_LIB.T6G(SCH_1):PAGE21_I159@PURE_QUANTA.GENOA_SP5(CHIPS)':
 'MLB_DATA25': CDS_PINID='MLB_DATA25';
NODE_NAME     J67 135
 '@T6G_MB_LIB.T6G(SCH_1):PAGE96_I22@PURE_QUANTA.SCONN288_DDR506112002KQ(CHIPS)':
 'DQ25_B': CDS_PINID='DQ25_B';
NET_NAME
'M_L_CPU0_SB_DQ<26>'
 '@T6G_MB_LIB.T6G(SCH_1):M_L_CPU0_SB_DQ'<26>:
 C_SIGNAL='@t6g_mb_lib.t6g(sch_1):m_l_cpu0_sb_dq(26)';
NODE_NAME     U25 DA9
 '@T6G_MB_LIB.T6G(SCH_1):PAGE21_I159@PURE_QUANTA.GENOA_SP5(CHIPS)':
 'MLB_DATA26': CDS_PINID='MLB_DATA26';
NODE_NAME     J67 278
 '@T6G_MB_LIB.T6G(SCH_1):PAGE96_I22@PURE_QUANTA.SCONN288_DDR506112002KQ(CHIPS)':
 'DQ26_B': CDS_PINID='DQ26_B';
NET_NAME
'M_L_CPU0_SB_DQ<27>'
 '@T6G_MB_LIB.T6G(SCH_1):M_L_CPU0_SB_DQ'<27>:
 C_SIGNAL='@t6g_mb_lib.t6g(sch_1):m_l_cpu0_sb_dq(27)';
NODE_NAME     U25 DB11
 '@T6G_MB_LIB.T6G(SCH_1):PAGE21_I159@PURE_QUANTA.GENOA_SP5(CHIPS)':
 'MLB_DATA27': CDS_PINID='MLB_DATA27';
NODE_NAME     J67 280
 '@T6G_MB_LIB.T6G(SCH_1):PAGE96_I22@PURE_QUANTA.SCONN288_DDR506112002KQ(CHIPS)':
 'DQ27_B': CDS_PINID='DQ27_B';
NET_NAME
'M_L_CPU0_SB_DQ<28>'
 '@T6G_MB_LIB.T6G(SCH_1):M_L_CPU0_SB_DQ'<28>:
 C_SIGNAL='@t6g_mb_lib.t6g(sch_1):m_l_cpu0_sb_dq(28)';
NODE_NAME     U25 DD9
 '@T6G_MB_LIB.T6G(SCH_1):PAGE21_I159@PURE_QUANTA.GENOA_SP5(CHIPS)':
 'MLB_DATA28': CDS_PINID='MLB_DATA28';
NODE_NAME     J67 140
 '@T6G_MB_LIB.T6G(SCH_1):PAGE96_I22@PURE_QUANTA.SCONN288_DDR506112002KQ(CHIPS)':
 'DQ28_B': CDS_PINID='DQ28_B';
NET_NAME
'M_L_CPU0_SB_DQ<29>'
 '@T6G_MB_LIB.T6G(SCH_1):M_L_CPU0_SB_DQ'<29>:
 C_SIGNAL='@t6g_mb_lib.t6g(sch_1):m_l_cpu0_sb_dq(29)';
NODE_NAME     U25 DE10
 '@T6G_MB_LIB.T6G(SCH_1):PAGE21_I159@PURE_QUANTA.GENOA_SP5(CHIPS)':
 'MLB_DATA29': CDS_PINID='MLB_DATA29';
NODE_NAME     J67 142
 '@T6G_MB_LIB.T6G(SCH_1):PAGE96_I22@PURE_QUANTA.SCONN288_DDR506112002KQ(CHIPS)':
 'DQ29_B': CDS_PINID='DQ29_B';
NET_NAME
'M_L_CPU0_SB_DQ<2>'
 '@T6G_MB_LIB.T6G(SCH_1):M_L_CPU0_SB_DQ'<2>:
 C_SIGNAL='@t6g_mb_lib.t6g(sch_1):m_l_cpu0_sb_dq(2)';
NODE_NAME     U25 CC9
 '@T6G_MB_LIB.T6G(SCH_1):PAGE21_I159@PURE_QUANTA.GENOA_SP5(CHIPS)':
 'MLB_DATA2': CDS_PINID='MLB_DATA2';
NODE_NAME     J67 245
 '@T6G_MB_LIB.T6G(SCH_1):PAGE96_I22@PURE_QUANTA.SCONN288_DDR506112002KQ(CHIPS)':
 'DQ2_B': CDS_PINID='DQ2_B';
NET_NAME
'M_L_CPU0_SB_DQ<30>'
 '@T6G_MB_LIB.T6G(SCH_1):M_L_CPU0_SB_DQ'<30>:
 C_SIGNAL='@t6g_mb_lib.t6g(sch_1):m_l_cpu0_sb_dq(30)';
NODE_NAME     U25 DE9
 '@T6G_MB_LIB.T6G(SCH_1):PAGE21_I159@PURE_QUANTA.GENOA_SP5(CHIPS)':
 'MLB_DATA30': CDS_PINID='MLB_DATA30';
NODE_NAME     J67 285
 '@T6G_MB_LIB.T6G(SCH_1):PAGE96_I22@PURE_QUANTA.SCONN288_DDR506112002KQ(CHIPS)':
 'DQ30_B': CDS_PINID='DQ30_B';
NET_NAME
'M_L_CPU0_SB_DQ<31>'
 '@T6G_MB_LIB.T6G(SCH_1):M_L_CPU0_SB_DQ'<31>:
 C_SIGNAL='@t6g_mb_lib.t6g(sch_1):m_l_cpu0_sb_dq(31)';
NODE_NAME     U25 DF9
 '@T6G_MB_LIB.T6G(SCH_1):PAGE21_I159@PURE_QUANTA.GENOA_SP5(CHIPS)':
 'MLB_DATA31': CDS_PINID='MLB_DATA31';
NODE_NAME     J67 287
 '@T6G_MB_LIB.T6G(SCH_1):PAGE96_I22@PURE_QUANTA.SCONN288_DDR506112002KQ(CHIPS)':
 'DQ31_B': CDS_PINID='DQ31_B';
NET_NAME
'M_L_CPU0_SB_DQ<3>'
 '@T6G_MB_LIB.T6G(SCH_1):M_L_CPU0_SB_DQ'<3>:
 C_SIGNAL='@t6g_mb_lib.t6g(sch_1):m_l_cpu0_sb_dq(3)';
NODE_NAME     U25 CD11
 '@T6G_MB_LIB.T6G(SCH_1):PAGE21_I159@PURE_QUANTA.GENOA_SP5(CHIPS)':
 'MLB_DATA3': CDS_PINID='MLB_DATA3';
NODE_NAME     J67 247
 '@T6G_MB_LIB.T6G(SCH_1):PAGE96_I22@PURE_QUANTA.SCONN288_DDR506112002KQ(CHIPS)':
 'DQ3_B': CDS_PINID='DQ3_B';
NET_NAME
'M_L_CPU0_SB_DQ<4>'
 '@T6G_MB_LIB.T6G(SCH_1):M_L_CPU0_SB_DQ'<4>:
 C_SIGNAL='@t6g_mb_lib.t6g(sch_1):m_l_cpu0_sb_dq(4)';
NODE_NAME     U25 CF9
 '@T6G_MB_LIB.T6G(SCH_1):PAGE21_I159@PURE_QUANTA.GENOA_SP5(CHIPS)':
 'MLB_DATA4': CDS_PINID='MLB_DATA4';
NODE_NAME     J67 107
 '@T6G_MB_LIB.T6G(SCH_1):PAGE96_I22@PURE_QUANTA.SCONN288_DDR506112002KQ(CHIPS)':
 'DQ4_B': CDS_PINID='DQ4_B';
NET_NAME
'M_L_CPU0_SB_DQ<5>'
 '@T6G_MB_LIB.T6G(SCH_1):M_L_CPU0_SB_DQ'<5>:
 C_SIGNAL='@t6g_mb_lib.t6g(sch_1):m_l_cpu0_sb_dq(5)';
NODE_NAME     U25 CG10
 '@T6G_MB_LIB.T6G(SCH_1):PAGE21_I159@PURE_QUANTA.GENOA_SP5(CHIPS)':
 'MLB_DATA5': CDS_PINID='MLB_DATA5';
NODE_NAME     J67 109
 '@T6G_MB_LIB.T6G(SCH_1):PAGE96_I22@PURE_QUANTA.SCONN288_DDR506112002KQ(CHIPS)':
 'DQ5_B': CDS_PINID='DQ5_B';
NET_NAME
'M_L_CPU0_SB_DQ<6>'
 '@T6G_MB_LIB.T6G(SCH_1):M_L_CPU0_SB_DQ'<6>:
 C_SIGNAL='@t6g_mb_lib.t6g(sch_1):m_l_cpu0_sb_dq(6)';
NODE_NAME     U25 CG9
 '@T6G_MB_LIB.T6G(SCH_1):PAGE21_I159@PURE_QUANTA.GENOA_SP5(CHIPS)':
 'MLB_DATA6': CDS_PINID='MLB_DATA6';
NODE_NAME     J67 252
 '@T6G_MB_LIB.T6G(SCH_1):PAGE96_I22@PURE_QUANTA.SCONN288_DDR506112002KQ(CHIPS)':
 'DQ6_B': CDS_PINID='DQ6_B';
NET_NAME
'M_L_CPU0_SB_DQ<7>'
 '@T6G_MB_LIB.T6G(SCH_1):M_L_CPU0_SB_DQ'<7>:
 C_SIGNAL='@t6g_mb_lib.t6g(sch_1):m_l_cpu0_sb_dq(7)';
NODE_NAME     U25 CH11
 '@T6G_MB_LIB.T6G(SCH_1):PAGE21_I159@PURE_QUANTA.GENOA_SP5(CHIPS)':
 'MLB_DATA7': CDS_PINID='MLB_DATA7';
NODE_NAME     J67 254
 '@T6G_MB_LIB.T6G(SCH_1):PAGE96_I22@PURE_QUANTA.SCONN288_DDR506112002KQ(CHIPS)':
 'DQ7_B': CDS_PINID='DQ7_B';
NET_NAME
'M_L_CPU0_SB_DQ<8>'
 '@T6G_MB_LIB.T6G(SCH_1):M_L_CPU0_SB_DQ'<8>:
 C_SIGNAL='@t6g_mb_lib.t6g(sch_1):m_l_cpu0_sb_dq(8)';
NODE_NAME     U25 CH9
 '@T6G_MB_LIB.T6G(SCH_1):PAGE21_I159@PURE_QUANTA.GENOA_SP5(CHIPS)':
 'MLB_DATA8': CDS_PINID='MLB_DATA8';
NODE_NAME     J67 111
 '@T6G_MB_LIB.T6G(SCH_1):PAGE96_I22@PURE_QUANTA.SCONN288_DDR506112002KQ(CHIPS)':
 'DQ8_B': CDS_PINID='DQ8_B';
NET_NAME
'M_L_CPU0_SB_DQ<9>'
 '@T6G_MB_LIB.T6G(SCH_1):M_L_CPU0_SB_DQ'<9>:
 C_SIGNAL='@t6g_mb_lib.t6g(sch_1):m_l_cpu0_sb_dq(9)';
NODE_NAME     U25 CJ10
 '@T6G_MB_LIB.T6G(SCH_1):PAGE21_I159@PURE_QUANTA.GENOA_SP5(CHIPS)':
 'MLB_DATA9': CDS_PINID='MLB_DATA9';
NODE_NAME     J67 113
 '@T6G_MB_LIB.T6G(SCH_1):PAGE96_I22@PURE_QUANTA.SCONN288_DDR506112002KQ(CHIPS)':
 'DQ9_B': CDS_PINID='DQ9_B';
NET_NAME
'M_L_CPU0_SB_DQS_DN<0>'
 '@T6G_MB_LIB.T6G(SCH_1):M_L_CPU0_SB_DQS_DN'<0>:
 C_SIGNAL='@t6g_mb_lib.t6g(sch_1):m_l_cpu0_sb_dqs_dn(0)';
NODE_NAME     U25 CE9
 '@T6G_MB_LIB.T6G(SCH_1):PAGE21_I159@PURE_QUANTA.GENOA_SP5(CHIPS)':
 'MLB_DQS_L0': CDS_PINID='MLB_DQS_L0';
NODE_NAME     J67 105
 '@T6G_MB_LIB.T6G(SCH_1):PAGE96_I236@PURE_QUANTA.SCONN288_DDR506112002KQ(CHIPS)':
 'DQS0_B_C': CDS_PINID='DQS0_B_C';
NET_NAME
'M_L_CPU0_SB_DQS_DN<1>'
 '@T6G_MB_LIB.T6G(SCH_1):M_L_CPU0_SB_DQS_DN'<1>:
 C_SIGNAL='@t6g_mb_lib.t6g(sch_1):m_l_cpu0_sb_dqs_dn(1)';
NODE_NAME     U25 CL9
 '@T6G_MB_LIB.T6G(SCH_1):PAGE21_I159@PURE_QUANTA.GENOA_SP5(CHIPS)':
 'MLB_DQS_L1': CDS_PINID='MLB_DQS_L1';
NODE_NAME     J67 116
 '@T6G_MB_LIB.T6G(SCH_1):PAGE96_I236@PURE_QUANTA.SCONN288_DDR506112002KQ(CHIPS)':
 'DQS1_B_C': CDS_PINID='DQS1_B_C';
NET_NAME
'M_L_CPU0_SB_DQS_DN<2>'
 '@T6G_MB_LIB.T6G(SCH_1):M_L_CPU0_SB_DQS_DN'<2>:
 C_SIGNAL='@t6g_mb_lib.t6g(sch_1):m_l_cpu0_sb_dqs_dn(2)';
NODE_NAME     U25 CU9
 '@T6G_MB_LIB.T6G(SCH_1):PAGE21_I159@PURE_QUANTA.GENOA_SP5(CHIPS)':
 'MLB_DQS_L2': CDS_PINID='MLB_DQS_L2';
NODE_NAME     J67 127
 '@T6G_MB_LIB.T6G(SCH_1):PAGE96_I236@PURE_QUANTA.SCONN288_DDR506112002KQ(CHIPS)':
 'DQS2_B_C': CDS_PINID='DQS2_B_C';
NET_NAME
'M_L_CPU0_SB_DQS_DN<3>'
 '@T6G_MB_LIB.T6G(SCH_1):M_L_CPU0_SB_DQS_DN'<3>:
 C_SIGNAL='@t6g_mb_lib.t6g(sch_1):m_l_cpu0_sb_dqs_dn(3)';
NODE_NAME     U25 DC9
 '@T6G_MB_LIB.T6G(SCH_1):PAGE21_I159@PURE_QUANTA.GENOA_SP5(CHIPS)':
 'MLB_DQS_L3': CDS_PINID='MLB_DQS_L3';
NODE_NAME     J67 138
 '@T6G_MB_LIB.T6G(SCH_1):PAGE96_I236@PURE_QUANTA.SCONN288_DDR506112002KQ(CHIPS)':
 'DQS3_B_C': CDS_PINID='DQS3_B_C';
NET_NAME
'M_L_CPU0_SB_DQS_DN<4>'
 '@T6G_MB_LIB.T6G(SCH_1):M_L_CPU0_SB_DQS_DN'<4>:
 C_SIGNAL='@t6g_mb_lib.t6g(sch_1):m_l_cpu0_sb_dqs_dn(4)';
NODE_NAME     U25 BW10
 '@T6G_MB_LIB.T6G(SCH_1):PAGE21_I159@PURE_QUANTA.GENOA_SP5(CHIPS)':
 'MLB_DQS_L4': CDS_PINID='MLB_DQS_L4';
NODE_NAME     J67 238
 '@T6G_MB_LIB.T6G(SCH_1):PAGE96_I236@PURE_QUANTA.SCONN288_DDR506112002KQ(CHIPS)':
 'DQS4_B_C': CDS_PINID='DQS4_B_C';
NET_NAME
'M_L_CPU0_SB_DQS_DN<5>'
 '@T6G_MB_LIB.T6G(SCH_1):M_L_CPU0_SB_DQS_DN'<5>:
 C_SIGNAL='@t6g_mb_lib.t6g(sch_1):m_l_cpu0_sb_dqs_dn(5)';
NODE_NAME     U25 CE10
 '@T6G_MB_LIB.T6G(SCH_1):PAGE21_I159@PURE_QUANTA.GENOA_SP5(CHIPS)':
 'MLB_DQS_L5': CDS_PINID='MLB_DQS_L5';
NODE_NAME     J67 249
 '@T6G_MB_LIB.T6G(SCH_1):PAGE96_I236@PURE_QUANTA.SCONN288_DDR506112002KQ(CHIPS)':
 'DQS5_B_C||TDQS5_B_C': CDS_PINID='\dqs5_b_c||tdqs5_b_c\';
NET_NAME
'M_L_CPU0_SB_DQS_DN<6>'
 '@T6G_MB_LIB.T6G(SCH_1):M_L_CPU0_SB_DQS_DN'<6>:
 C_SIGNAL='@t6g_mb_lib.t6g(sch_1):m_l_cpu0_sb_dqs_dn(6)';
NODE_NAME     U25 CL10
 '@T6G_MB_LIB.T6G(SCH_1):PAGE21_I159@PURE_QUANTA.GENOA_SP5(CHIPS)':
 'MLB_DQS_L6': CDS_PINID='MLB_DQS_L6';
NODE_NAME     J67 260
 '@T6G_MB_LIB.T6G(SCH_1):PAGE96_I236@PURE_QUANTA.SCONN288_DDR506112002KQ(CHIPS)':
 'DQS6_B_C||TDQS6_B_C': CDS_PINID='\dqs6_b_c||tdqs6_b_c\';
NET_NAME
'M_L_CPU0_SB_DQS_DN<7>'
 '@T6G_MB_LIB.T6G(SCH_1):M_L_CPU0_SB_DQS_DN'<7>:
 C_SIGNAL='@t6g_mb_lib.t6g(sch_1):m_l_cpu0_sb_dqs_dn(7)';
NODE_NAME     U25 CU10
 '@T6G_MB_LIB.T6G(SCH_1):PAGE21_I159@PURE_QUANTA.GENOA_SP5(CHIPS)':
 'MLB_DQS_L7': CDS_PINID='MLB_DQS_L7';
NODE_NAME     J67 271
 '@T6G_MB_LIB.T6G(SCH_1):PAGE96_I236@PURE_QUANTA.SCONN288_DDR506112002KQ(CHIPS)':
 'DQS7_B_C||TDQS7_B_C': CDS_PINID='\dqs7_b_c||tdqs7_b_c\';
NET_NAME
'M_L_CPU0_SB_DQS_DN<8>'
 '@T6G_MB_LIB.T6G(SCH_1):M_L_CPU0_SB_DQS_DN'<8>:
 C_SIGNAL='@t6g_mb_lib.t6g(sch_1):m_l_cpu0_sb_dqs_dn(8)';
NODE_NAME     U25 DC10
 '@T6G_MB_LIB.T6G(SCH_1):PAGE21_I159@PURE_QUANTA.GENOA_SP5(CHIPS)':
 'MLB_DQS_L8': CDS_PINID='MLB_DQS_L8';
NODE_NAME     J67 282
 '@T6G_MB_LIB.T6G(SCH_1):PAGE96_I236@PURE_QUANTA.SCONN288_DDR506112002KQ(CHIPS)':
 'DQS8_B_C||TDQS8_B_C': CDS_PINID='\dqs8_b_c||tdqs8_b_c\';
NET_NAME
'M_L_CPU0_SB_DQS_DN<9>'
 '@T6G_MB_LIB.T6G(SCH_1):M_L_CPU0_SB_DQS_DN'<9>:
 C_SIGNAL='@t6g_mb_lib.t6g(sch_1):m_l_cpu0_sb_dqs_dn(9)';
NODE_NAME     U25 BW9
 '@T6G_MB_LIB.T6G(SCH_1):PAGE21_I159@PURE_QUANTA.GENOA_SP5(CHIPS)':
 'MLB_DQS_L9': CDS_PINID='MLB_DQS_L9';
NODE_NAME     J67 94
 '@T6G_MB_LIB.T6G(SCH_1):PAGE96_I236@PURE_QUANTA.SCONN288_DDR506112002KQ(CHIPS)':
 'DQS9_B_C||TDQS9_B_C': CDS_PINID='\dqs9_b_c||tdqs9_b_c\';
NET_NAME
'M_L_CPU0_SB_DQS_DP<0>'
 '@T6G_MB_LIB.T6G(SCH_1):M_L_CPU0_SB_DQS_DP'<0>:
 C_SIGNAL='@t6g_mb_lib.t6g(sch_1):m_l_cpu0_sb_dqs_dp(0)';
NODE_NAME     U25 CD9
 '@T6G_MB_LIB.T6G(SCH_1):PAGE21_I159@PURE_QUANTA.GENOA_SP5(CHIPS)':
 'MLB_DQS_H0': CDS_PINID='MLB_DQS_H0';
NODE_NAME     J67 104
 '@T6G_MB_LIB.T6G(SCH_1):PAGE96_I236@PURE_QUANTA.SCONN288_DDR506112002KQ(CHIPS)':
 'DQS0_B_T': CDS_PINID='DQS0_B_T';
NET_NAME
'M_L_CPU0_SB_DQS_DP<1>'
 '@T6G_MB_LIB.T6G(SCH_1):M_L_CPU0_SB_DQS_DP'<1>:
 C_SIGNAL='@t6g_mb_lib.t6g(sch_1):m_l_cpu0_sb_dqs_dp(1)';
NODE_NAME     U25 CK9
 '@T6G_MB_LIB.T6G(SCH_1):PAGE21_I159@PURE_QUANTA.GENOA_SP5(CHIPS)':
 'MLB_DQS_H1': CDS_PINID='MLB_DQS_H1';
NODE_NAME     J67 115
 '@T6G_MB_LIB.T6G(SCH_1):PAGE96_I236@PURE_QUANTA.SCONN288_DDR506112002KQ(CHIPS)':
 'DQS1_B_T': CDS_PINID='DQS1_B_T';
NET_NAME
'M_L_CPU0_SB_DQS_DP<2>'
 '@T6G_MB_LIB.T6G(SCH_1):M_L_CPU0_SB_DQS_DP'<2>:
 C_SIGNAL='@t6g_mb_lib.t6g(sch_1):m_l_cpu0_sb_dqs_dp(2)';
NODE_NAME     U25 CT9
 '@T6G_MB_LIB.T6G(SCH_1):PAGE21_I159@PURE_QUANTA.GENOA_SP5(CHIPS)':
 'MLB_DQS_H2': CDS_PINID='MLB_DQS_H2';
NODE_NAME     J67 126
 '@T6G_MB_LIB.T6G(SCH_1):PAGE96_I236@PURE_QUANTA.SCONN288_DDR506112002KQ(CHIPS)':
 'DQS2_B_T': CDS_PINID='DQS2_B_T';
NET_NAME
'M_L_CPU0_SB_DQS_DP<3>'
 '@T6G_MB_LIB.T6G(SCH_1):M_L_CPU0_SB_DQS_DP'<3>:
 C_SIGNAL='@t6g_mb_lib.t6g(sch_1):m_l_cpu0_sb_dqs_dp(3)';
NODE_NAME     U25 DB9
 '@T6G_MB_LIB.T6G(SCH_1):PAGE21_I159@PURE_QUANTA.GENOA_SP5(CHIPS)':
 'MLB_DQS_H3': CDS_PINID='MLB_DQS_H3';
NODE_NAME     J67 137
 '@T6G_MB_LIB.T6G(SCH_1):PAGE96_I236@PURE_QUANTA.SCONN288_DDR506112002KQ(CHIPS)':
 'DQS3_B_T': CDS_PINID='DQS3_B_T';
NET_NAME
'M_L_CPU0_SB_DQS_DP<4>'
 '@T6G_MB_LIB.T6G(SCH_1):M_L_CPU0_SB_DQS_DP'<4>:
 C_SIGNAL='@t6g_mb_lib.t6g(sch_1):m_l_cpu0_sb_dqs_dp(4)';
NODE_NAME     U25 BY11
 '@T6G_MB_LIB.T6G(SCH_1):PAGE21_I159@PURE_QUANTA.GENOA_SP5(CHIPS)':
 'MLB_DQS_H4': CDS_PINID='MLB_DQS_H4';
NODE_NAME     J67 239
 '@T6G_MB_LIB.T6G(SCH_1):PAGE96_I236@PURE_QUANTA.SCONN288_DDR506112002KQ(CHIPS)':
 'DQS4_B_T': CDS_PINID='DQS4_B_T';
NET_NAME
'M_L_CPU0_SB_DQS_DP<5>'
 '@T6G_MB_LIB.T6G(SCH_1):M_L_CPU0_SB_DQS_DP'<5>:
 C_SIGNAL='@t6g_mb_lib.t6g(sch_1):m_l_cpu0_sb_dqs_dp(5)';
NODE_NAME     U25 CF11
 '@T6G_MB_LIB.T6G(SCH_1):PAGE21_I159@PURE_QUANTA.GENOA_SP5(CHIPS)':
 'MLB_DQS_H5': CDS_PINID='MLB_DQS_H5';
NODE_NAME     J67 250
 '@T6G_MB_LIB.T6G(SCH_1):PAGE96_I236@PURE_QUANTA.SCONN288_DDR506112002KQ(CHIPS)':
 'DQS5_B_T||TDQS5_B_T': CDS_PINID='\dqs5_b_t||tdqs5_b_t\';
NET_NAME
'M_L_CPU0_SB_DQS_DP<6>'
 '@T6G_MB_LIB.T6G(SCH_1):M_L_CPU0_SB_DQS_DP'<6>:
 C_SIGNAL='@t6g_mb_lib.t6g(sch_1):m_l_cpu0_sb_dqs_dp(6)';
NODE_NAME     U25 CM11
 '@T6G_MB_LIB.T6G(SCH_1):PAGE21_I159@PURE_QUANTA.GENOA_SP5(CHIPS)':
 'MLB_DQS_H6': CDS_PINID='MLB_DQS_H6';
NODE_NAME     J67 261
 '@T6G_MB_LIB.T6G(SCH_1):PAGE96_I236@PURE_QUANTA.SCONN288_DDR506112002KQ(CHIPS)':
 'DQS6_B_T||TDQS6_B_T': CDS_PINID='\dqs6_b_t||tdqs6_b_t\';
NET_NAME
'M_L_CPU0_SB_DQS_DP<7>'
 '@T6G_MB_LIB.T6G(SCH_1):M_L_CPU0_SB_DQS_DP'<7>:
 C_SIGNAL='@t6g_mb_lib.t6g(sch_1):m_l_cpu0_sb_dqs_dp(7)';
NODE_NAME     U25 CV11
 '@T6G_MB_LIB.T6G(SCH_1):PAGE21_I159@PURE_QUANTA.GENOA_SP5(CHIPS)':
 'MLB_DQS_H7': CDS_PINID='MLB_DQS_H7';
NODE_NAME     J67 272
 '@T6G_MB_LIB.T6G(SCH_1):PAGE96_I236@PURE_QUANTA.SCONN288_DDR506112002KQ(CHIPS)':
 'DQS7_B_T||TDQS7_B_T': CDS_PINID='\dqs7_b_t||tdqs7_b_t\';
NET_NAME
'M_L_CPU0_SB_DQS_DP<8>'
 '@T6G_MB_LIB.T6G(SCH_1):M_L_CPU0_SB_DQS_DP'<8>:
 C_SIGNAL='@t6g_mb_lib.t6g(sch_1):m_l_cpu0_sb_dqs_dp(8)';
NODE_NAME     U25 DD11
 '@T6G_MB_LIB.T6G(SCH_1):PAGE21_I159@PURE_QUANTA.GENOA_SP5(CHIPS)':
 'MLB_DQS_H8': CDS_PINID='MLB_DQS_H8';
NODE_NAME     J67 283
 '@T6G_MB_LIB.T6G(SCH_1):PAGE96_I236@PURE_QUANTA.SCONN288_DDR506112002KQ(CHIPS)':
 'DQS8_B_T||TDQS8_B_T': CDS_PINID='\dqs8_b_t||tdqs8_b_t\';
NET_NAME
'M_L_CPU0_SB_DQS_DP<9>'
 '@T6G_MB_LIB.T6G(SCH_1):M_L_CPU0_SB_DQS_DP'<9>:
 C_SIGNAL='@t6g_mb_lib.t6g(sch_1):m_l_cpu0_sb_dqs_dp(9)';
NODE_NAME     U25 BV9
 '@T6G_MB_LIB.T6G(SCH_1):PAGE21_I159@PURE_QUANTA.GENOA_SP5(CHIPS)':
 'MLB_DQS_H9': CDS_PINID='MLB_DQS_H9';
NODE_NAME     J67 93
 '@T6G_MB_LIB.T6G(SCH_1):PAGE96_I236@PURE_QUANTA.SCONN288_DDR506112002KQ(CHIPS)':
 'DQS9_B_T||TDQS9_B_T||DBI4_B_N': CDS_PINID='\dqs9_b_t||tdqs9_b_t||dbi4_b_n\';
NET_NAME
'M_L_CPU0_SB_PAR'
 '@T6G_MB_LIB.T6G(SCH_1):M_L_CPU0_SB_PAR':
 C_SIGNAL='@t6g_mb_lib.t6g(sch_1):m_l_cpu0_sb_par';
NODE_NAME     U25 BL10
 '@T6G_MB_LIB.T6G(SCH_1):PAGE21_I159@PURE_QUANTA.GENOA_SP5(CHIPS)':
 'MLB_PAR': CDS_PINID='MLB_PAR';
NODE_NAME     J67 227
 '@T6G_MB_LIB.T6G(SCH_1):PAGE96_I22@PURE_QUANTA.SCONN288_DDR506112002KQ(CHIPS)':
 'PAR_B': CDS_PINID='PAR_B';
NET_NAME
'M_L_CPU0_SB_RSP<0>'
 '@T6G_MB_LIB.T6G(SCH_1):M_L_CPU0_SB_RSP'<0>:
 C_SIGNAL='@t6g_mb_lib.t6g(sch_1):m_l_cpu0_sb_rsp(0)';
NODE_NAME     U25 BP9
 '@T6G_MB_LIB.T6G(SCH_1):PAGE21_I159@PURE_QUANTA.GENOA_SP5(CHIPS)':
 'MLB0_RSP_L': CDS_PINID='MLB0_RSP_L';
NODE_NAME     J67 87
 '@T6G_MB_LIB.T6G(SCH_1):PAGE96_I22@PURE_QUANTA.SCONN288_DDR506112002KQ(CHIPS)':
 'LBS||RSP_B_N': CDS_PINID='\lbs||rsp_b_n\';
NET_NAME
'M_L_CPU1_ALERT_N'
 '@T6G_MB_LIB.T6G(SCH_1):M_L_CPU1_ALERT_N':
 C_SIGNAL='@t6g_mb_lib.t6g(sch_1):m_l_cpu1_alert_n';
NODE_NAME     R511 1
 '@T6G_MB_LIB.T6G(SCH_1):PAGE48_I313@PURE_QUANTA.Q_RES(CHIPS)':
 'A': CDS_PINID='A';
NODE_NAME     J37 62
 '@T6G_MB_LIB.T6G(SCH_1):PAGE108_I22@PURE_QUANTA.SCONN288_DDR506112002KQ(CHIPS)':
 'ALERT_N': CDS_PINID='ALERT_N';
NET_NAME
'M_L_CPU1_ALERT_R_N'
 '@T6G_MB_LIB.T6G(SCH_1):M_L_CPU1_ALERT_R_N':
 C_SIGNAL='@t6g_mb_lib.t6g(sch_1):m_l_cpu1_alert_r_n';
NODE_NAME     U26 AT11
 '@T6G_MB_LIB.T6G(SCH_1):PAGE48_I159@PURE_QUANTA.GENOA_SP5(CHIPS)':
 'ML_ALERT_L': CDS_PINID='ML_ALERT_L';
NODE_NAME     R511 2
 '@T6G_MB_LIB.T6G(SCH_1):PAGE48_I313@PURE_QUANTA.Q_RES(CHIPS)':
 'B': CDS_PINID='B';
NET_NAME
'M_L_CPU1_CLK_DN<0>'
 '@T6G_MB_LIB.T6G(SCH_1):M_L_CPU1_CLK_DN'<0>:
 C_SIGNAL='@t6g_mb_lib.t6g(sch_1):m_l_cpu1_clk_dn(0)';
NODE_NAME     U26 BD9
 '@T6G_MB_LIB.T6G(SCH_1):PAGE48_I159@PURE_QUANTA.GENOA_SP5(CHIPS)':
 'ML0_CLK_L': CDS_PINID='ML0_CLK_L';
NODE_NAME     J37 218
 '@T6G_MB_LIB.T6G(SCH_1):PAGE108_I22@PURE_QUANTA.SCONN288_DDR506112002KQ(CHIPS)':
 'CK_C': CDS_PINID='CK_C';
NET_NAME
'M_L_CPU1_CLK_DP<0>'
 '@T6G_MB_LIB.T6G(SCH_1):M_L_CPU1_CLK_DP'<0>:
 C_SIGNAL='@t6g_mb_lib.t6g(sch_1):m_l_cpu1_clk_dp(0)';
NODE_NAME     U26 BC9
 '@T6G_MB_LIB.T6G(SCH_1):PAGE48_I159@PURE_QUANTA.GENOA_SP5(CHIPS)':
 'ML0_CLK_H': CDS_PINID='ML0_CLK_H';
NODE_NAME     J37 217
 '@T6G_MB_LIB.T6G(SCH_1):PAGE108_I22@PURE_QUANTA.SCONN288_DDR506112002KQ(CHIPS)':
 'CK_T': CDS_PINID='CK_T';
NET_NAME
'M_L_CPU1_RESET_N'
 '@T6G_MB_LIB.T6G(SCH_1):M_L_CPU1_RESET_N':
 C_SIGNAL='@t6g_mb_lib.t6g(sch_1):m_l_cpu1_reset_n';
NODE_NAME     U26 AU10
 '@T6G_MB_LIB.T6G(SCH_1):PAGE48_I159@PURE_QUANTA.GENOA_SP5(CHIPS)':
 'ML_RESET_L': CDS_PINID='ML_RESET_L';
NODE_NAME     J37 207
 '@T6G_MB_LIB.T6G(SCH_1):PAGE108_I22@PURE_QUANTA.SCONN288_DDR506112002KQ(CHIPS)':
 'RESET_N': CDS_PINID='RESET_N';
NET_NAME
'M_L_CPU1_SA_CA<0>'
 '@T6G_MB_LIB.T6G(SCH_1):M_L_CPU1_SA_CA'<0>:
 C_SIGNAL='@t6g_mb_lib.t6g(sch_1):m_l_cpu1_sa_ca(0)';
NODE_NAME     U26 AW9
 '@T6G_MB_LIB.T6G(SCH_1):PAGE48_I159@PURE_QUANTA.GENOA_SP5(CHIPS)':
 'MLA_CA0': CDS_PINID='MLA_CA0';
NODE_NAME     J37 66
 '@T6G_MB_LIB.T6G(SCH_1):PAGE108_I22@PURE_QUANTA.SCONN288_DDR506112002KQ(CHIPS)':
 'CA0_A': CDS_PINID='CA0_A';
NET_NAME
'M_L_CPU1_SA_CA<1>'
 '@T6G_MB_LIB.T6G(SCH_1):M_L_CPU1_SA_CA'<1>:
 C_SIGNAL='@t6g_mb_lib.t6g(sch_1):m_l_cpu1_sa_ca(1)';
NODE_NAME     U26 AY9
 '@T6G_MB_LIB.T6G(SCH_1):PAGE48_I159@PURE_QUANTA.GENOA_SP5(CHIPS)':
 'MLA_CA1': CDS_PINID='MLA_CA1';
NODE_NAME     J37 211
 '@T6G_MB_LIB.T6G(SCH_1):PAGE108_I22@PURE_QUANTA.SCONN288_DDR506112002KQ(CHIPS)':
 'CA1_A': CDS_PINID='CA1_A';
NET_NAME
'M_L_CPU1_SA_CA<2>'
 '@T6G_MB_LIB.T6G(SCH_1):M_L_CPU1_SA_CA'<2>:
 C_SIGNAL='@t6g_mb_lib.t6g(sch_1):m_l_cpu1_sa_ca(2)';
NODE_NAME     U26 AY11
 '@T6G_MB_LIB.T6G(SCH_1):PAGE48_I159@PURE_QUANTA.GENOA_SP5(CHIPS)':
 'MLA_CA2': CDS_PINID='MLA_CA2';
NODE_NAME     J37 68
 '@T6G_MB_LIB.T6G(SCH_1):PAGE108_I22@PURE_QUANTA.SCONN288_DDR506112002KQ(CHIPS)':
 'CA2_A': CDS_PINID='CA2_A';
NET_NAME
'M_L_CPU1_SA_CA<3>'
 '@T6G_MB_LIB.T6G(SCH_1):M_L_CPU1_SA_CA'<3>:
 C_SIGNAL='@t6g_mb_lib.t6g(sch_1):m_l_cpu1_sa_ca(3)';
NODE_NAME     U26 BA10
 '@T6G_MB_LIB.T6G(SCH_1):PAGE48_I159@PURE_QUANTA.GENOA_SP5(CHIPS)':
 'MLA_CA3': CDS_PINID='MLA_CA3';
NODE_NAME     J37 213
 '@T6G_MB_LIB.T6G(SCH_1):PAGE108_I22@PURE_QUANTA.SCONN288_DDR506112002KQ(CHIPS)':
 'CA3_A': CDS_PINID='CA3_A';
NET_NAME
'M_L_CPU1_SA_CA<4>'
 '@T6G_MB_LIB.T6G(SCH_1):M_L_CPU1_SA_CA'<4>:
 C_SIGNAL='@t6g_mb_lib.t6g(sch_1):m_l_cpu1_sa_ca(4)';
NODE_NAME     U26 BA9
 '@T6G_MB_LIB.T6G(SCH_1):PAGE48_I159@PURE_QUANTA.GENOA_SP5(CHIPS)':
 'MLA_CA4': CDS_PINID='MLA_CA4';
NODE_NAME     J37 70
 '@T6G_MB_LIB.T6G(SCH_1):PAGE108_I22@PURE_QUANTA.SCONN288_DDR506112002KQ(CHIPS)':
 'CA4_A': CDS_PINID='CA4_A';
NET_NAME
'M_L_CPU1_SA_CA<5>'
 '@T6G_MB_LIB.T6G(SCH_1):M_L_CPU1_SA_CA'<5>:
 C_SIGNAL='@t6g_mb_lib.t6g(sch_1):m_l_cpu1_sa_ca(5)';
NODE_NAME     U26 BB9
 '@T6G_MB_LIB.T6G(SCH_1):PAGE48_I159@PURE_QUANTA.GENOA_SP5(CHIPS)':
 'MLA_CA5': CDS_PINID='MLA_CA5';
NODE_NAME     J37 215
 '@T6G_MB_LIB.T6G(SCH_1):PAGE108_I22@PURE_QUANTA.SCONN288_DDR506112002KQ(CHIPS)':
 'CA5_A': CDS_PINID='CA5_A';
NET_NAME
'M_L_CPU1_SA_CA<6>'
 '@T6G_MB_LIB.T6G(SCH_1):M_L_CPU1_SA_CA'<6>:
 C_SIGNAL='@t6g_mb_lib.t6g(sch_1):m_l_cpu1_sa_ca(6)';
NODE_NAME     U26 BB11
 '@T6G_MB_LIB.T6G(SCH_1):PAGE48_I159@PURE_QUANTA.GENOA_SP5(CHIPS)':
 'MLA_CA6': CDS_PINID='MLA_CA6';
NODE_NAME     J37 72
 '@T6G_MB_LIB.T6G(SCH_1):PAGE108_I22@PURE_QUANTA.SCONN288_DDR506112002KQ(CHIPS)':
 'CA6_A': CDS_PINID='CA6_A';
NET_NAME
'M_L_CPU1_SA_CB<0>'
 '@T6G_MB_LIB.T6G(SCH_1):M_L_CPU1_SA_CB'<0>:
 C_SIGNAL='@t6g_mb_lib.t6g(sch_1):m_l_cpu1_sa_cb(0)';
NODE_NAME     U26 AJ9
 '@T6G_MB_LIB.T6G(SCH_1):PAGE48_I159@PURE_QUANTA.GENOA_SP5(CHIPS)':
 'MLA_CHECK0': CDS_PINID='MLA_CHECK0';
NODE_NAME     J37 51
 '@T6G_MB_LIB.T6G(SCH_1):PAGE108_I22@PURE_QUANTA.SCONN288_DDR506112002KQ(CHIPS)':
 'CB0_A': CDS_PINID='CB0_A';
NET_NAME
'M_L_CPU1_SA_CB<1>'
 '@T6G_MB_LIB.T6G(SCH_1):M_L_CPU1_SA_CB'<1>:
 C_SIGNAL='@t6g_mb_lib.t6g(sch_1):m_l_cpu1_sa_cb(1)';
NODE_NAME     U26 AK11
 '@T6G_MB_LIB.T6G(SCH_1):PAGE48_I159@PURE_QUANTA.GENOA_SP5(CHIPS)':
 'MLA_CHECK1': CDS_PINID='MLA_CHECK1';
NODE_NAME     J37 53
 '@T6G_MB_LIB.T6G(SCH_1):PAGE108_I22@PURE_QUANTA.SCONN288_DDR506112002KQ(CHIPS)':
 'CB1_A': CDS_PINID='CB1_A';
NET_NAME
'M_L_CPU1_SA_CB<2>'
 '@T6G_MB_LIB.T6G(SCH_1):M_L_CPU1_SA_CB'<2>:
 C_SIGNAL='@t6g_mb_lib.t6g(sch_1):m_l_cpu1_sa_cb(2)';
NODE_NAME     U26 AK9
 '@T6G_MB_LIB.T6G(SCH_1):PAGE48_I159@PURE_QUANTA.GENOA_SP5(CHIPS)':
 'MLA_CHECK2': CDS_PINID='MLA_CHECK2';
NODE_NAME     J37 196
 '@T6G_MB_LIB.T6G(SCH_1):PAGE108_I22@PURE_QUANTA.SCONN288_DDR506112002KQ(CHIPS)':
 'CB2_A': CDS_PINID='CB2_A';
NET_NAME
'M_L_CPU1_SA_CB<3>'
 '@T6G_MB_LIB.T6G(SCH_1):M_L_CPU1_SA_CB'<3>:
 C_SIGNAL='@t6g_mb_lib.t6g(sch_1):m_l_cpu1_sa_cb(3)';
NODE_NAME     U26 AL10
 '@T6G_MB_LIB.T6G(SCH_1):PAGE48_I159@PURE_QUANTA.GENOA_SP5(CHIPS)':
 'MLA_CHECK3': CDS_PINID='MLA_CHECK3';
NODE_NAME     J37 198
 '@T6G_MB_LIB.T6G(SCH_1):PAGE108_I22@PURE_QUANTA.SCONN288_DDR506112002KQ(CHIPS)':
 'CB3_A': CDS_PINID='CB3_A';
NET_NAME
'M_L_CPU1_SA_CB<4>'
 '@T6G_MB_LIB.T6G(SCH_1):M_L_CPU1_SA_CB'<4>:
 C_SIGNAL='@t6g_mb_lib.t6g(sch_1):m_l_cpu1_sa_cb(4)';
NODE_NAME     U26 AN9
 '@T6G_MB_LIB.T6G(SCH_1):PAGE48_I159@PURE_QUANTA.GENOA_SP5(CHIPS)':
 'MLA_CHECK4': CDS_PINID='MLA_CHECK4';
NODE_NAME     J37 58
 '@T6G_MB_LIB.T6G(SCH_1):PAGE108_I22@PURE_QUANTA.SCONN288_DDR506112002KQ(CHIPS)':
 'CB4_A': CDS_PINID='CB4_A';
NET_NAME
'M_L_CPU1_SA_CB<5>'
 '@T6G_MB_LIB.T6G(SCH_1):M_L_CPU1_SA_CB'<5>:
 C_SIGNAL='@t6g_mb_lib.t6g(sch_1):m_l_cpu1_sa_cb(5)';
NODE_NAME     U26 AP11
 '@T6G_MB_LIB.T6G(SCH_1):PAGE48_I159@PURE_QUANTA.GENOA_SP5(CHIPS)':
 'MLA_CHECK5': CDS_PINID='MLA_CHECK5';
NODE_NAME     J37 60
 '@T6G_MB_LIB.T6G(SCH_1):PAGE108_I22@PURE_QUANTA.SCONN288_DDR506112002KQ(CHIPS)':
 'CB5_A': CDS_PINID='CB5_A';
NET_NAME
'M_L_CPU1_SA_CB<6>'
 '@T6G_MB_LIB.T6G(SCH_1):M_L_CPU1_SA_CB'<6>:
 C_SIGNAL='@t6g_mb_lib.t6g(sch_1):m_l_cpu1_sa_cb(6)';
NODE_NAME     U26 AP9
 '@T6G_MB_LIB.T6G(SCH_1):PAGE48_I159@PURE_QUANTA.GENOA_SP5(CHIPS)':
 'MLA_CHECK6': CDS_PINID='MLA_CHECK6';
NODE_NAME     J37 203
 '@T6G_MB_LIB.T6G(SCH_1):PAGE108_I22@PURE_QUANTA.SCONN288_DDR506112002KQ(CHIPS)':
 'CB6_A': CDS_PINID='CB6_A';
NET_NAME
'M_L_CPU1_SA_CB<7>'
 '@T6G_MB_LIB.T6G(SCH_1):M_L_CPU1_SA_CB'<7>:
 C_SIGNAL='@t6g_mb_lib.t6g(sch_1):m_l_cpu1_sa_cb(7)';
NODE_NAME     U26 AR10
 '@T6G_MB_LIB.T6G(SCH_1):PAGE48_I159@PURE_QUANTA.GENOA_SP5(CHIPS)':
 'MLA_CHECK7': CDS_PINID='MLA_CHECK7';
NODE_NAME     J37 205
 '@T6G_MB_LIB.T6G(SCH_1):PAGE108_I22@PURE_QUANTA.SCONN288_DDR506112002KQ(CHIPS)':
 'CB7_A': CDS_PINID='CB7_A';
NET_NAME
'M_L_CPU1_SA_CS_N<0>'
 '@T6G_MB_LIB.T6G(SCH_1):M_L_CPU1_SA_CS_N'<0>:
 C_SIGNAL='@t6g_mb_lib.t6g(sch_1):m_l_cpu1_sa_cs_n(0)';
NODE_NAME     U26 AU9
 '@T6G_MB_LIB.T6G(SCH_1):PAGE48_I159@PURE_QUANTA.GENOA_SP5(CHIPS)':
 'MLA0_CS_L0': CDS_PINID='MLA0_CS_L0';
NODE_NAME     J37 64
 '@T6G_MB_LIB.T6G(SCH_1):PAGE108_I22@PURE_QUANTA.SCONN288_DDR506112002KQ(CHIPS)':
 'CS0_A_N': CDS_PINID='CS0_A_N';
NET_NAME
'M_L_CPU1_SA_CS_N<1>'
 '@T6G_MB_LIB.T6G(SCH_1):M_L_CPU1_SA_CS_N'<1>:
 C_SIGNAL='@t6g_mb_lib.t6g(sch_1):m_l_cpu1_sa_cs_n(1)';
NODE_NAME     U26 AV11
 '@T6G_MB_LIB.T6G(SCH_1):PAGE48_I159@PURE_QUANTA.GENOA_SP5(CHIPS)':
 'MLA0_CS_L1': CDS_PINID='MLA0_CS_L1';
NODE_NAME     J37 209
 '@T6G_MB_LIB.T6G(SCH_1):PAGE108_I22@PURE_QUANTA.SCONN288_DDR506112002KQ(CHIPS)':
 'CS1_A_N': CDS_PINID='CS1_A_N';
NET_NAME
'M_L_CPU1_SA_DQ<0>'
 '@T6G_MB_LIB.T6G(SCH_1):M_L_CPU1_SA_DQ'<0>:
 C_SIGNAL='@t6g_mb_lib.t6g(sch_1):m_l_cpu1_sa_dq(0)';
NODE_NAME     U26 E9
 '@T6G_MB_LIB.T6G(SCH_1):PAGE48_I159@PURE_QUANTA.GENOA_SP5(CHIPS)':
 'MLA_DATA0': CDS_PINID='MLA_DATA0';
NODE_NAME     J37 7
 '@T6G_MB_LIB.T6G(SCH_1):PAGE108_I22@PURE_QUANTA.SCONN288_DDR506112002KQ(CHIPS)':
 'DQ0_A': CDS_PINID='DQ0_A';
NET_NAME
'M_L_CPU1_SA_DQ<10>'
 '@T6G_MB_LIB.T6G(SCH_1):M_L_CPU1_SA_DQ'<10>:
 C_SIGNAL='@t6g_mb_lib.t6g(sch_1):m_l_cpu1_sa_dq(10)';
NODE_NAME     U26 M9
 '@T6G_MB_LIB.T6G(SCH_1):PAGE48_I159@PURE_QUANTA.GENOA_SP5(CHIPS)':
 'MLA_DATA10': CDS_PINID='MLA_DATA10';
NODE_NAME     J37 163
 '@T6G_MB_LIB.T6G(SCH_1):PAGE108_I22@PURE_QUANTA.SCONN288_DDR506112002KQ(CHIPS)':
 'DQ10_A': CDS_PINID='DQ10_A';
NET_NAME
'M_L_CPU1_SA_DQ<11>'
 '@T6G_MB_LIB.T6G(SCH_1):M_L_CPU1_SA_DQ'<11>:
 C_SIGNAL='@t6g_mb_lib.t6g(sch_1):m_l_cpu1_sa_dq(11)';
NODE_NAME     U26 N10
 '@T6G_MB_LIB.T6G(SCH_1):PAGE48_I159@PURE_QUANTA.GENOA_SP5(CHIPS)':
 'MLA_DATA11': CDS_PINID='MLA_DATA11';
NODE_NAME     J37 165
 '@T6G_MB_LIB.T6G(SCH_1):PAGE108_I22@PURE_QUANTA.SCONN288_DDR506112002KQ(CHIPS)':
 'DQ11_A': CDS_PINID='DQ11_A';
NET_NAME
'M_L_CPU1_SA_DQ<12>'
 '@T6G_MB_LIB.T6G(SCH_1):M_L_CPU1_SA_DQ'<12>:
 C_SIGNAL='@t6g_mb_lib.t6g(sch_1):m_l_cpu1_sa_dq(12)';
NODE_NAME     U26 R9
 '@T6G_MB_LIB.T6G(SCH_1):PAGE48_I159@PURE_QUANTA.GENOA_SP5(CHIPS)':
 'MLA_DATA12': CDS_PINID='MLA_DATA12';
NODE_NAME     J37 25
 '@T6G_MB_LIB.T6G(SCH_1):PAGE108_I22@PURE_QUANTA.SCONN288_DDR506112002KQ(CHIPS)':
 'DQ12_A': CDS_PINID='DQ12_A';
NET_NAME
'M_L_CPU1_SA_DQ<13>'
 '@T6G_MB_LIB.T6G(SCH_1):M_L_CPU1_SA_DQ'<13>:
 C_SIGNAL='@t6g_mb_lib.t6g(sch_1):m_l_cpu1_sa_dq(13)';
NODE_NAME     U26 T11
 '@T6G_MB_LIB.T6G(SCH_1):PAGE48_I159@PURE_QUANTA.GENOA_SP5(CHIPS)':
 'MLA_DATA13': CDS_PINID='MLA_DATA13';
NODE_NAME     J37 27
 '@T6G_MB_LIB.T6G(SCH_1):PAGE108_I22@PURE_QUANTA.SCONN288_DDR506112002KQ(CHIPS)':
 'DQ13_A': CDS_PINID='DQ13_A';
NET_NAME
'M_L_CPU1_SA_DQ<14>'
 '@T6G_MB_LIB.T6G(SCH_1):M_L_CPU1_SA_DQ'<14>:
 C_SIGNAL='@t6g_mb_lib.t6g(sch_1):m_l_cpu1_sa_dq(14)';
NODE_NAME     U26 T9
 '@T6G_MB_LIB.T6G(SCH_1):PAGE48_I159@PURE_QUANTA.GENOA_SP5(CHIPS)':
 'MLA_DATA14': CDS_PINID='MLA_DATA14';
NODE_NAME     J37 170
 '@T6G_MB_LIB.T6G(SCH_1):PAGE108_I22@PURE_QUANTA.SCONN288_DDR506112002KQ(CHIPS)':
 'DQ14_A': CDS_PINID='DQ14_A';
NET_NAME
'M_L_CPU1_SA_DQ<15>'
 '@T6G_MB_LIB.T6G(SCH_1):M_L_CPU1_SA_DQ'<15>:
 C_SIGNAL='@t6g_mb_lib.t6g(sch_1):m_l_cpu1_sa_dq(15)';
NODE_NAME     U26 U10
 '@T6G_MB_LIB.T6G(SCH_1):PAGE48_I159@PURE_QUANTA.GENOA_SP5(CHIPS)':
 'MLA_DATA15': CDS_PINID='MLA_DATA15';
NODE_NAME     J37 172
 '@T6G_MB_LIB.T6G(SCH_1):PAGE108_I22@PURE_QUANTA.SCONN288_DDR506112002KQ(CHIPS)':
 'DQ15_A': CDS_PINID='DQ15_A';
NET_NAME
'M_L_CPU1_SA_DQ<16>'
 '@T6G_MB_LIB.T6G(SCH_1):M_L_CPU1_SA_DQ'<16>:
 C_SIGNAL='@t6g_mb_lib.t6g(sch_1):m_l_cpu1_sa_dq(16)';
NODE_NAME     U26 U9
 '@T6G_MB_LIB.T6G(SCH_1):PAGE48_I159@PURE_QUANTA.GENOA_SP5(CHIPS)':
 'MLA_DATA16': CDS_PINID='MLA_DATA16';
NODE_NAME     J37 29
 '@T6G_MB_LIB.T6G(SCH_1):PAGE108_I22@PURE_QUANTA.SCONN288_DDR506112002KQ(CHIPS)':
 'DQ16_A': CDS_PINID='DQ16_A';
NET_NAME
'M_L_CPU1_SA_DQ<17>'
 '@T6G_MB_LIB.T6G(SCH_1):M_L_CPU1_SA_DQ'<17>:
 C_SIGNAL='@t6g_mb_lib.t6g(sch_1):m_l_cpu1_sa_dq(17)';
NODE_NAME     U26 V11
 '@T6G_MB_LIB.T6G(SCH_1):PAGE48_I159@PURE_QUANTA.GENOA_SP5(CHIPS)':
 'MLA_DATA17': CDS_PINID='MLA_DATA17';
NODE_NAME     J37 31
 '@T6G_MB_LIB.T6G(SCH_1):PAGE108_I22@PURE_QUANTA.SCONN288_DDR506112002KQ(CHIPS)':
 'DQ17_A': CDS_PINID='DQ17_A';
NET_NAME
'M_L_CPU1_SA_DQ<18>'
 '@T6G_MB_LIB.T6G(SCH_1):M_L_CPU1_SA_DQ'<18>:
 C_SIGNAL='@t6g_mb_lib.t6g(sch_1):m_l_cpu1_sa_dq(18)';
NODE_NAME     U26 V9
 '@T6G_MB_LIB.T6G(SCH_1):PAGE48_I159@PURE_QUANTA.GENOA_SP5(CHIPS)':
 'MLA_DATA18': CDS_PINID='MLA_DATA18';
NODE_NAME     J37 174
 '@T6G_MB_LIB.T6G(SCH_1):PAGE108_I22@PURE_QUANTA.SCONN288_DDR506112002KQ(CHIPS)':
 'DQ18_A': CDS_PINID='DQ18_A';
NET_NAME
'M_L_CPU1_SA_DQ<19>'
 '@T6G_MB_LIB.T6G(SCH_1):M_L_CPU1_SA_DQ'<19>:
 C_SIGNAL='@t6g_mb_lib.t6g(sch_1):m_l_cpu1_sa_dq(19)';
NODE_NAME     U26 W10
 '@T6G_MB_LIB.T6G(SCH_1):PAGE48_I159@PURE_QUANTA.GENOA_SP5(CHIPS)':
 'MLA_DATA19': CDS_PINID='MLA_DATA19';
NODE_NAME     J37 176
 '@T6G_MB_LIB.T6G(SCH_1):PAGE108_I22@PURE_QUANTA.SCONN288_DDR506112002KQ(CHIPS)':
 'DQ19_A': CDS_PINID='DQ19_A';
NET_NAME
'M_L_CPU1_SA_DQ<1>'
 '@T6G_MB_LIB.T6G(SCH_1):M_L_CPU1_SA_DQ'<1>:
 C_SIGNAL='@t6g_mb_lib.t6g(sch_1):m_l_cpu1_sa_dq(1)';
NODE_NAME     U26 F11
 '@T6G_MB_LIB.T6G(SCH_1):PAGE48_I159@PURE_QUANTA.GENOA_SP5(CHIPS)':
 'MLA_DATA1': CDS_PINID='MLA_DATA1';
NODE_NAME     J37 9
 '@T6G_MB_LIB.T6G(SCH_1):PAGE108_I22@PURE_QUANTA.SCONN288_DDR506112002KQ(CHIPS)':
 'DQ1_A': CDS_PINID='DQ1_A';
NET_NAME
'M_L_CPU1_SA_DQ<20>'
 '@T6G_MB_LIB.T6G(SCH_1):M_L_CPU1_SA_DQ'<20>:
 C_SIGNAL='@t6g_mb_lib.t6g(sch_1):m_l_cpu1_sa_dq(20)';
NODE_NAME     U26 AA9
 '@T6G_MB_LIB.T6G(SCH_1):PAGE48_I159@PURE_QUANTA.GENOA_SP5(CHIPS)':
 'MLA_DATA20': CDS_PINID='MLA_DATA20';
NODE_NAME     J37 36
 '@T6G_MB_LIB.T6G(SCH_1):PAGE108_I22@PURE_QUANTA.SCONN288_DDR506112002KQ(CHIPS)':
 'DQ20_A': CDS_PINID='DQ20_A';
NET_NAME
'M_L_CPU1_SA_DQ<21>'
 '@T6G_MB_LIB.T6G(SCH_1):M_L_CPU1_SA_DQ'<21>:
 C_SIGNAL='@t6g_mb_lib.t6g(sch_1):m_l_cpu1_sa_dq(21)';
NODE_NAME     U26 AB11
 '@T6G_MB_LIB.T6G(SCH_1):PAGE48_I159@PURE_QUANTA.GENOA_SP5(CHIPS)':
 'MLA_DATA21': CDS_PINID='MLA_DATA21';
NODE_NAME     J37 38
 '@T6G_MB_LIB.T6G(SCH_1):PAGE108_I22@PURE_QUANTA.SCONN288_DDR506112002KQ(CHIPS)':
 'DQ21_A': CDS_PINID='DQ21_A';
NET_NAME
'M_L_CPU1_SA_DQ<22>'
 '@T6G_MB_LIB.T6G(SCH_1):M_L_CPU1_SA_DQ'<22>:
 C_SIGNAL='@t6g_mb_lib.t6g(sch_1):m_l_cpu1_sa_dq(22)';
NODE_NAME     U26 AB9
 '@T6G_MB_LIB.T6G(SCH_1):PAGE48_I159@PURE_QUANTA.GENOA_SP5(CHIPS)':
 'MLA_DATA22': CDS_PINID='MLA_DATA22';
NODE_NAME     J37 181
 '@T6G_MB_LIB.T6G(SCH_1):PAGE108_I22@PURE_QUANTA.SCONN288_DDR506112002KQ(CHIPS)':
 'DQ22_A': CDS_PINID='DQ22_A';
NET_NAME
'M_L_CPU1_SA_DQ<23>'
 '@T6G_MB_LIB.T6G(SCH_1):M_L_CPU1_SA_DQ'<23>:
 C_SIGNAL='@t6g_mb_lib.t6g(sch_1):m_l_cpu1_sa_dq(23)';
NODE_NAME     U26 AC10
 '@T6G_MB_LIB.T6G(SCH_1):PAGE48_I159@PURE_QUANTA.GENOA_SP5(CHIPS)':
 'MLA_DATA23': CDS_PINID='MLA_DATA23';
NODE_NAME     J37 183
 '@T6G_MB_LIB.T6G(SCH_1):PAGE108_I22@PURE_QUANTA.SCONN288_DDR506112002KQ(CHIPS)':
 'DQ23_A': CDS_PINID='DQ23_A';
NET_NAME
'M_L_CPU1_SA_DQ<24>'
 '@T6G_MB_LIB.T6G(SCH_1):M_L_CPU1_SA_DQ'<24>:
 C_SIGNAL='@t6g_mb_lib.t6g(sch_1):m_l_cpu1_sa_dq(24)';
NODE_NAME     U26 AC9
 '@T6G_MB_LIB.T6G(SCH_1):PAGE48_I159@PURE_QUANTA.GENOA_SP5(CHIPS)':
 'MLA_DATA24': CDS_PINID='MLA_DATA24';
NODE_NAME     J37 40
 '@T6G_MB_LIB.T6G(SCH_1):PAGE108_I22@PURE_QUANTA.SCONN288_DDR506112002KQ(CHIPS)':
 'DQ24_A': CDS_PINID='DQ24_A';
NET_NAME
'M_L_CPU1_SA_DQ<25>'
 '@T6G_MB_LIB.T6G(SCH_1):M_L_CPU1_SA_DQ'<25>:
 C_SIGNAL='@t6g_mb_lib.t6g(sch_1):m_l_cpu1_sa_dq(25)';
NODE_NAME     U26 AD11
 '@T6G_MB_LIB.T6G(SCH_1):PAGE48_I159@PURE_QUANTA.GENOA_SP5(CHIPS)':
 'MLA_DATA25': CDS_PINID='MLA_DATA25';
NODE_NAME     J37 42
 '@T6G_MB_LIB.T6G(SCH_1):PAGE108_I22@PURE_QUANTA.SCONN288_DDR506112002KQ(CHIPS)':
 'DQ25_A': CDS_PINID='DQ25_A';
NET_NAME
'M_L_CPU1_SA_DQ<26>'
 '@T6G_MB_LIB.T6G(SCH_1):M_L_CPU1_SA_DQ'<26>:
 C_SIGNAL='@t6g_mb_lib.t6g(sch_1):m_l_cpu1_sa_dq(26)';
NODE_NAME     U26 AD9
 '@T6G_MB_LIB.T6G(SCH_1):PAGE48_I159@PURE_QUANTA.GENOA_SP5(CHIPS)':
 'MLA_DATA26': CDS_PINID='MLA_DATA26';
NODE_NAME     J37 185
 '@T6G_MB_LIB.T6G(SCH_1):PAGE108_I22@PURE_QUANTA.SCONN288_DDR506112002KQ(CHIPS)':
 'DQ26_A': CDS_PINID='DQ26_A';
NET_NAME
'M_L_CPU1_SA_DQ<27>'
 '@T6G_MB_LIB.T6G(SCH_1):M_L_CPU1_SA_DQ'<27>:
 C_SIGNAL='@t6g_mb_lib.t6g(sch_1):m_l_cpu1_sa_dq(27)';
NODE_NAME     U26 AE10
 '@T6G_MB_LIB.T6G(SCH_1):PAGE48_I159@PURE_QUANTA.GENOA_SP5(CHIPS)':
 'MLA_DATA27': CDS_PINID='MLA_DATA27';
NODE_NAME     J37 187
 '@T6G_MB_LIB.T6G(SCH_1):PAGE108_I22@PURE_QUANTA.SCONN288_DDR506112002KQ(CHIPS)':
 'DQ27_A': CDS_PINID='DQ27_A';
NET_NAME
'M_L_CPU1_SA_DQ<28>'
 '@T6G_MB_LIB.T6G(SCH_1):M_L_CPU1_SA_DQ'<28>:
 C_SIGNAL='@t6g_mb_lib.t6g(sch_1):m_l_cpu1_sa_dq(28)';
NODE_NAME     U26 AG9
 '@T6G_MB_LIB.T6G(SCH_1):PAGE48_I159@PURE_QUANTA.GENOA_SP5(CHIPS)':
 'MLA_DATA28': CDS_PINID='MLA_DATA28';
NODE_NAME     J37 47
 '@T6G_MB_LIB.T6G(SCH_1):PAGE108_I22@PURE_QUANTA.SCONN288_DDR506112002KQ(CHIPS)':
 'DQ28_A': CDS_PINID='DQ28_A';
NET_NAME
'M_L_CPU1_SA_DQ<29>'
 '@T6G_MB_LIB.T6G(SCH_1):M_L_CPU1_SA_DQ'<29>:
 C_SIGNAL='@t6g_mb_lib.t6g(sch_1):m_l_cpu1_sa_dq(29)';
NODE_NAME     U26 AH11
 '@T6G_MB_LIB.T6G(SCH_1):PAGE48_I159@PURE_QUANTA.GENOA_SP5(CHIPS)':
 'MLA_DATA29': CDS_PINID='MLA_DATA29';
NODE_NAME     J37 49
 '@T6G_MB_LIB.T6G(SCH_1):PAGE108_I22@PURE_QUANTA.SCONN288_DDR506112002KQ(CHIPS)':
 'DQ29_A': CDS_PINID='DQ29_A';
NET_NAME
'M_L_CPU1_SA_DQ<2>'
 '@T6G_MB_LIB.T6G(SCH_1):M_L_CPU1_SA_DQ'<2>:
 C_SIGNAL='@t6g_mb_lib.t6g(sch_1):m_l_cpu1_sa_dq(2)';
NODE_NAME     U26 F9
 '@T6G_MB_LIB.T6G(SCH_1):PAGE48_I159@PURE_QUANTA.GENOA_SP5(CHIPS)':
 'MLA_DATA2': CDS_PINID='MLA_DATA2';
NODE_NAME     J37 152
 '@T6G_MB_LIB.T6G(SCH_1):PAGE108_I22@PURE_QUANTA.SCONN288_DDR506112002KQ(CHIPS)':
 'DQ2_A': CDS_PINID='DQ2_A';
NET_NAME
'M_L_CPU1_SA_DQ<30>'
 '@T6G_MB_LIB.T6G(SCH_1):M_L_CPU1_SA_DQ'<30>:
 C_SIGNAL='@t6g_mb_lib.t6g(sch_1):m_l_cpu1_sa_dq(30)';
NODE_NAME     U26 AH9
 '@T6G_MB_LIB.T6G(SCH_1):PAGE48_I159@PURE_QUANTA.GENOA_SP5(CHIPS)':
 'MLA_DATA30': CDS_PINID='MLA_DATA30';
NODE_NAME     J37 192
 '@T6G_MB_LIB.T6G(SCH_1):PAGE108_I22@PURE_QUANTA.SCONN288_DDR506112002KQ(CHIPS)':
 'DQ30_A': CDS_PINID='DQ30_A';
NET_NAME
'M_L_CPU1_SA_DQ<31>'
 '@T6G_MB_LIB.T6G(SCH_1):M_L_CPU1_SA_DQ'<31>:
 C_SIGNAL='@t6g_mb_lib.t6g(sch_1):m_l_cpu1_sa_dq(31)';
NODE_NAME     U26 AJ10
 '@T6G_MB_LIB.T6G(SCH_1):PAGE48_I159@PURE_QUANTA.GENOA_SP5(CHIPS)':
 'MLA_DATA31': CDS_PINID='MLA_DATA31';
NODE_NAME     J37 194
 '@T6G_MB_LIB.T6G(SCH_1):PAGE108_I22@PURE_QUANTA.SCONN288_DDR506112002KQ(CHIPS)':
 'DQ31_A': CDS_PINID='DQ31_A';
NET_NAME
'M_L_CPU1_SA_DQ<3>'
 '@T6G_MB_LIB.T6G(SCH_1):M_L_CPU1_SA_DQ'<3>:
 C_SIGNAL='@t6g_mb_lib.t6g(sch_1):m_l_cpu1_sa_dq(3)';
NODE_NAME     U26 G10
 '@T6G_MB_LIB.T6G(SCH_1):PAGE48_I159@PURE_QUANTA.GENOA_SP5(CHIPS)':
 'MLA_DATA3': CDS_PINID='MLA_DATA3';
NODE_NAME     J37 154
 '@T6G_MB_LIB.T6G(SCH_1):PAGE108_I22@PURE_QUANTA.SCONN288_DDR506112002KQ(CHIPS)':
 'DQ3_A': CDS_PINID='DQ3_A';
NET_NAME
'M_L_CPU1_SA_DQ<4>'
 '@T6G_MB_LIB.T6G(SCH_1):M_L_CPU1_SA_DQ'<4>:
 C_SIGNAL='@t6g_mb_lib.t6g(sch_1):m_l_cpu1_sa_dq(4)';
NODE_NAME     U26 J9
 '@T6G_MB_LIB.T6G(SCH_1):PAGE48_I159@PURE_QUANTA.GENOA_SP5(CHIPS)':
 'MLA_DATA4': CDS_PINID='MLA_DATA4';
NODE_NAME     J37 14
 '@T6G_MB_LIB.T6G(SCH_1):PAGE108_I22@PURE_QUANTA.SCONN288_DDR506112002KQ(CHIPS)':
 'DQ4_A': CDS_PINID='DQ4_A';
NET_NAME
'M_L_CPU1_SA_DQ<5>'
 '@T6G_MB_LIB.T6G(SCH_1):M_L_CPU1_SA_DQ'<5>:
 C_SIGNAL='@t6g_mb_lib.t6g(sch_1):m_l_cpu1_sa_dq(5)';
NODE_NAME     U26 K11
 '@T6G_MB_LIB.T6G(SCH_1):PAGE48_I159@PURE_QUANTA.GENOA_SP5(CHIPS)':
 'MLA_DATA5': CDS_PINID='MLA_DATA5';
NODE_NAME     J37 16
 '@T6G_MB_LIB.T6G(SCH_1):PAGE108_I22@PURE_QUANTA.SCONN288_DDR506112002KQ(CHIPS)':
 'DQ5_A': CDS_PINID='DQ5_A';
NET_NAME
'M_L_CPU1_SA_DQ<6>'
 '@T6G_MB_LIB.T6G(SCH_1):M_L_CPU1_SA_DQ'<6>:
 C_SIGNAL='@t6g_mb_lib.t6g(sch_1):m_l_cpu1_sa_dq(6)';
NODE_NAME     U26 K9
 '@T6G_MB_LIB.T6G(SCH_1):PAGE48_I159@PURE_QUANTA.GENOA_SP5(CHIPS)':
 'MLA_DATA6': CDS_PINID='MLA_DATA6';
NODE_NAME     J37 159
 '@T6G_MB_LIB.T6G(SCH_1):PAGE108_I22@PURE_QUANTA.SCONN288_DDR506112002KQ(CHIPS)':
 'DQ6_A': CDS_PINID='DQ6_A';
NET_NAME
'M_L_CPU1_SA_DQ<7>'
 '@T6G_MB_LIB.T6G(SCH_1):M_L_CPU1_SA_DQ'<7>:
 C_SIGNAL='@t6g_mb_lib.t6g(sch_1):m_l_cpu1_sa_dq(7)';
NODE_NAME     U26 L10
 '@T6G_MB_LIB.T6G(SCH_1):PAGE48_I159@PURE_QUANTA.GENOA_SP5(CHIPS)':
 'MLA_DATA7': CDS_PINID='MLA_DATA7';
NODE_NAME     J37 161
 '@T6G_MB_LIB.T6G(SCH_1):PAGE108_I22@PURE_QUANTA.SCONN288_DDR506112002KQ(CHIPS)':
 'DQ7_A': CDS_PINID='DQ7_A';
NET_NAME
'M_L_CPU1_SA_DQ<8>'
 '@T6G_MB_LIB.T6G(SCH_1):M_L_CPU1_SA_DQ'<8>:
 C_SIGNAL='@t6g_mb_lib.t6g(sch_1):m_l_cpu1_sa_dq(8)';
NODE_NAME     U26 L9
 '@T6G_MB_LIB.T6G(SCH_1):PAGE48_I159@PURE_QUANTA.GENOA_SP5(CHIPS)':
 'MLA_DATA8': CDS_PINID='MLA_DATA8';
NODE_NAME     J37 18
 '@T6G_MB_LIB.T6G(SCH_1):PAGE108_I22@PURE_QUANTA.SCONN288_DDR506112002KQ(CHIPS)':
 'DQ8_A': CDS_PINID='DQ8_A';
NET_NAME
'M_L_CPU1_SA_DQ<9>'
 '@T6G_MB_LIB.T6G(SCH_1):M_L_CPU1_SA_DQ'<9>:
 C_SIGNAL='@t6g_mb_lib.t6g(sch_1):m_l_cpu1_sa_dq(9)';
NODE_NAME     U26 M11
 '@T6G_MB_LIB.T6G(SCH_1):PAGE48_I159@PURE_QUANTA.GENOA_SP5(CHIPS)':
 'MLA_DATA9': CDS_PINID='MLA_DATA9';
NODE_NAME     J37 20
 '@T6G_MB_LIB.T6G(SCH_1):PAGE108_I22@PURE_QUANTA.SCONN288_DDR506112002KQ(CHIPS)':
 'DQ9_A': CDS_PINID='DQ9_A';
NET_NAME
'M_L_CPU1_SA_DQS_DN<0>'
 '@T6G_MB_LIB.T6G(SCH_1):M_L_CPU1_SA_DQS_DN'<0>:
 C_SIGNAL='@t6g_mb_lib.t6g(sch_1):m_l_cpu1_sa_dqs_dn(0)';
NODE_NAME     U26 H9
 '@T6G_MB_LIB.T6G(SCH_1):PAGE48_I159@PURE_QUANTA.GENOA_SP5(CHIPS)':
 'MLA_DQS_L0': CDS_PINID='MLA_DQS_L0';
NODE_NAME     J37 12
 '@T6G_MB_LIB.T6G(SCH_1):PAGE108_I235@PURE_QUANTA.SCONN288_DDR506112002KQ(CHIPS)':
 'DQS0_A_C': CDS_PINID='DQS0_A_C';
NET_NAME
'M_L_CPU1_SA_DQS_DN<1>'
 '@T6G_MB_LIB.T6G(SCH_1):M_L_CPU1_SA_DQS_DN'<1>:
 C_SIGNAL='@t6g_mb_lib.t6g(sch_1):m_l_cpu1_sa_dqs_dn(1)';
NODE_NAME     U26 P9
 '@T6G_MB_LIB.T6G(SCH_1):PAGE48_I159@PURE_QUANTA.GENOA_SP5(CHIPS)':
 'MLA_DQS_L1': CDS_PINID='MLA_DQS_L1';
NODE_NAME     J37 23
 '@T6G_MB_LIB.T6G(SCH_1):PAGE108_I235@PURE_QUANTA.SCONN288_DDR506112002KQ(CHIPS)':
 'DQS1_A_C': CDS_PINID='DQS1_A_C';
NET_NAME
'M_L_CPU1_SA_DQS_DN<2>'
 '@T6G_MB_LIB.T6G(SCH_1):M_L_CPU1_SA_DQS_DN'<2>:
 C_SIGNAL='@t6g_mb_lib.t6g(sch_1):m_l_cpu1_sa_dqs_dn(2)';
NODE_NAME     U26 Y9
 '@T6G_MB_LIB.T6G(SCH_1):PAGE48_I159@PURE_QUANTA.GENOA_SP5(CHIPS)':
 'MLA_DQS_L2': CDS_PINID='MLA_DQS_L2';
NODE_NAME     J37 34
 '@T6G_MB_LIB.T6G(SCH_1):PAGE108_I235@PURE_QUANTA.SCONN288_DDR506112002KQ(CHIPS)':
 'DQS2_A_C': CDS_PINID='DQS2_A_C';
NET_NAME
'M_L_CPU1_SA_DQS_DN<3>'
 '@T6G_MB_LIB.T6G(SCH_1):M_L_CPU1_SA_DQS_DN'<3>:
 C_SIGNAL='@t6g_mb_lib.t6g(sch_1):m_l_cpu1_sa_dqs_dn(3)';
NODE_NAME     U26 AF9
 '@T6G_MB_LIB.T6G(SCH_1):PAGE48_I159@PURE_QUANTA.GENOA_SP5(CHIPS)':
 'MLA_DQS_L3': CDS_PINID='MLA_DQS_L3';
NODE_NAME     J37 45
 '@T6G_MB_LIB.T6G(SCH_1):PAGE108_I235@PURE_QUANTA.SCONN288_DDR506112002KQ(CHIPS)':
 'DQS3_A_C': CDS_PINID='DQS3_A_C';
NET_NAME
'M_L_CPU1_SA_DQS_DN<4>'
 '@T6G_MB_LIB.T6G(SCH_1):M_L_CPU1_SA_DQS_DN'<4>:
 C_SIGNAL='@t6g_mb_lib.t6g(sch_1):m_l_cpu1_sa_dqs_dn(4)';
NODE_NAME     U26 AM9
 '@T6G_MB_LIB.T6G(SCH_1):PAGE48_I159@PURE_QUANTA.GENOA_SP5(CHIPS)':
 'MLA_DQS_L4': CDS_PINID='MLA_DQS_L4';
NODE_NAME     J37 56
 '@T6G_MB_LIB.T6G(SCH_1):PAGE108_I235@PURE_QUANTA.SCONN288_DDR506112002KQ(CHIPS)':
 'DQS4_A_C': CDS_PINID='DQS4_A_C';
NET_NAME
'M_L_CPU1_SA_DQS_DN<5>'
 '@T6G_MB_LIB.T6G(SCH_1):M_L_CPU1_SA_DQS_DN'<5>:
 C_SIGNAL='@t6g_mb_lib.t6g(sch_1):m_l_cpu1_sa_dqs_dn(5)';
NODE_NAME     U26 H11
 '@T6G_MB_LIB.T6G(SCH_1):PAGE48_I159@PURE_QUANTA.GENOA_SP5(CHIPS)':
 'MLA_DQS_L5': CDS_PINID='MLA_DQS_L5';
NODE_NAME     J37 156
 '@T6G_MB_LIB.T6G(SCH_1):PAGE108_I235@PURE_QUANTA.SCONN288_DDR506112002KQ(CHIPS)':
 'DQS5_A_C||TDQS5_A_C||DQS5_A_T||TDQS5_A_T': CDS_PINID='\dqs5_a_c||tdqs5_a_c||dqs5_a_t||tdqs5_a_t\';
NET_NAME
'M_L_CPU1_SA_DQS_DN<6>'
 '@T6G_MB_LIB.T6G(SCH_1):M_L_CPU1_SA_DQS_DN'<6>:
 C_SIGNAL='@t6g_mb_lib.t6g(sch_1):m_l_cpu1_sa_dqs_dn(6)';
NODE_NAME     U26 P11
 '@T6G_MB_LIB.T6G(SCH_1):PAGE48_I159@PURE_QUANTA.GENOA_SP5(CHIPS)':
 'MLA_DQS_L6': CDS_PINID='MLA_DQS_L6';
NODE_NAME     J37 167
 '@T6G_MB_LIB.T6G(SCH_1):PAGE108_I235@PURE_QUANTA.SCONN288_DDR506112002KQ(CHIPS)':
 'DQS6_A_C||TDQS6_A_C||DQS6_A_T||TDQS6_A_T': CDS_PINID='\dqs6_a_c||tdqs6_a_c||dqs6_a_t||tdqs6_a_t\';
NET_NAME
'M_L_CPU1_SA_DQS_DN<7>'
 '@T6G_MB_LIB.T6G(SCH_1):M_L_CPU1_SA_DQS_DN'<7>:
 C_SIGNAL='@t6g_mb_lib.t6g(sch_1):m_l_cpu1_sa_dqs_dn(7)';
NODE_NAME     U26 Y11
 '@T6G_MB_LIB.T6G(SCH_1):PAGE48_I159@PURE_QUANTA.GENOA_SP5(CHIPS)':
 'MLA_DQS_L7': CDS_PINID='MLA_DQS_L7';
NODE_NAME     J37 178
 '@T6G_MB_LIB.T6G(SCH_1):PAGE108_I235@PURE_QUANTA.SCONN288_DDR506112002KQ(CHIPS)':
 'DQS7_A_C||TDQS7_A_C': CDS_PINID='\dqs7_a_c||tdqs7_a_c\';
NET_NAME
'M_L_CPU1_SA_DQS_DN<8>'
 '@T6G_MB_LIB.T6G(SCH_1):M_L_CPU1_SA_DQS_DN'<8>:
 C_SIGNAL='@t6g_mb_lib.t6g(sch_1):m_l_cpu1_sa_dqs_dn(8)';
NODE_NAME     U26 AF11
 '@T6G_MB_LIB.T6G(SCH_1):PAGE48_I159@PURE_QUANTA.GENOA_SP5(CHIPS)':
 'MLA_DQS_L8': CDS_PINID='MLA_DQS_L8';
NODE_NAME     J37 189
 '@T6G_MB_LIB.T6G(SCH_1):PAGE108_I235@PURE_QUANTA.SCONN288_DDR506112002KQ(CHIPS)':
 'DQS8_A_C||TDQS8_A_C': CDS_PINID='\dqs8_a_c||tdqs8_a_c\';
NET_NAME
'M_L_CPU1_SA_DQS_DN<9>'
 '@T6G_MB_LIB.T6G(SCH_1):M_L_CPU1_SA_DQS_DN'<9>:
 C_SIGNAL='@t6g_mb_lib.t6g(sch_1):m_l_cpu1_sa_dqs_dn(9)';
NODE_NAME     U26 AM11
 '@T6G_MB_LIB.T6G(SCH_1):PAGE48_I159@PURE_QUANTA.GENOA_SP5(CHIPS)':
 'MLA_DQS_L9': CDS_PINID='MLA_DQS_L9';
NODE_NAME     J37 200
 '@T6G_MB_LIB.T6G(SCH_1):PAGE108_I235@PURE_QUANTA.SCONN288_DDR506112002KQ(CHIPS)':
 'DQS9_A_C||TDQS9_A_C': CDS_PINID='\dqs9_a_c||tdqs9_a_c\';
NET_NAME
'M_L_CPU1_SA_DQS_DP<0>'
 '@T6G_MB_LIB.T6G(SCH_1):M_L_CPU1_SA_DQS_DP'<0>:
 C_SIGNAL='@t6g_mb_lib.t6g(sch_1):m_l_cpu1_sa_dqs_dp(0)';
NODE_NAME     U26 G9
 '@T6G_MB_LIB.T6G(SCH_1):PAGE48_I159@PURE_QUANTA.GENOA_SP5(CHIPS)':
 'MLA_DQS_H0': CDS_PINID='MLA_DQS_H0';
NODE_NAME     J37 11
 '@T6G_MB_LIB.T6G(SCH_1):PAGE108_I235@PURE_QUANTA.SCONN288_DDR506112002KQ(CHIPS)':
 'DQS0_A_T': CDS_PINID='DQS0_A_T';
NET_NAME
'M_L_CPU1_SA_DQS_DP<1>'
 '@T6G_MB_LIB.T6G(SCH_1):M_L_CPU1_SA_DQS_DP'<1>:
 C_SIGNAL='@t6g_mb_lib.t6g(sch_1):m_l_cpu1_sa_dqs_dp(1)';
NODE_NAME     U26 N9
 '@T6G_MB_LIB.T6G(SCH_1):PAGE48_I159@PURE_QUANTA.GENOA_SP5(CHIPS)':
 'MLA_DQS_H1': CDS_PINID='MLA_DQS_H1';
NODE_NAME     J37 22
 '@T6G_MB_LIB.T6G(SCH_1):PAGE108_I235@PURE_QUANTA.SCONN288_DDR506112002KQ(CHIPS)':
 'DQS1_A_T': CDS_PINID='DQS1_A_T';
NET_NAME
'M_L_CPU1_SA_DQS_DP<2>'
 '@T6G_MB_LIB.T6G(SCH_1):M_L_CPU1_SA_DQS_DP'<2>:
 C_SIGNAL='@t6g_mb_lib.t6g(sch_1):m_l_cpu1_sa_dqs_dp(2)';
NODE_NAME     U26 W9
 '@T6G_MB_LIB.T6G(SCH_1):PAGE48_I159@PURE_QUANTA.GENOA_SP5(CHIPS)':
 'MLA_DQS_H2': CDS_PINID='MLA_DQS_H2';
NODE_NAME     J37 33
 '@T6G_MB_LIB.T6G(SCH_1):PAGE108_I235@PURE_QUANTA.SCONN288_DDR506112002KQ(CHIPS)':
 'DQS2_A_T': CDS_PINID='DQS2_A_T';
NET_NAME
'M_L_CPU1_SA_DQS_DP<3>'
 '@T6G_MB_LIB.T6G(SCH_1):M_L_CPU1_SA_DQS_DP'<3>:
 C_SIGNAL='@t6g_mb_lib.t6g(sch_1):m_l_cpu1_sa_dqs_dp(3)';
NODE_NAME     U26 AE9
 '@T6G_MB_LIB.T6G(SCH_1):PAGE48_I159@PURE_QUANTA.GENOA_SP5(CHIPS)':
 'MLA_DQS_H3': CDS_PINID='MLA_DQS_H3';
NODE_NAME     J37 44
 '@T6G_MB_LIB.T6G(SCH_1):PAGE108_I235@PURE_QUANTA.SCONN288_DDR506112002KQ(CHIPS)':
 'DQS3_A_T': CDS_PINID='DQS3_A_T';
NET_NAME
'M_L_CPU1_SA_DQS_DP<4>'
 '@T6G_MB_LIB.T6G(SCH_1):M_L_CPU1_SA_DQS_DP'<4>:
 C_SIGNAL='@t6g_mb_lib.t6g(sch_1):m_l_cpu1_sa_dqs_dp(4)';
NODE_NAME     U26 AL9
 '@T6G_MB_LIB.T6G(SCH_1):PAGE48_I159@PURE_QUANTA.GENOA_SP5(CHIPS)':
 'MLA_DQS_H4': CDS_PINID='MLA_DQS_H4';
NODE_NAME     J37 55
 '@T6G_MB_LIB.T6G(SCH_1):PAGE108_I235@PURE_QUANTA.SCONN288_DDR506112002KQ(CHIPS)':
 'DQS4_A_T': CDS_PINID='DQS4_A_T';
NET_NAME
'M_L_CPU1_SA_DQS_DP<5>'
 '@T6G_MB_LIB.T6G(SCH_1):M_L_CPU1_SA_DQS_DP'<5>:
 C_SIGNAL='@t6g_mb_lib.t6g(sch_1):m_l_cpu1_sa_dqs_dp(5)';
NODE_NAME     U26 J10
 '@T6G_MB_LIB.T6G(SCH_1):PAGE48_I159@PURE_QUANTA.GENOA_SP5(CHIPS)':
 'MLA_DQS_H5': CDS_PINID='MLA_DQS_H5';
NODE_NAME     J37 157
 '@T6G_MB_LIB.T6G(SCH_1):PAGE108_I235@PURE_QUANTA.SCONN288_DDR506112002KQ(CHIPS)':
 'DQS5_A_T||TDQS5_A_T': CDS_PINID='\dqs5_a_t||tdqs5_a_t\';
NET_NAME
'M_L_CPU1_SA_DQS_DP<6>'
 '@T6G_MB_LIB.T6G(SCH_1):M_L_CPU1_SA_DQS_DP'<6>:
 C_SIGNAL='@t6g_mb_lib.t6g(sch_1):m_l_cpu1_sa_dqs_dp(6)';
NODE_NAME     U26 R10
 '@T6G_MB_LIB.T6G(SCH_1):PAGE48_I159@PURE_QUANTA.GENOA_SP5(CHIPS)':
 'MLA_DQS_H6': CDS_PINID='MLA_DQS_H6';
NODE_NAME     J37 168
 '@T6G_MB_LIB.T6G(SCH_1):PAGE108_I235@PURE_QUANTA.SCONN288_DDR506112002KQ(CHIPS)':
 'DQS6_A_T||TDQS6_A_T': CDS_PINID='\dqs6_a_t||tdqs6_a_t\';
NET_NAME
'M_L_CPU1_SA_DQS_DP<7>'
 '@T6G_MB_LIB.T6G(SCH_1):M_L_CPU1_SA_DQS_DP'<7>:
 C_SIGNAL='@t6g_mb_lib.t6g(sch_1):m_l_cpu1_sa_dqs_dp(7)';
NODE_NAME     U26 AA10
 '@T6G_MB_LIB.T6G(SCH_1):PAGE48_I159@PURE_QUANTA.GENOA_SP5(CHIPS)':
 'MLA_DQS_H7': CDS_PINID='MLA_DQS_H7';
NODE_NAME     J37 179
 '@T6G_MB_LIB.T6G(SCH_1):PAGE108_I235@PURE_QUANTA.SCONN288_DDR506112002KQ(CHIPS)':
 'DQS7_A_T||TDQS7_A_T': CDS_PINID='\dqs7_a_t||tdqs7_a_t\';
NET_NAME
'M_L_CPU1_SA_DQS_DP<8>'
 '@T6G_MB_LIB.T6G(SCH_1):M_L_CPU1_SA_DQS_DP'<8>:
 C_SIGNAL='@t6g_mb_lib.t6g(sch_1):m_l_cpu1_sa_dqs_dp(8)';
NODE_NAME     U26 AG10
 '@T6G_MB_LIB.T6G(SCH_1):PAGE48_I159@PURE_QUANTA.GENOA_SP5(CHIPS)':
 'MLA_DQS_H8': CDS_PINID='MLA_DQS_H8';
NODE_NAME     J37 190
 '@T6G_MB_LIB.T6G(SCH_1):PAGE108_I235@PURE_QUANTA.SCONN288_DDR506112002KQ(CHIPS)':
 'DQS8_A_T||TDQS8_A_T': CDS_PINID='\dqs8_a_t||tdqs8_a_t\';
NET_NAME
'M_L_CPU1_SA_DQS_DP<9>'
 '@T6G_MB_LIB.T6G(SCH_1):M_L_CPU1_SA_DQS_DP'<9>:
 C_SIGNAL='@t6g_mb_lib.t6g(sch_1):m_l_cpu1_sa_dqs_dp(9)';
NODE_NAME     U26 AN10
 '@T6G_MB_LIB.T6G(SCH_1):PAGE48_I159@PURE_QUANTA.GENOA_SP5(CHIPS)':
 'MLA_DQS_H9': CDS_PINID='MLA_DQS_H9';
NODE_NAME     J37 201
 '@T6G_MB_LIB.T6G(SCH_1):PAGE108_I235@PURE_QUANTA.SCONN288_DDR506112002KQ(CHIPS)':
 'DQS9_A_T||TDQS9_A_T': CDS_PINID='\dqs9_a_t||tdqs9_a_t\';
NET_NAME
'M_L_CPU1_SA_PAR'
 '@T6G_MB_LIB.T6G(SCH_1):M_L_CPU1_SA_PAR':
 C_SIGNAL='@t6g_mb_lib.t6g(sch_1):m_l_cpu1_sa_par';
NODE_NAME     U26 BC10
 '@T6G_MB_LIB.T6G(SCH_1):PAGE48_I159@PURE_QUANTA.GENOA_SP5(CHIPS)':
 'MLA_PAR': CDS_PINID='MLA_PAR';
NODE_NAME     J37 74
 '@T6G_MB_LIB.T6G(SCH_1):PAGE108_I22@PURE_QUANTA.SCONN288_DDR506112002KQ(CHIPS)':
 'PAR_A': CDS_PINID='PAR_A';
NET_NAME
'M_L_CPU1_SA_RSP<0>'
 '@T6G_MB_LIB.T6G(SCH_1):M_L_CPU1_SA_RSP'<0>:
 C_SIGNAL='@t6g_mb_lib.t6g(sch_1):m_l_cpu1_sa_rsp(0)';
NODE_NAME     U26 BN10
 '@T6G_MB_LIB.T6G(SCH_1):PAGE48_I159@PURE_QUANTA.GENOA_SP5(CHIPS)':
 'MLA0_RSP_L': CDS_PINID='MLA0_RSP_L';
NODE_NAME     J37 86
 '@T6G_MB_LIB.T6G(SCH_1):PAGE108_I22@PURE_QUANTA.SCONN288_DDR506112002KQ(CHIPS)':
 'LBD||RSP_A_N': CDS_PINID='\lbd||rsp_a_n\';
NET_NAME
'M_L_CPU1_SB_CA<0>'
 '@T6G_MB_LIB.T6G(SCH_1):M_L_CPU1_SB_CA'<0>:
 C_SIGNAL='@t6g_mb_lib.t6g(sch_1):m_l_cpu1_sb_ca(0)';
NODE_NAME     U26 BG10
 '@T6G_MB_LIB.T6G(SCH_1):PAGE48_I159@PURE_QUANTA.GENOA_SP5(CHIPS)':
 'MLB_CA0': CDS_PINID='MLB_CA0';
NODE_NAME     J37 76
 '@T6G_MB_LIB.T6G(SCH_1):PAGE108_I22@PURE_QUANTA.SCONN288_DDR506112002KQ(CHIPS)':
 'CA0_B': CDS_PINID='CA0_B';
NET_NAME
'M_L_CPU1_SB_CA<1>'
 '@T6G_MB_LIB.T6G(SCH_1):M_L_CPU1_SB_CA'<1>:
 C_SIGNAL='@t6g_mb_lib.t6g(sch_1):m_l_cpu1_sb_ca(1)';
NODE_NAME     U26 BH11
 '@T6G_MB_LIB.T6G(SCH_1):PAGE48_I159@PURE_QUANTA.GENOA_SP5(CHIPS)':
 'MLB_CA1': CDS_PINID='MLB_CA1';
NODE_NAME     J37 221
 '@T6G_MB_LIB.T6G(SCH_1):PAGE108_I22@PURE_QUANTA.SCONN288_DDR506112002KQ(CHIPS)':
 'CA1_B': CDS_PINID='CA1_B';
NET_NAME
'M_L_CPU1_SB_CA<2>'
 '@T6G_MB_LIB.T6G(SCH_1):M_L_CPU1_SB_CA'<2>:
 C_SIGNAL='@t6g_mb_lib.t6g(sch_1):m_l_cpu1_sb_ca(2)';
NODE_NAME     U26 BH9
 '@T6G_MB_LIB.T6G(SCH_1):PAGE48_I159@PURE_QUANTA.GENOA_SP5(CHIPS)':
 'MLB_CA2': CDS_PINID='MLB_CA2';
NODE_NAME     J37 78
 '@T6G_MB_LIB.T6G(SCH_1):PAGE108_I22@PURE_QUANTA.SCONN288_DDR506112002KQ(CHIPS)':
 'CA2_B': CDS_PINID='CA2_B';
NET_NAME
'M_L_CPU1_SB_CA<3>'
 '@T6G_MB_LIB.T6G(SCH_1):M_L_CPU1_SB_CA'<3>:
 C_SIGNAL='@t6g_mb_lib.t6g(sch_1):m_l_cpu1_sb_ca(3)';
NODE_NAME     U26 BJ9
 '@T6G_MB_LIB.T6G(SCH_1):PAGE48_I159@PURE_QUANTA.GENOA_SP5(CHIPS)':
 'MLB_CA3': CDS_PINID='MLB_CA3';
NODE_NAME     J37 223
 '@T6G_MB_LIB.T6G(SCH_1):PAGE108_I22@PURE_QUANTA.SCONN288_DDR506112002KQ(CHIPS)':
 'CA3_B': CDS_PINID='CA3_B';
NET_NAME
'M_L_CPU1_SB_CA<4>'
 '@T6G_MB_LIB.T6G(SCH_1):M_L_CPU1_SB_CA'<4>:
 C_SIGNAL='@t6g_mb_lib.t6g(sch_1):m_l_cpu1_sb_ca(4)';
NODE_NAME     U26 BJ10
 '@T6G_MB_LIB.T6G(SCH_1):PAGE48_I159@PURE_QUANTA.GENOA_SP5(CHIPS)':
 'MLB_CA4': CDS_PINID='MLB_CA4';
NODE_NAME     J37 80
 '@T6G_MB_LIB.T6G(SCH_1):PAGE108_I22@PURE_QUANTA.SCONN288_DDR506112002KQ(CHIPS)':
 'CA4_B': CDS_PINID='CA4_B';
NET_NAME
'M_L_CPU1_SB_CA<5>'
 '@T6G_MB_LIB.T6G(SCH_1):M_L_CPU1_SB_CA'<5>:
 C_SIGNAL='@t6g_mb_lib.t6g(sch_1):m_l_cpu1_sb_ca(5)';
NODE_NAME     U26 BK11
 '@T6G_MB_LIB.T6G(SCH_1):PAGE48_I159@PURE_QUANTA.GENOA_SP5(CHIPS)':
 'MLB_CA5': CDS_PINID='MLB_CA5';
NODE_NAME     J37 225
 '@T6G_MB_LIB.T6G(SCH_1):PAGE108_I22@PURE_QUANTA.SCONN288_DDR506112002KQ(CHIPS)':
 'CA5_B': CDS_PINID='CA5_B';
NET_NAME
'M_L_CPU1_SB_CA<6>'
 '@T6G_MB_LIB.T6G(SCH_1):M_L_CPU1_SB_CA'<6>:
 C_SIGNAL='@t6g_mb_lib.t6g(sch_1):m_l_cpu1_sb_ca(6)';
NODE_NAME     U26 BK9
 '@T6G_MB_LIB.T6G(SCH_1):PAGE48_I159@PURE_QUANTA.GENOA_SP5(CHIPS)':
 'MLB_CA6': CDS_PINID='MLB_CA6';
NODE_NAME     J37 82
 '@T6G_MB_LIB.T6G(SCH_1):PAGE108_I22@PURE_QUANTA.SCONN288_DDR506112002KQ(CHIPS)':
 'CA6_B': CDS_PINID='CA6_B';
NET_NAME
'M_L_CPU1_SB_CB<0>'
 '@T6G_MB_LIB.T6G(SCH_1):M_L_CPU1_SB_CB'<0>:
 C_SIGNAL='@t6g_mb_lib.t6g(sch_1):m_l_cpu1_sb_cb(0)';
NODE_NAME     U26 BY9
 '@T6G_MB_LIB.T6G(SCH_1):PAGE48_I159@PURE_QUANTA.GENOA_SP5(CHIPS)':
 'MLB_CHECK0': CDS_PINID='MLB_CHECK0';
NODE_NAME     J37 96
 '@T6G_MB_LIB.T6G(SCH_1):PAGE108_I22@PURE_QUANTA.SCONN288_DDR506112002KQ(CHIPS)':
 'CB0_B': CDS_PINID='CB0_B';
NET_NAME
'M_L_CPU1_SB_CB<1>'
 '@T6G_MB_LIB.T6G(SCH_1):M_L_CPU1_SB_CB'<1>:
 C_SIGNAL='@t6g_mb_lib.t6g(sch_1):m_l_cpu1_sb_cb(1)';
NODE_NAME     U26 CA10
 '@T6G_MB_LIB.T6G(SCH_1):PAGE48_I159@PURE_QUANTA.GENOA_SP5(CHIPS)':
 'MLB_CHECK1': CDS_PINID='MLB_CHECK1';
NODE_NAME     J37 98
 '@T6G_MB_LIB.T6G(SCH_1):PAGE108_I22@PURE_QUANTA.SCONN288_DDR506112002KQ(CHIPS)':
 'CB1_B': CDS_PINID='CB1_B';
NET_NAME
'M_L_CPU1_SB_CB<2>'
 '@T6G_MB_LIB.T6G(SCH_1):M_L_CPU1_SB_CB'<2>:
 C_SIGNAL='@t6g_mb_lib.t6g(sch_1):m_l_cpu1_sb_cb(2)';
NODE_NAME     U26 CA9
 '@T6G_MB_LIB.T6G(SCH_1):PAGE48_I159@PURE_QUANTA.GENOA_SP5(CHIPS)':
 'MLB_CHECK2': CDS_PINID='MLB_CHECK2';
NODE_NAME     J37 241
 '@T6G_MB_LIB.T6G(SCH_1):PAGE108_I22@PURE_QUANTA.SCONN288_DDR506112002KQ(CHIPS)':
 'CB2_B': CDS_PINID='CB2_B';
NET_NAME
'M_L_CPU1_SB_CB<3>'
 '@T6G_MB_LIB.T6G(SCH_1):M_L_CPU1_SB_CB'<3>:
 C_SIGNAL='@t6g_mb_lib.t6g(sch_1):m_l_cpu1_sb_cb(3)';
NODE_NAME     U26 CB11
 '@T6G_MB_LIB.T6G(SCH_1):PAGE48_I159@PURE_QUANTA.GENOA_SP5(CHIPS)':
 'MLB_CHECK3': CDS_PINID='MLB_CHECK3';
NODE_NAME     J37 243
 '@T6G_MB_LIB.T6G(SCH_1):PAGE108_I22@PURE_QUANTA.SCONN288_DDR506112002KQ(CHIPS)':
 'CB3_B': CDS_PINID='CB3_B';
NET_NAME
'M_L_CPU1_SB_CB<4>'
 '@T6G_MB_LIB.T6G(SCH_1):M_L_CPU1_SB_CB'<4>:
 C_SIGNAL='@t6g_mb_lib.t6g(sch_1):m_l_cpu1_sb_cb(4)';
NODE_NAME     U26 BT9
 '@T6G_MB_LIB.T6G(SCH_1):PAGE48_I159@PURE_QUANTA.GENOA_SP5(CHIPS)':
 'MLB_CHECK4': CDS_PINID='MLB_CHECK4';
NODE_NAME     J37 89
 '@T6G_MB_LIB.T6G(SCH_1):PAGE108_I22@PURE_QUANTA.SCONN288_DDR506112002KQ(CHIPS)':
 'CB4_B': CDS_PINID='CB4_B';
NET_NAME
'M_L_CPU1_SB_CB<5>'
 '@T6G_MB_LIB.T6G(SCH_1):M_L_CPU1_SB_CB'<5>:
 C_SIGNAL='@t6g_mb_lib.t6g(sch_1):m_l_cpu1_sb_cb(5)';
NODE_NAME     U26 BU10
 '@T6G_MB_LIB.T6G(SCH_1):PAGE48_I159@PURE_QUANTA.GENOA_SP5(CHIPS)':
 'MLB_CHECK5': CDS_PINID='MLB_CHECK5';
NODE_NAME     J37 91
 '@T6G_MB_LIB.T6G(SCH_1):PAGE108_I22@PURE_QUANTA.SCONN288_DDR506112002KQ(CHIPS)':
 'CB5_B': CDS_PINID='CB5_B';
NET_NAME
'M_L_CPU1_SB_CB<6>'
 '@T6G_MB_LIB.T6G(SCH_1):M_L_CPU1_SB_CB'<6>:
 C_SIGNAL='@t6g_mb_lib.t6g(sch_1):m_l_cpu1_sb_cb(6)';
NODE_NAME     U26 BU9
 '@T6G_MB_LIB.T6G(SCH_1):PAGE48_I159@PURE_QUANTA.GENOA_SP5(CHIPS)':
 'MLB_CHECK6': CDS_PINID='MLB_CHECK6';
NODE_NAME     J37 234
 '@T6G_MB_LIB.T6G(SCH_1):PAGE108_I22@PURE_QUANTA.SCONN288_DDR506112002KQ(CHIPS)':
 'CB6_B': CDS_PINID='CB6_B';
NET_NAME
'M_L_CPU1_SB_CB<7>'
 '@T6G_MB_LIB.T6G(SCH_1):M_L_CPU1_SB_CB'<7>:
 C_SIGNAL='@t6g_mb_lib.t6g(sch_1):m_l_cpu1_sb_cb(7)';
NODE_NAME     U26 BV11
 '@T6G_MB_LIB.T6G(SCH_1):PAGE48_I159@PURE_QUANTA.GENOA_SP5(CHIPS)':
 'MLB_CHECK7': CDS_PINID='MLB_CHECK7';
NODE_NAME     J37 236
 '@T6G_MB_LIB.T6G(SCH_1):PAGE108_I22@PURE_QUANTA.SCONN288_DDR506112002KQ(CHIPS)':
 'CB7_B': CDS_PINID='CB7_B';
NET_NAME
'M_L_CPU1_SB_CS_N<0>'
 '@T6G_MB_LIB.T6G(SCH_1):M_L_CPU1_SB_CS_N'<0>:
 C_SIGNAL='@t6g_mb_lib.t6g(sch_1):m_l_cpu1_sb_cs_n(0)';
NODE_NAME     U26 BM11
 '@T6G_MB_LIB.T6G(SCH_1):PAGE48_I159@PURE_QUANTA.GENOA_SP5(CHIPS)':
 'MLB0_CS_L0': CDS_PINID='MLB0_CS_L0';
NODE_NAME     J37 84
 '@T6G_MB_LIB.T6G(SCH_1):PAGE108_I22@PURE_QUANTA.SCONN288_DDR506112002KQ(CHIPS)':
 'CS0_B_N': CDS_PINID='CS0_B_N';
NET_NAME
'M_L_CPU1_SB_CS_N<1>'
 '@T6G_MB_LIB.T6G(SCH_1):M_L_CPU1_SB_CS_N'<1>:
 C_SIGNAL='@t6g_mb_lib.t6g(sch_1):m_l_cpu1_sb_cs_n(1)';
NODE_NAME     U26 BN9
 '@T6G_MB_LIB.T6G(SCH_1):PAGE48_I159@PURE_QUANTA.GENOA_SP5(CHIPS)':
 'MLB0_CS_L1': CDS_PINID='MLB0_CS_L1';
NODE_NAME     J37 229
 '@T6G_MB_LIB.T6G(SCH_1):PAGE108_I22@PURE_QUANTA.SCONN288_DDR506112002KQ(CHIPS)':
 'CS1_B_N': CDS_PINID='CS1_B_N';
NET_NAME
'M_L_CPU1_SB_DQ<0>'
 '@T6G_MB_LIB.T6G(SCH_1):M_L_CPU1_SB_DQ'<0>:
 C_SIGNAL='@t6g_mb_lib.t6g(sch_1):m_l_cpu1_sb_dq(0)';
NODE_NAME     U26 CB9
 '@T6G_MB_LIB.T6G(SCH_1):PAGE48_I159@PURE_QUANTA.GENOA_SP5(CHIPS)':
 'MLB_DATA0': CDS_PINID='MLB_DATA0';
NODE_NAME     J37 100
 '@T6G_MB_LIB.T6G(SCH_1):PAGE108_I22@PURE_QUANTA.SCONN288_DDR506112002KQ(CHIPS)':
 'DQ0_B': CDS_PINID='DQ0_B';
NET_NAME
'M_L_CPU1_SB_DQ<10>'
 '@T6G_MB_LIB.T6G(SCH_1):M_L_CPU1_SB_DQ'<10>:
 C_SIGNAL='@t6g_mb_lib.t6g(sch_1):m_l_cpu1_sb_dq(10)';
NODE_NAME     U26 CJ9
 '@T6G_MB_LIB.T6G(SCH_1):PAGE48_I159@PURE_QUANTA.GENOA_SP5(CHIPS)':
 'MLB_DATA10': CDS_PINID='MLB_DATA10';
NODE_NAME     J37 256
 '@T6G_MB_LIB.T6G(SCH_1):PAGE108_I22@PURE_QUANTA.SCONN288_DDR506112002KQ(CHIPS)':
 'DQ10_B': CDS_PINID='DQ10_B';
NET_NAME
'M_L_CPU1_SB_DQ<11>'
 '@T6G_MB_LIB.T6G(SCH_1):M_L_CPU1_SB_DQ'<11>:
 C_SIGNAL='@t6g_mb_lib.t6g(sch_1):m_l_cpu1_sb_dq(11)';
NODE_NAME     U26 CK11
 '@T6G_MB_LIB.T6G(SCH_1):PAGE48_I159@PURE_QUANTA.GENOA_SP5(CHIPS)':
 'MLB_DATA11': CDS_PINID='MLB_DATA11';
NODE_NAME     J37 258
 '@T6G_MB_LIB.T6G(SCH_1):PAGE108_I22@PURE_QUANTA.SCONN288_DDR506112002KQ(CHIPS)':
 'DQ11_B': CDS_PINID='DQ11_B';
NET_NAME
'M_L_CPU1_SB_DQ<12>'
 '@T6G_MB_LIB.T6G(SCH_1):M_L_CPU1_SB_DQ'<12>:
 C_SIGNAL='@t6g_mb_lib.t6g(sch_1):m_l_cpu1_sb_dq(12)';
NODE_NAME     U26 CM9
 '@T6G_MB_LIB.T6G(SCH_1):PAGE48_I159@PURE_QUANTA.GENOA_SP5(CHIPS)':
 'MLB_DATA12': CDS_PINID='MLB_DATA12';
NODE_NAME     J37 118
 '@T6G_MB_LIB.T6G(SCH_1):PAGE108_I22@PURE_QUANTA.SCONN288_DDR506112002KQ(CHIPS)':
 'DQ12_B': CDS_PINID='DQ12_B';
NET_NAME
'M_L_CPU1_SB_DQ<13>'
 '@T6G_MB_LIB.T6G(SCH_1):M_L_CPU1_SB_DQ'<13>:
 C_SIGNAL='@t6g_mb_lib.t6g(sch_1):m_l_cpu1_sb_dq(13)';
NODE_NAME     U26 CN10
 '@T6G_MB_LIB.T6G(SCH_1):PAGE48_I159@PURE_QUANTA.GENOA_SP5(CHIPS)':
 'MLB_DATA13': CDS_PINID='MLB_DATA13';
NODE_NAME     J37 120
 '@T6G_MB_LIB.T6G(SCH_1):PAGE108_I22@PURE_QUANTA.SCONN288_DDR506112002KQ(CHIPS)':
 'DQ13_B': CDS_PINID='DQ13_B';
NET_NAME
'M_L_CPU1_SB_DQ<14>'
 '@T6G_MB_LIB.T6G(SCH_1):M_L_CPU1_SB_DQ'<14>:
 C_SIGNAL='@t6g_mb_lib.t6g(sch_1):m_l_cpu1_sb_dq(14)';
NODE_NAME     U26 CN9
 '@T6G_MB_LIB.T6G(SCH_1):PAGE48_I159@PURE_QUANTA.GENOA_SP5(CHIPS)':
 'MLB_DATA14': CDS_PINID='MLB_DATA14';
NODE_NAME     J37 263
 '@T6G_MB_LIB.T6G(SCH_1):PAGE108_I22@PURE_QUANTA.SCONN288_DDR506112002KQ(CHIPS)':
 'DQ14_B': CDS_PINID='DQ14_B';
NET_NAME
'M_L_CPU1_SB_DQ<15>'
 '@T6G_MB_LIB.T6G(SCH_1):M_L_CPU1_SB_DQ'<15>:
 C_SIGNAL='@t6g_mb_lib.t6g(sch_1):m_l_cpu1_sb_dq(15)';
NODE_NAME     U26 CP11
 '@T6G_MB_LIB.T6G(SCH_1):PAGE48_I159@PURE_QUANTA.GENOA_SP5(CHIPS)':
 'MLB_DATA15': CDS_PINID='MLB_DATA15';
NODE_NAME     J37 265
 '@T6G_MB_LIB.T6G(SCH_1):PAGE108_I22@PURE_QUANTA.SCONN288_DDR506112002KQ(CHIPS)':
 'DQ15_B': CDS_PINID='DQ15_B';
NET_NAME
'M_L_CPU1_SB_DQ<16>'
 '@T6G_MB_LIB.T6G(SCH_1):M_L_CPU1_SB_DQ'<16>:
 C_SIGNAL='@t6g_mb_lib.t6g(sch_1):m_l_cpu1_sb_dq(16)';
NODE_NAME     U26 CP9
 '@T6G_MB_LIB.T6G(SCH_1):PAGE48_I159@PURE_QUANTA.GENOA_SP5(CHIPS)':
 'MLB_DATA16': CDS_PINID='MLB_DATA16';
NODE_NAME     J37 122
 '@T6G_MB_LIB.T6G(SCH_1):PAGE108_I22@PURE_QUANTA.SCONN288_DDR506112002KQ(CHIPS)':
 'DQ16_B': CDS_PINID='DQ16_B';
NET_NAME
'M_L_CPU1_SB_DQ<17>'
 '@T6G_MB_LIB.T6G(SCH_1):M_L_CPU1_SB_DQ'<17>:
 C_SIGNAL='@t6g_mb_lib.t6g(sch_1):m_l_cpu1_sb_dq(17)';
NODE_NAME     U26 CR10
 '@T6G_MB_LIB.T6G(SCH_1):PAGE48_I159@PURE_QUANTA.GENOA_SP5(CHIPS)':
 'MLB_DATA17': CDS_PINID='MLB_DATA17';
NODE_NAME     J37 124
 '@T6G_MB_LIB.T6G(SCH_1):PAGE108_I22@PURE_QUANTA.SCONN288_DDR506112002KQ(CHIPS)':
 'DQ17_B': CDS_PINID='DQ17_B';
NET_NAME
'M_L_CPU1_SB_DQ<18>'
 '@T6G_MB_LIB.T6G(SCH_1):M_L_CPU1_SB_DQ'<18>:
 C_SIGNAL='@t6g_mb_lib.t6g(sch_1):m_l_cpu1_sb_dq(18)';
NODE_NAME     U26 CR9
 '@T6G_MB_LIB.T6G(SCH_1):PAGE48_I159@PURE_QUANTA.GENOA_SP5(CHIPS)':
 'MLB_DATA18': CDS_PINID='MLB_DATA18';
NODE_NAME     J37 267
 '@T6G_MB_LIB.T6G(SCH_1):PAGE108_I22@PURE_QUANTA.SCONN288_DDR506112002KQ(CHIPS)':
 'DQ18_B': CDS_PINID='DQ18_B';
NET_NAME
'M_L_CPU1_SB_DQ<19>'
 '@T6G_MB_LIB.T6G(SCH_1):M_L_CPU1_SB_DQ'<19>:
 C_SIGNAL='@t6g_mb_lib.t6g(sch_1):m_l_cpu1_sb_dq(19)';
NODE_NAME     U26 CT11
 '@T6G_MB_LIB.T6G(SCH_1):PAGE48_I159@PURE_QUANTA.GENOA_SP5(CHIPS)':
 'MLB_DATA19': CDS_PINID='MLB_DATA19';
NODE_NAME     J37 269
 '@T6G_MB_LIB.T6G(SCH_1):PAGE108_I22@PURE_QUANTA.SCONN288_DDR506112002KQ(CHIPS)':
 'DQ19_B': CDS_PINID='DQ19_B';
NET_NAME
'M_L_CPU1_SB_DQ<1>'
 '@T6G_MB_LIB.T6G(SCH_1):M_L_CPU1_SB_DQ'<1>:
 C_SIGNAL='@t6g_mb_lib.t6g(sch_1):m_l_cpu1_sb_dq(1)';
NODE_NAME     U26 CC10
 '@T6G_MB_LIB.T6G(SCH_1):PAGE48_I159@PURE_QUANTA.GENOA_SP5(CHIPS)':
 'MLB_DATA1': CDS_PINID='MLB_DATA1';
NODE_NAME     J37 102
 '@T6G_MB_LIB.T6G(SCH_1):PAGE108_I22@PURE_QUANTA.SCONN288_DDR506112002KQ(CHIPS)':
 'DQ1_B': CDS_PINID='DQ1_B';
NET_NAME
'M_L_CPU1_SB_DQ<20>'
 '@T6G_MB_LIB.T6G(SCH_1):M_L_CPU1_SB_DQ'<20>:
 C_SIGNAL='@t6g_mb_lib.t6g(sch_1):m_l_cpu1_sb_dq(20)';
NODE_NAME     U26 CV9
 '@T6G_MB_LIB.T6G(SCH_1):PAGE48_I159@PURE_QUANTA.GENOA_SP5(CHIPS)':
 'MLB_DATA20': CDS_PINID='MLB_DATA20';
NODE_NAME     J37 129
 '@T6G_MB_LIB.T6G(SCH_1):PAGE108_I22@PURE_QUANTA.SCONN288_DDR506112002KQ(CHIPS)':
 'DQ20_B': CDS_PINID='DQ20_B';
NET_NAME
'M_L_CPU1_SB_DQ<21>'
 '@T6G_MB_LIB.T6G(SCH_1):M_L_CPU1_SB_DQ'<21>:
 C_SIGNAL='@t6g_mb_lib.t6g(sch_1):m_l_cpu1_sb_dq(21)';
NODE_NAME     U26 CW10
 '@T6G_MB_LIB.T6G(SCH_1):PAGE48_I159@PURE_QUANTA.GENOA_SP5(CHIPS)':
 'MLB_DATA21': CDS_PINID='MLB_DATA21';
NODE_NAME     J37 131
 '@T6G_MB_LIB.T6G(SCH_1):PAGE108_I22@PURE_QUANTA.SCONN288_DDR506112002KQ(CHIPS)':
 'DQ21_B': CDS_PINID='DQ21_B';
NET_NAME
'M_L_CPU1_SB_DQ<22>'
 '@T6G_MB_LIB.T6G(SCH_1):M_L_CPU1_SB_DQ'<22>:
 C_SIGNAL='@t6g_mb_lib.t6g(sch_1):m_l_cpu1_sb_dq(22)';
NODE_NAME     U26 CW9
 '@T6G_MB_LIB.T6G(SCH_1):PAGE48_I159@PURE_QUANTA.GENOA_SP5(CHIPS)':
 'MLB_DATA22': CDS_PINID='MLB_DATA22';
NODE_NAME     J37 274
 '@T6G_MB_LIB.T6G(SCH_1):PAGE108_I22@PURE_QUANTA.SCONN288_DDR506112002KQ(CHIPS)':
 'DQ22_B': CDS_PINID='DQ22_B';
NET_NAME
'M_L_CPU1_SB_DQ<23>'
 '@T6G_MB_LIB.T6G(SCH_1):M_L_CPU1_SB_DQ'<23>:
 C_SIGNAL='@t6g_mb_lib.t6g(sch_1):m_l_cpu1_sb_dq(23)';
NODE_NAME     U26 CY11
 '@T6G_MB_LIB.T6G(SCH_1):PAGE48_I159@PURE_QUANTA.GENOA_SP5(CHIPS)':
 'MLB_DATA23': CDS_PINID='MLB_DATA23';
NODE_NAME     J37 276
 '@T6G_MB_LIB.T6G(SCH_1):PAGE108_I22@PURE_QUANTA.SCONN288_DDR506112002KQ(CHIPS)':
 'DQ23_B': CDS_PINID='DQ23_B';
NET_NAME
'M_L_CPU1_SB_DQ<24>'
 '@T6G_MB_LIB.T6G(SCH_1):M_L_CPU1_SB_DQ'<24>:
 C_SIGNAL='@t6g_mb_lib.t6g(sch_1):m_l_cpu1_sb_dq(24)';
NODE_NAME     U26 CY9
 '@T6G_MB_LIB.T6G(SCH_1):PAGE48_I159@PURE_QUANTA.GENOA_SP5(CHIPS)':
 'MLB_DATA24': CDS_PINID='MLB_DATA24';
NODE_NAME     J37 133
 '@T6G_MB_LIB.T6G(SCH_1):PAGE108_I22@PURE_QUANTA.SCONN288_DDR506112002KQ(CHIPS)':
 'DQ24_B': CDS_PINID='DQ24_B';
NET_NAME
'M_L_CPU1_SB_DQ<25>'
 '@T6G_MB_LIB.T6G(SCH_1):M_L_CPU1_SB_DQ'<25>:
 C_SIGNAL='@t6g_mb_lib.t6g(sch_1):m_l_cpu1_sb_dq(25)';
NODE_NAME     U26 DA10
 '@T6G_MB_LIB.T6G(SCH_1):PAGE48_I159@PURE_QUANTA.GENOA_SP5(CHIPS)':
 'MLB_DATA25': CDS_PINID='MLB_DATA25';
NODE_NAME     J37 135
 '@T6G_MB_LIB.T6G(SCH_1):PAGE108_I22@PURE_QUANTA.SCONN288_DDR506112002KQ(CHIPS)':
 'DQ25_B': CDS_PINID='DQ25_B';
NET_NAME
'M_L_CPU1_SB_DQ<26>'
 '@T6G_MB_LIB.T6G(SCH_1):M_L_CPU1_SB_DQ'<26>:
 C_SIGNAL='@t6g_mb_lib.t6g(sch_1):m_l_cpu1_sb_dq(26)';
NODE_NAME     U26 DA9
 '@T6G_MB_LIB.T6G(SCH_1):PAGE48_I159@PURE_QUANTA.GENOA_SP5(CHIPS)':
 'MLB_DATA26': CDS_PINID='MLB_DATA26';
NODE_NAME     J37 278
 '@T6G_MB_LIB.T6G(SCH_1):PAGE108_I22@PURE_QUANTA.SCONN288_DDR506112002KQ(CHIPS)':
 'DQ26_B': CDS_PINID='DQ26_B';
NET_NAME
'M_L_CPU1_SB_DQ<27>'
 '@T6G_MB_LIB.T6G(SCH_1):M_L_CPU1_SB_DQ'<27>:
 C_SIGNAL='@t6g_mb_lib.t6g(sch_1):m_l_cpu1_sb_dq(27)';
NODE_NAME     U26 DB11
 '@T6G_MB_LIB.T6G(SCH_1):PAGE48_I159@PURE_QUANTA.GENOA_SP5(CHIPS)':
 'MLB_DATA27': CDS_PINID='MLB_DATA27';
NODE_NAME     J37 280
 '@T6G_MB_LIB.T6G(SCH_1):PAGE108_I22@PURE_QUANTA.SCONN288_DDR506112002KQ(CHIPS)':
 'DQ27_B': CDS_PINID='DQ27_B';
NET_NAME
'M_L_CPU1_SB_DQ<28>'
 '@T6G_MB_LIB.T6G(SCH_1):M_L_CPU1_SB_DQ'<28>:
 C_SIGNAL='@t6g_mb_lib.t6g(sch_1):m_l_cpu1_sb_dq(28)';
NODE_NAME     U26 DD9
 '@T6G_MB_LIB.T6G(SCH_1):PAGE48_I159@PURE_QUANTA.GENOA_SP5(CHIPS)':
 'MLB_DATA28': CDS_PINID='MLB_DATA28';
NODE_NAME     J37 140
 '@T6G_MB_LIB.T6G(SCH_1):PAGE108_I22@PURE_QUANTA.SCONN288_DDR506112002KQ(CHIPS)':
 'DQ28_B': CDS_PINID='DQ28_B';
NET_NAME
'M_L_CPU1_SB_DQ<29>'
 '@T6G_MB_LIB.T6G(SCH_1):M_L_CPU1_SB_DQ'<29>:
 C_SIGNAL='@t6g_mb_lib.t6g(sch_1):m_l_cpu1_sb_dq(29)';
NODE_NAME     U26 DE10
 '@T6G_MB_LIB.T6G(SCH_1):PAGE48_I159@PURE_QUANTA.GENOA_SP5(CHIPS)':
 'MLB_DATA29': CDS_PINID='MLB_DATA29';
NODE_NAME     J37 142
 '@T6G_MB_LIB.T6G(SCH_1):PAGE108_I22@PURE_QUANTA.SCONN288_DDR506112002KQ(CHIPS)':
 'DQ29_B': CDS_PINID='DQ29_B';
NET_NAME
'M_L_CPU1_SB_DQ<2>'
 '@T6G_MB_LIB.T6G(SCH_1):M_L_CPU1_SB_DQ'<2>:
 C_SIGNAL='@t6g_mb_lib.t6g(sch_1):m_l_cpu1_sb_dq(2)';
NODE_NAME     U26 CC9
 '@T6G_MB_LIB.T6G(SCH_1):PAGE48_I159@PURE_QUANTA.GENOA_SP5(CHIPS)':
 'MLB_DATA2': CDS_PINID='MLB_DATA2';
NODE_NAME     J37 245
 '@T6G_MB_LIB.T6G(SCH_1):PAGE108_I22@PURE_QUANTA.SCONN288_DDR506112002KQ(CHIPS)':
 'DQ2_B': CDS_PINID='DQ2_B';
NET_NAME
'M_L_CPU1_SB_DQ<30>'
 '@T6G_MB_LIB.T6G(SCH_1):M_L_CPU1_SB_DQ'<30>:
 C_SIGNAL='@t6g_mb_lib.t6g(sch_1):m_l_cpu1_sb_dq(30)';
NODE_NAME     U26 DE9
 '@T6G_MB_LIB.T6G(SCH_1):PAGE48_I159@PURE_QUANTA.GENOA_SP5(CHIPS)':
 'MLB_DATA30': CDS_PINID='MLB_DATA30';
NODE_NAME     J37 285
 '@T6G_MB_LIB.T6G(SCH_1):PAGE108_I22@PURE_QUANTA.SCONN288_DDR506112002KQ(CHIPS)':
 'DQ30_B': CDS_PINID='DQ30_B';
NET_NAME
'M_L_CPU1_SB_DQ<31>'
 '@T6G_MB_LIB.T6G(SCH_1):M_L_CPU1_SB_DQ'<31>:
 C_SIGNAL='@t6g_mb_lib.t6g(sch_1):m_l_cpu1_sb_dq(31)';
NODE_NAME     U26 DF9
 '@T6G_MB_LIB.T6G(SCH_1):PAGE48_I159@PURE_QUANTA.GENOA_SP5(CHIPS)':
 'MLB_DATA31': CDS_PINID='MLB_DATA31';
NODE_NAME     J37 287
 '@T6G_MB_LIB.T6G(SCH_1):PAGE108_I22@PURE_QUANTA.SCONN288_DDR506112002KQ(CHIPS)':
 'DQ31_B': CDS_PINID='DQ31_B';
NET_NAME
'M_L_CPU1_SB_DQ<3>'
 '@T6G_MB_LIB.T6G(SCH_1):M_L_CPU1_SB_DQ'<3>:
 C_SIGNAL='@t6g_mb_lib.t6g(sch_1):m_l_cpu1_sb_dq(3)';
NODE_NAME     U26 CD11
 '@T6G_MB_LIB.T6G(SCH_1):PAGE48_I159@PURE_QUANTA.GENOA_SP5(CHIPS)':
 'MLB_DATA3': CDS_PINID='MLB_DATA3';
NODE_NAME     J37 247
 '@T6G_MB_LIB.T6G(SCH_1):PAGE108_I22@PURE_QUANTA.SCONN288_DDR506112002KQ(CHIPS)':
 'DQ3_B': CDS_PINID='DQ3_B';
NET_NAME
'M_L_CPU1_SB_DQ<4>'
 '@T6G_MB_LIB.T6G(SCH_1):M_L_CPU1_SB_DQ'<4>:
 C_SIGNAL='@t6g_mb_lib.t6g(sch_1):m_l_cpu1_sb_dq(4)';
NODE_NAME     U26 CF9
 '@T6G_MB_LIB.T6G(SCH_1):PAGE48_I159@PURE_QUANTA.GENOA_SP5(CHIPS)':
 'MLB_DATA4': CDS_PINID='MLB_DATA4';
NODE_NAME     J37 107
 '@T6G_MB_LIB.T6G(SCH_1):PAGE108_I22@PURE_QUANTA.SCONN288_DDR506112002KQ(CHIPS)':
 'DQ4_B': CDS_PINID='DQ4_B';
NET_NAME
'M_L_CPU1_SB_DQ<5>'
 '@T6G_MB_LIB.T6G(SCH_1):M_L_CPU1_SB_DQ'<5>:
 C_SIGNAL='@t6g_mb_lib.t6g(sch_1):m_l_cpu1_sb_dq(5)';
NODE_NAME     U26 CG10
 '@T6G_MB_LIB.T6G(SCH_1):PAGE48_I159@PURE_QUANTA.GENOA_SP5(CHIPS)':
 'MLB_DATA5': CDS_PINID='MLB_DATA5';
NODE_NAME     J37 109
 '@T6G_MB_LIB.T6G(SCH_1):PAGE108_I22@PURE_QUANTA.SCONN288_DDR506112002KQ(CHIPS)':
 'DQ5_B': CDS_PINID='DQ5_B';
NET_NAME
'M_L_CPU1_SB_DQ<6>'
 '@T6G_MB_LIB.T6G(SCH_1):M_L_CPU1_SB_DQ'<6>:
 C_SIGNAL='@t6g_mb_lib.t6g(sch_1):m_l_cpu1_sb_dq(6)';
NODE_NAME     U26 CG9
 '@T6G_MB_LIB.T6G(SCH_1):PAGE48_I159@PURE_QUANTA.GENOA_SP5(CHIPS)':
 'MLB_DATA6': CDS_PINID='MLB_DATA6';
NODE_NAME     J37 252
 '@T6G_MB_LIB.T6G(SCH_1):PAGE108_I22@PURE_QUANTA.SCONN288_DDR506112002KQ(CHIPS)':
 'DQ6_B': CDS_PINID='DQ6_B';
NET_NAME
'M_L_CPU1_SB_DQ<7>'
 '@T6G_MB_LIB.T6G(SCH_1):M_L_CPU1_SB_DQ'<7>:
 C_SIGNAL='@t6g_mb_lib.t6g(sch_1):m_l_cpu1_sb_dq(7)';
NODE_NAME     U26 CH11
 '@T6G_MB_LIB.T6G(SCH_1):PAGE48_I159@PURE_QUANTA.GENOA_SP5(CHIPS)':
 'MLB_DATA7': CDS_PINID='MLB_DATA7';
NODE_NAME     J37 254
 '@T6G_MB_LIB.T6G(SCH_1):PAGE108_I22@PURE_QUANTA.SCONN288_DDR506112002KQ(CHIPS)':
 'DQ7_B': CDS_PINID='DQ7_B';
NET_NAME
'M_L_CPU1_SB_DQ<8>'
 '@T6G_MB_LIB.T6G(SCH_1):M_L_CPU1_SB_DQ'<8>:
 C_SIGNAL='@t6g_mb_lib.t6g(sch_1):m_l_cpu1_sb_dq(8)';
NODE_NAME     U26 CH9
 '@T6G_MB_LIB.T6G(SCH_1):PAGE48_I159@PURE_QUANTA.GENOA_SP5(CHIPS)':
 'MLB_DATA8': CDS_PINID='MLB_DATA8';
NODE_NAME     J37 111
 '@T6G_MB_LIB.T6G(SCH_1):PAGE108_I22@PURE_QUANTA.SCONN288_DDR506112002KQ(CHIPS)':
 'DQ8_B': CDS_PINID='DQ8_B';
NET_NAME
'M_L_CPU1_SB_DQ<9>'
 '@T6G_MB_LIB.T6G(SCH_1):M_L_CPU1_SB_DQ'<9>:
 C_SIGNAL='@t6g_mb_lib.t6g(sch_1):m_l_cpu1_sb_dq(9)';
NODE_NAME     U26 CJ10
 '@T6G_MB_LIB.T6G(SCH_1):PAGE48_I159@PURE_QUANTA.GENOA_SP5(CHIPS)':
 'MLB_DATA9': CDS_PINID='MLB_DATA9';
NODE_NAME     J37 113
 '@T6G_MB_LIB.T6G(SCH_1):PAGE108_I22@PURE_QUANTA.SCONN288_DDR506112002KQ(CHIPS)':
 'DQ9_B': CDS_PINID='DQ9_B';
NET_NAME
'M_L_CPU1_SB_DQS_DN<0>'
 '@T6G_MB_LIB.T6G(SCH_1):M_L_CPU1_SB_DQS_DN'<0>:
 C_SIGNAL='@t6g_mb_lib.t6g(sch_1):m_l_cpu1_sb_dqs_dn(0)';
NODE_NAME     U26 CE9
 '@T6G_MB_LIB.T6G(SCH_1):PAGE48_I159@PURE_QUANTA.GENOA_SP5(CHIPS)':
 'MLB_DQS_L0': CDS_PINID='MLB_DQS_L0';
NODE_NAME     J37 105
 '@T6G_MB_LIB.T6G(SCH_1):PAGE108_I235@PURE_QUANTA.SCONN288_DDR506112002KQ(CHIPS)':
 'DQS0_B_C': CDS_PINID='DQS0_B_C';
NET_NAME
'M_L_CPU1_SB_DQS_DN<1>'
 '@T6G_MB_LIB.T6G(SCH_1):M_L_CPU1_SB_DQS_DN'<1>:
 C_SIGNAL='@t6g_mb_lib.t6g(sch_1):m_l_cpu1_sb_dqs_dn(1)';
NODE_NAME     U26 CL9
 '@T6G_MB_LIB.T6G(SCH_1):PAGE48_I159@PURE_QUANTA.GENOA_SP5(CHIPS)':
 'MLB_DQS_L1': CDS_PINID='MLB_DQS_L1';
NODE_NAME     J37 116
 '@T6G_MB_LIB.T6G(SCH_1):PAGE108_I235@PURE_QUANTA.SCONN288_DDR506112002KQ(CHIPS)':
 'DQS1_B_C': CDS_PINID='DQS1_B_C';
NET_NAME
'M_L_CPU1_SB_DQS_DN<2>'
 '@T6G_MB_LIB.T6G(SCH_1):M_L_CPU1_SB_DQS_DN'<2>:
 C_SIGNAL='@t6g_mb_lib.t6g(sch_1):m_l_cpu1_sb_dqs_dn(2)';
NODE_NAME     U26 CU9
 '@T6G_MB_LIB.T6G(SCH_1):PAGE48_I159@PURE_QUANTA.GENOA_SP5(CHIPS)':
 'MLB_DQS_L2': CDS_PINID='MLB_DQS_L2';
NODE_NAME     J37 127
 '@T6G_MB_LIB.T6G(SCH_1):PAGE108_I235@PURE_QUANTA.SCONN288_DDR506112002KQ(CHIPS)':
 'DQS2_B_C': CDS_PINID='DQS2_B_C';
NET_NAME
'M_L_CPU1_SB_DQS_DN<3>'
 '@T6G_MB_LIB.T6G(SCH_1):M_L_CPU1_SB_DQS_DN'<3>:
 C_SIGNAL='@t6g_mb_lib.t6g(sch_1):m_l_cpu1_sb_dqs_dn(3)';
NODE_NAME     U26 DC9
 '@T6G_MB_LIB.T6G(SCH_1):PAGE48_I159@PURE_QUANTA.GENOA_SP5(CHIPS)':
 'MLB_DQS_L3': CDS_PINID='MLB_DQS_L3';
NODE_NAME     J37 138
 '@T6G_MB_LIB.T6G(SCH_1):PAGE108_I235@PURE_QUANTA.SCONN288_DDR506112002KQ(CHIPS)':
 'DQS3_B_C': CDS_PINID='DQS3_B_C';
NET_NAME
'M_L_CPU1_SB_DQS_DN<4>'
 '@T6G_MB_LIB.T6G(SCH_1):M_L_CPU1_SB_DQS_DN'<4>:
 C_SIGNAL='@t6g_mb_lib.t6g(sch_1):m_l_cpu1_sb_dqs_dn(4)';
NODE_NAME     U26 BW10
 '@T6G_MB_LIB.T6G(SCH_1):PAGE48_I159@PURE_QUANTA.GENOA_SP5(CHIPS)':
 'MLB_DQS_L4': CDS_PINID='MLB_DQS_L4';
NODE_NAME     J37 238
 '@T6G_MB_LIB.T6G(SCH_1):PAGE108_I235@PURE_QUANTA.SCONN288_DDR506112002KQ(CHIPS)':
 'DQS4_B_C': CDS_PINID='DQS4_B_C';
NET_NAME
'M_L_CPU1_SB_DQS_DN<5>'
 '@T6G_MB_LIB.T6G(SCH_1):M_L_CPU1_SB_DQS_DN'<5>:
 C_SIGNAL='@t6g_mb_lib.t6g(sch_1):m_l_cpu1_sb_dqs_dn(5)';
NODE_NAME     U26 CE10
 '@T6G_MB_LIB.T6G(SCH_1):PAGE48_I159@PURE_QUANTA.GENOA_SP5(CHIPS)':
 'MLB_DQS_L5': CDS_PINID='MLB_DQS_L5';
NODE_NAME     J37 249
 '@T6G_MB_LIB.T6G(SCH_1):PAGE108_I235@PURE_QUANTA.SCONN288_DDR506112002KQ(CHIPS)':
 'DQS5_B_C||TDQS5_B_C': CDS_PINID='\dqs5_b_c||tdqs5_b_c\';
NET_NAME
'M_L_CPU1_SB_DQS_DN<6>'
 '@T6G_MB_LIB.T6G(SCH_1):M_L_CPU1_SB_DQS_DN'<6>:
 C_SIGNAL='@t6g_mb_lib.t6g(sch_1):m_l_cpu1_sb_dqs_dn(6)';
NODE_NAME     U26 CL10
 '@T6G_MB_LIB.T6G(SCH_1):PAGE48_I159@PURE_QUANTA.GENOA_SP5(CHIPS)':
 'MLB_DQS_L6': CDS_PINID='MLB_DQS_L6';
NODE_NAME     J37 260
 '@T6G_MB_LIB.T6G(SCH_1):PAGE108_I235@PURE_QUANTA.SCONN288_DDR506112002KQ(CHIPS)':
 'DQS6_B_C||TDQS6_B_C': CDS_PINID='\dqs6_b_c||tdqs6_b_c\';
NET_NAME
'M_L_CPU1_SB_DQS_DN<7>'
 '@T6G_MB_LIB.T6G(SCH_1):M_L_CPU1_SB_DQS_DN'<7>:
 C_SIGNAL='@t6g_mb_lib.t6g(sch_1):m_l_cpu1_sb_dqs_dn(7)';
NODE_NAME     U26 CU10
 '@T6G_MB_LIB.T6G(SCH_1):PAGE48_I159@PURE_QUANTA.GENOA_SP5(CHIPS)':
 'MLB_DQS_L7': CDS_PINID='MLB_DQS_L7';
NODE_NAME     J37 271
 '@T6G_MB_LIB.T6G(SCH_1):PAGE108_I235@PURE_QUANTA.SCONN288_DDR506112002KQ(CHIPS)':
 'DQS7_B_C||TDQS7_B_C': CDS_PINID='\dqs7_b_c||tdqs7_b_c\';
NET_NAME
'M_L_CPU1_SB_DQS_DN<8>'
 '@T6G_MB_LIB.T6G(SCH_1):M_L_CPU1_SB_DQS_DN'<8>:
 C_SIGNAL='@t6g_mb_lib.t6g(sch_1):m_l_cpu1_sb_dqs_dn(8)';
NODE_NAME     U26 DC10
 '@T6G_MB_LIB.T6G(SCH_1):PAGE48_I159@PURE_QUANTA.GENOA_SP5(CHIPS)':
 'MLB_DQS_L8': CDS_PINID='MLB_DQS_L8';
NODE_NAME     J37 282
 '@T6G_MB_LIB.T6G(SCH_1):PAGE108_I235@PURE_QUANTA.SCONN288_DDR506112002KQ(CHIPS)':
 'DQS8_B_C||TDQS8_B_C': CDS_PINID='\dqs8_b_c||tdqs8_b_c\';
NET_NAME
'M_L_CPU1_SB_DQS_DN<9>'
 '@T6G_MB_LIB.T6G(SCH_1):M_L_CPU1_SB_DQS_DN'<9>:
 C_SIGNAL='@t6g_mb_lib.t6g(sch_1):m_l_cpu1_sb_dqs_dn(9)';
NODE_NAME     U26 BW9
 '@T6G_MB_LIB.T6G(SCH_1):PAGE48_I159@PURE_QUANTA.GENOA_SP5(CHIPS)':
 'MLB_DQS_L9': CDS_PINID='MLB_DQS_L9';
NODE_NAME     J37 94
 '@T6G_MB_LIB.T6G(SCH_1):PAGE108_I235@PURE_QUANTA.SCONN288_DDR506112002KQ(CHIPS)':
 'DQS9_B_C||TDQS9_B_C': CDS_PINID='\dqs9_b_c||tdqs9_b_c\';
NET_NAME
'M_L_CPU1_SB_DQS_DP<0>'
 '@T6G_MB_LIB.T6G(SCH_1):M_L_CPU1_SB_DQS_DP'<0>:
 C_SIGNAL='@t6g_mb_lib.t6g(sch_1):m_l_cpu1_sb_dqs_dp(0)';
NODE_NAME     U26 CD9
 '@T6G_MB_LIB.T6G(SCH_1):PAGE48_I159@PURE_QUANTA.GENOA_SP5(CHIPS)':
 'MLB_DQS_H0': CDS_PINID='MLB_DQS_H0';
NODE_NAME     J37 104
 '@T6G_MB_LIB.T6G(SCH_1):PAGE108_I235@PURE_QUANTA.SCONN288_DDR506112002KQ(CHIPS)':
 'DQS0_B_T': CDS_PINID='DQS0_B_T';
NET_NAME
'M_L_CPU1_SB_DQS_DP<1>'
 '@T6G_MB_LIB.T6G(SCH_1):M_L_CPU1_SB_DQS_DP'<1>:
 C_SIGNAL='@t6g_mb_lib.t6g(sch_1):m_l_cpu1_sb_dqs_dp(1)';
NODE_NAME     U26 CK9
 '@T6G_MB_LIB.T6G(SCH_1):PAGE48_I159@PURE_QUANTA.GENOA_SP5(CHIPS)':
 'MLB_DQS_H1': CDS_PINID='MLB_DQS_H1';
NODE_NAME     J37 115
 '@T6G_MB_LIB.T6G(SCH_1):PAGE108_I235@PURE_QUANTA.SCONN288_DDR506112002KQ(CHIPS)':
 'DQS1_B_T': CDS_PINID='DQS1_B_T';
NET_NAME
'M_L_CPU1_SB_DQS_DP<2>'
 '@T6G_MB_LIB.T6G(SCH_1):M_L_CPU1_SB_DQS_DP'<2>:
 C_SIGNAL='@t6g_mb_lib.t6g(sch_1):m_l_cpu1_sb_dqs_dp(2)';
NODE_NAME     U26 CT9
 '@T6G_MB_LIB.T6G(SCH_1):PAGE48_I159@PURE_QUANTA.GENOA_SP5(CHIPS)':
 'MLB_DQS_H2': CDS_PINID='MLB_DQS_H2';
NODE_NAME     J37 126
 '@T6G_MB_LIB.T6G(SCH_1):PAGE108_I235@PURE_QUANTA.SCONN288_DDR506112002KQ(CHIPS)':
 'DQS2_B_T': CDS_PINID='DQS2_B_T';
NET_NAME
'M_L_CPU1_SB_DQS_DP<3>'
 '@T6G_MB_LIB.T6G(SCH_1):M_L_CPU1_SB_DQS_DP'<3>:
 C_SIGNAL='@t6g_mb_lib.t6g(sch_1):m_l_cpu1_sb_dqs_dp(3)';
NODE_NAME     U26 DB9
 '@T6G_MB_LIB.T6G(SCH_1):PAGE48_I159@PURE_QUANTA.GENOA_SP5(CHIPS)':
 'MLB_DQS_H3': CDS_PINID='MLB_DQS_H3';
NODE_NAME     J37 137
 '@T6G_MB_LIB.T6G(SCH_1):PAGE108_I235@PURE_QUANTA.SCONN288_DDR506112002KQ(CHIPS)':
 'DQS3_B_T': CDS_PINID='DQS3_B_T';
NET_NAME
'M_L_CPU1_SB_DQS_DP<4>'
 '@T6G_MB_LIB.T6G(SCH_1):M_L_CPU1_SB_DQS_DP'<4>:
 C_SIGNAL='@t6g_mb_lib.t6g(sch_1):m_l_cpu1_sb_dqs_dp(4)';
NODE_NAME     U26 BY11
 '@T6G_MB_LIB.T6G(SCH_1):PAGE48_I159@PURE_QUANTA.GENOA_SP5(CHIPS)':
 'MLB_DQS_H4': CDS_PINID='MLB_DQS_H4';
NODE_NAME     J37 239
 '@T6G_MB_LIB.T6G(SCH_1):PAGE108_I235@PURE_QUANTA.SCONN288_DDR506112002KQ(CHIPS)':
 'DQS4_B_T': CDS_PINID='DQS4_B_T';
NET_NAME
'M_L_CPU1_SB_DQS_DP<5>'
 '@T6G_MB_LIB.T6G(SCH_1):M_L_CPU1_SB_DQS_DP'<5>:
 C_SIGNAL='@t6g_mb_lib.t6g(sch_1):m_l_cpu1_sb_dqs_dp(5)';
NODE_NAME     U26 CF11
 '@T6G_MB_LIB.T6G(SCH_1):PAGE48_I159@PURE_QUANTA.GENOA_SP5(CHIPS)':
 'MLB_DQS_H5': CDS_PINID='MLB_DQS_H5';
NODE_NAME     J37 250
 '@T6G_MB_LIB.T6G(SCH_1):PAGE108_I235@PURE_QUANTA.SCONN288_DDR506112002KQ(CHIPS)':
 'DQS5_B_T||TDQS5_B_T': CDS_PINID='\dqs5_b_t||tdqs5_b_t\';
NET_NAME
'M_L_CPU1_SB_DQS_DP<6>'
 '@T6G_MB_LIB.T6G(SCH_1):M_L_CPU1_SB_DQS_DP'<6>:
 C_SIGNAL='@t6g_mb_lib.t6g(sch_1):m_l_cpu1_sb_dqs_dp(6)';
NODE_NAME     U26 CM11
 '@T6G_MB_LIB.T6G(SCH_1):PAGE48_I159@PURE_QUANTA.GENOA_SP5(CHIPS)':
 'MLB_DQS_H6': CDS_PINID='MLB_DQS_H6';
NODE_NAME     J37 261
 '@T6G_MB_LIB.T6G(SCH_1):PAGE108_I235@PURE_QUANTA.SCONN288_DDR506112002KQ(CHIPS)':
 'DQS6_B_T||TDQS6_B_T': CDS_PINID='\dqs6_b_t||tdqs6_b_t\';
NET_NAME
'M_L_CPU1_SB_DQS_DP<7>'
 '@T6G_MB_LIB.T6G(SCH_1):M_L_CPU1_SB_DQS_DP'<7>:
 C_SIGNAL='@t6g_mb_lib.t6g(sch_1):m_l_cpu1_sb_dqs_dp(7)';
NODE_NAME     U26 CV11
 '@T6G_MB_LIB.T6G(SCH_1):PAGE48_I159@PURE_QUANTA.GENOA_SP5(CHIPS)':
 'MLB_DQS_H7': CDS_PINID='MLB_DQS_H7';
NODE_NAME     J37 272
 '@T6G_MB_LIB.T6G(SCH_1):PAGE108_I235@PURE_QUANTA.SCONN288_DDR506112002KQ(CHIPS)':
 'DQS7_B_T||TDQS7_B_T': CDS_PINID='\dqs7_b_t||tdqs7_b_t\';
NET_NAME
'M_L_CPU1_SB_DQS_DP<8>'
 '@T6G_MB_LIB.T6G(SCH_1):M_L_CPU1_SB_DQS_DP'<8>:
 C_SIGNAL='@t6g_mb_lib.t6g(sch_1):m_l_cpu1_sb_dqs_dp(8)';
NODE_NAME     U26 DD11
 '@T6G_MB_LIB.T6G(SCH_1):PAGE48_I159@PURE_QUANTA.GENOA_SP5(CHIPS)':
 'MLB_DQS_H8': CDS_PINID='MLB_DQS_H8';
NODE_NAME     J37 283
 '@T6G_MB_LIB.T6G(SCH_1):PAGE108_I235@PURE_QUANTA.SCONN288_DDR506112002KQ(CHIPS)':
 'DQS8_B_T||TDQS8_B_T': CDS_PINID='\dqs8_b_t||tdqs8_b_t\';
NET_NAME
'M_L_CPU1_SB_DQS_DP<9>'
 '@T6G_MB_LIB.T6G(SCH_1):M_L_CPU1_SB_DQS_DP'<9>:
 C_SIGNAL='@t6g_mb_lib.t6g(sch_1):m_l_cpu1_sb_dqs_dp(9)';
NODE_NAME     U26 BV9
 '@T6G_MB_LIB.T6G(SCH_1):PAGE48_I159@PURE_QUANTA.GENOA_SP5(CHIPS)':
 'MLB_DQS_H9': CDS_PINID='MLB_DQS_H9';
NODE_NAME     J37 93
 '@T6G_MB_LIB.T6G(SCH_1):PAGE108_I235@PURE_QUANTA.SCONN288_DDR506112002KQ(CHIPS)':
 'DQS9_B_T||TDQS9_B_T||DBI4_B_N': CDS_PINID='\dqs9_b_t||tdqs9_b_t||dbi4_b_n\';
NET_NAME
'M_L_CPU1_SB_PAR'
 '@T6G_MB_LIB.T6G(SCH_1):M_L_CPU1_SB_PAR':
 C_SIGNAL='@t6g_mb_lib.t6g(sch_1):m_l_cpu1_sb_par';
NODE_NAME     U26 BL10
 '@T6G_MB_LIB.T6G(SCH_1):PAGE48_I159@PURE_QUANTA.GENOA_SP5(CHIPS)':
 'MLB_PAR': CDS_PINID='MLB_PAR';
NODE_NAME     J37 227
 '@T6G_MB_LIB.T6G(SCH_1):PAGE108_I22@PURE_QUANTA.SCONN288_DDR506112002KQ(CHIPS)':
 'PAR_B': CDS_PINID='PAR_B';
NET_NAME
'M_L_CPU1_SB_RSP<0>'
 '@T6G_MB_LIB.T6G(SCH_1):M_L_CPU1_SB_RSP'<0>:
 C_SIGNAL='@t6g_mb_lib.t6g(sch_1):m_l_cpu1_sb_rsp(0)';
NODE_NAME     U26 BP9
 '@T6G_MB_LIB.T6G(SCH_1):PAGE48_I159@PURE_QUANTA.GENOA_SP5(CHIPS)':
 'MLB0_RSP_L': CDS_PINID='MLB0_RSP_L';
NODE_NAME     J37 87
 '@T6G_MB_LIB.T6G(SCH_1):PAGE108_I22@PURE_QUANTA.SCONN288_DDR506112002KQ(CHIPS)':
 'LBS||RSP_B_N': CDS_PINID='\lbs||rsp_b_n\';
NET_NAME
'NC'
 'NC':
 C_SIGNAL='NC';
NODE_NAME     U25 BF74
 '@T6G_MB_LIB.T6G(SCH_1):PAGE10_I200@PURE_QUANTA.GENOA_SP5(CHIPS)':
 'MA1_CLK_H': CDS_PINID='MA1_CLK_H';
NODE_NAME     U25 BG74
 '@T6G_MB_LIB.T6G(SCH_1):PAGE10_I200@PURE_QUANTA.GENOA_SP5(CHIPS)':
 'MA1_CLK_L': CDS_PINID='MA1_CLK_L';
NODE_NAME     U25 AU74
 '@T6G_MB_LIB.T6G(SCH_1):PAGE10_I200@PURE_QUANTA.GENOA_SP5(CHIPS)':
 'MAA1_CS_L0': CDS_PINID='MAA1_CS_L0';
NODE_NAME     U25 AV72
 '@T6G_MB_LIB.T6G(SCH_1):PAGE10_I200@PURE_QUANTA.GENOA_SP5(CHIPS)':
 'MAA1_CS_L1': CDS_PINID='MAA1_CS_L1';
NODE_NAME     U25 BP72
 '@T6G_MB_LIB.T6G(SCH_1):PAGE10_I200@PURE_QUANTA.GENOA_SP5(CHIPS)':
 'MAA1_RSP_L': CDS_PINID='MAA1_RSP_L';
NODE_NAME     U25 BL73
 '@T6G_MB_LIB.T6G(SCH_1):PAGE10_I200@PURE_QUANTA.GENOA_SP5(CHIPS)':
 'MAB1_CS_L0': CDS_PINID='MAB1_CS_L0';
NODE_NAME     U25 BM74
 '@T6G_MB_LIB.T6G(SCH_1):PAGE10_I200@PURE_QUANTA.GENOA_SP5(CHIPS)':
 'MAB1_CS_L1': CDS_PINID='MAB1_CS_L1';
NODE_NAME     U25 BR74
 '@T6G_MB_LIB.T6G(SCH_1):PAGE10_I200@PURE_QUANTA.GENOA_SP5(CHIPS)':
 'MAB1_RSP_L': CDS_PINID='MAB1_RSP_L';
NODE_NAME     U25 BF63
 '@T6G_MB_LIB.T6G(SCH_1):PAGE11_I171@PURE_QUANTA.GENOA_SP5(CHIPS)':
 'MB1_CLK_H': CDS_PINID='MB1_CLK_H';
NODE_NAME     U25 BG64
 '@T6G_MB_LIB.T6G(SCH_1):PAGE11_I171@PURE_QUANTA.GENOA_SP5(CHIPS)':
 'MB1_CLK_L': CDS_PINID='MB1_CLK_L';
NODE_NAME     U25 AU64
 '@T6G_MB_LIB.T6G(SCH_1):PAGE11_I171@PURE_QUANTA.GENOA_SP5(CHIPS)':
 'MBA1_CS_L0': CDS_PINID='MBA1_CS_L0';
NODE_NAME     U25 AV62
 '@T6G_MB_LIB.T6G(SCH_1):PAGE11_I171@PURE_QUANTA.GENOA_SP5(CHIPS)':
 'MBA1_CS_L1': CDS_PINID='MBA1_CS_L1';
NODE_NAME     U25 BP62
 '@T6G_MB_LIB.T6G(SCH_1):PAGE11_I171@PURE_QUANTA.GENOA_SP5(CHIPS)':
 'MBA1_RSP_L': CDS_PINID='MBA1_RSP_L';
NODE_NAME     U25 BL62
 '@T6G_MB_LIB.T6G(SCH_1):PAGE11_I171@PURE_QUANTA.GENOA_SP5(CHIPS)':
 'MBB1_CS_L0': CDS_PINID='MBB1_CS_L0';
NODE_NAME     U25 BM63
 '@T6G_MB_LIB.T6G(SCH_1):PAGE11_I171@PURE_QUANTA.GENOA_SP5(CHIPS)':
 'MBB1_CS_L1': CDS_PINID='MBB1_CS_L1';
NODE_NAME     U25 BR64
 '@T6G_MB_LIB.T6G(SCH_1):PAGE11_I171@PURE_QUANTA.GENOA_SP5(CHIPS)':
 'MBB1_RSP_L': CDS_PINID='MBB1_RSP_L';
NODE_NAME     U25 BF56
 '@T6G_MB_LIB.T6G(SCH_1):PAGE12_I159@PURE_QUANTA.GENOA_SP5(CHIPS)':
 'MC1_CLK_H': CDS_PINID='MC1_CLK_H';
NODE_NAME     U25 BG57
 '@T6G_MB_LIB.T6G(SCH_1):PAGE12_I159@PURE_QUANTA.GENOA_SP5(CHIPS)':
 'MC1_CLK_L': CDS_PINID='MC1_CLK_L';
NODE_NAME     U25 AU57
 '@T6G_MB_LIB.T6G(SCH_1):PAGE12_I159@PURE_QUANTA.GENOA_SP5(CHIPS)':
 'MCA1_CS_L0': CDS_PINID='MCA1_CS_L0';
NODE_NAME     U25 AV55
 '@T6G_MB_LIB.T6G(SCH_1):PAGE12_I159@PURE_QUANTA.GENOA_SP5(CHIPS)':
 'MCA1_CS_L1': CDS_PINID='MCA1_CS_L1';
NODE_NAME     U25 BP55
 '@T6G_MB_LIB.T6G(SCH_1):PAGE12_I159@PURE_QUANTA.GENOA_SP5(CHIPS)':
 'MCA1_RSP_L': CDS_PINID='MCA1_RSP_L';
NODE_NAME     U25 BL55
 '@T6G_MB_LIB.T6G(SCH_1):PAGE12_I159@PURE_QUANTA.GENOA_SP5(CHIPS)':
 'MCB1_CS_L0': CDS_PINID='MCB1_CS_L0';
NODE_NAME     U25 BM56
 '@T6G_MB_LIB.T6G(SCH_1):PAGE12_I159@PURE_QUANTA.GENOA_SP5(CHIPS)':
 'MCB1_CS_L1': CDS_PINID='MCB1_CS_L1';
NODE_NAME     U25 BR57
 '@T6G_MB_LIB.T6G(SCH_1):PAGE12_I159@PURE_QUANTA.GENOA_SP5(CHIPS)':
 'MCB1_RSP_L': CDS_PINID='MCB1_RSP_L';
NODE_NAME     U25 BF60
 '@T6G_MB_LIB.T6G(SCH_1):PAGE13_I159@PURE_QUANTA.GENOA_SP5(CHIPS)':
 'MD1_CLK_H': CDS_PINID='MD1_CLK_H';
NODE_NAME     U25 BG60
 '@T6G_MB_LIB.T6G(SCH_1):PAGE13_I159@PURE_QUANTA.GENOA_SP5(CHIPS)':
 'MD1_CLK_L': CDS_PINID='MD1_CLK_L';
NODE_NAME     U25 AU60
 '@T6G_MB_LIB.T6G(SCH_1):PAGE13_I159@PURE_QUANTA.GENOA_SP5(CHIPS)':
 'MDA1_CS_L0': CDS_PINID='MDA1_CS_L0';
NODE_NAME     U25 AV58
 '@T6G_MB_LIB.T6G(SCH_1):PAGE13_I159@PURE_QUANTA.GENOA_SP5(CHIPS)':
 'MDA1_CS_L1': CDS_PINID='MDA1_CS_L1';
NODE_NAME     U25 BP58
 '@T6G_MB_LIB.T6G(SCH_1):PAGE13_I159@PURE_QUANTA.GENOA_SP5(CHIPS)':
 'MDA1_RSP_L': CDS_PINID='MDA1_RSP_L';
NODE_NAME     U25 BL59
 '@T6G_MB_LIB.T6G(SCH_1):PAGE13_I159@PURE_QUANTA.GENOA_SP5(CHIPS)':
 'MDB1_CS_L0': CDS_PINID='MDB1_CS_L0';
NODE_NAME     U25 BM60
 '@T6G_MB_LIB.T6G(SCH_1):PAGE13_I159@PURE_QUANTA.GENOA_SP5(CHIPS)':
 'MDB1_CS_L1': CDS_PINID='MDB1_CS_L1';
NODE_NAME     U25 BR60
 '@T6G_MB_LIB.T6G(SCH_1):PAGE13_I159@PURE_QUANTA.GENOA_SP5(CHIPS)':
 'MDB1_RSP_L': CDS_PINID='MDB1_RSP_L';
NODE_NAME     U25 BF70
 '@T6G_MB_LIB.T6G(SCH_1):PAGE14_I159@PURE_QUANTA.GENOA_SP5(CHIPS)':
 'ME1_CLK_H': CDS_PINID='ME1_CLK_H';
NODE_NAME     U25 BG71
 '@T6G_MB_LIB.T6G(SCH_1):PAGE14_I159@PURE_QUANTA.GENOA_SP5(CHIPS)':
 'ME1_CLK_L': CDS_PINID='ME1_CLK_L';
NODE_NAME     U25 AU71
 '@T6G_MB_LIB.T6G(SCH_1):PAGE14_I159@PURE_QUANTA.GENOA_SP5(CHIPS)':
 'MEA1_CS_L0': CDS_PINID='MEA1_CS_L0';
NODE_NAME     U25 AV69
 '@T6G_MB_LIB.T6G(SCH_1):PAGE14_I159@PURE_QUANTA.GENOA_SP5(CHIPS)':
 'MEA1_CS_L1': CDS_PINID='MEA1_CS_L1';
NODE_NAME     U25 BP69
 '@T6G_MB_LIB.T6G(SCH_1):PAGE14_I159@PURE_QUANTA.GENOA_SP5(CHIPS)':
 'MEA1_RSP_L': CDS_PINID='MEA1_RSP_L';
NODE_NAME     U25 BL69
 '@T6G_MB_LIB.T6G(SCH_1):PAGE14_I159@PURE_QUANTA.GENOA_SP5(CHIPS)':
 'MEB1_CS_L0': CDS_PINID='MEB1_CS_L0';
NODE_NAME     U25 BM70
 '@T6G_MB_LIB.T6G(SCH_1):PAGE14_I159@PURE_QUANTA.GENOA_SP5(CHIPS)':
 'MEB1_CS_L1': CDS_PINID='MEB1_CS_L1';
NODE_NAME     U25 BR71
 '@T6G_MB_LIB.T6G(SCH_1):PAGE14_I159@PURE_QUANTA.GENOA_SP5(CHIPS)':
 'MEB1_RSP_L': CDS_PINID='MEB1_RSP_L';
NODE_NAME     U25 BF67
 '@T6G_MB_LIB.T6G(SCH_1):PAGE15_I159@PURE_QUANTA.GENOA_SP5(CHIPS)':
 'MF1_CLK_H': CDS_PINID='MF1_CLK_H';
NODE_NAME     U25 BG67
 '@T6G_MB_LIB.T6G(SCH_1):PAGE15_I159@PURE_QUANTA.GENOA_SP5(CHIPS)':
 'MF1_CLK_L': CDS_PINID='MF1_CLK_L';
NODE_NAME     U25 AU67
 '@T6G_MB_LIB.T6G(SCH_1):PAGE15_I159@PURE_QUANTA.GENOA_SP5(CHIPS)':
 'MFA1_CS_L0': CDS_PINID='MFA1_CS_L0';
NODE_NAME     U25 AV65
 '@T6G_MB_LIB.T6G(SCH_1):PAGE15_I159@PURE_QUANTA.GENOA_SP5(CHIPS)':
 'MFA1_CS_L1': CDS_PINID='MFA1_CS_L1';
NODE_NAME     U25 BP65
 '@T6G_MB_LIB.T6G(SCH_1):PAGE15_I159@PURE_QUANTA.GENOA_SP5(CHIPS)':
 'MFA1_RSP_L': CDS_PINID='MFA1_RSP_L';
NODE_NAME     U25 BL66
 '@T6G_MB_LIB.T6G(SCH_1):PAGE15_I159@PURE_QUANTA.GENOA_SP5(CHIPS)':
 'MFB1_CS_L0': CDS_PINID='MFB1_CS_L0';
NODE_NAME     U25 BM67
 '@T6G_MB_LIB.T6G(SCH_1):PAGE15_I159@PURE_QUANTA.GENOA_SP5(CHIPS)':
 'MFB1_CS_L1': CDS_PINID='MFB1_CS_L1';
NODE_NAME     U25 BR67
 '@T6G_MB_LIB.T6G(SCH_1):PAGE15_I159@PURE_QUANTA.GENOA_SP5(CHIPS)':
 'MFB1_RSP_L': CDS_PINID='MFB1_RSP_L';
NODE_NAME     U25 BF2
 '@T6G_MB_LIB.T6G(SCH_1):PAGE16_I167@PURE_QUANTA.GENOA_SP5(CHIPS)':
 'MG1_CLK_H': CDS_PINID='MG1_CLK_H';
NODE_NAME     U25 BG2
 '@T6G_MB_LIB.T6G(SCH_1):PAGE16_I167@PURE_QUANTA.GENOA_SP5(CHIPS)':
 'MG1_CLK_L': CDS_PINID='MG1_CLK_L';
NODE_NAME     U25 AV2
 '@T6G_MB_LIB.T6G(SCH_1):PAGE16_I167@PURE_QUANTA.GENOA_SP5(CHIPS)':
 'MGA1_CS_L0': CDS_PINID='MGA1_CS_L0';
NODE_NAME     U25 AW3
 '@T6G_MB_LIB.T6G(SCH_1):PAGE16_I167@PURE_QUANTA.GENOA_SP5(CHIPS)':
 'MGA1_CS_L1': CDS_PINID='MGA1_CS_L1';
NODE_NAME     U25 BP4
 '@T6G_MB_LIB.T6G(SCH_1):PAGE16_I167@PURE_QUANTA.GENOA_SP5(CHIPS)':
 'MGA1_RSP_L': CDS_PINID='MGA1_RSP_L';
NODE_NAME     U25 BL2
 '@T6G_MB_LIB.T6G(SCH_1):PAGE16_I167@PURE_QUANTA.GENOA_SP5(CHIPS)':
 'MGB1_CS_L0': CDS_PINID='MGB1_CS_L0';
NODE_NAME     U25 BM2
 '@T6G_MB_LIB.T6G(SCH_1):PAGE16_I167@PURE_QUANTA.GENOA_SP5(CHIPS)':
 'MGB1_CS_L1': CDS_PINID='MGB1_CS_L1';
NODE_NAME     U25 BR2
 '@T6G_MB_LIB.T6G(SCH_1):PAGE16_I167@PURE_QUANTA.GENOA_SP5(CHIPS)':
 'MGB1_RSP_L': CDS_PINID='MGB1_RSP_L';
NODE_NAME     U25 BF13
 '@T6G_MB_LIB.T6G(SCH_1):PAGE17_I159@PURE_QUANTA.GENOA_SP5(CHIPS)':
 'MH1_CLK_H': CDS_PINID='MH1_CLK_H';
NODE_NAME     U25 BG12
 '@T6G_MB_LIB.T6G(SCH_1):PAGE17_I159@PURE_QUANTA.GENOA_SP5(CHIPS)':
 'MH1_CLK_L': CDS_PINID='MH1_CLK_L';
NODE_NAME     U25 AV13
 '@T6G_MB_LIB.T6G(SCH_1):PAGE17_I159@PURE_QUANTA.GENOA_SP5(CHIPS)':
 'MHA1_CS_L0': CDS_PINID='MHA1_CS_L0';
NODE_NAME     U25 AW14
 '@T6G_MB_LIB.T6G(SCH_1):PAGE17_I159@PURE_QUANTA.GENOA_SP5(CHIPS)':
 'MHA1_CS_L1': CDS_PINID='MHA1_CS_L1';
NODE_NAME     U25 BP14
 '@T6G_MB_LIB.T6G(SCH_1):PAGE17_I159@PURE_QUANTA.GENOA_SP5(CHIPS)':
 'MHA1_RSP_L': CDS_PINID='MHA1_RSP_L';
NODE_NAME     U25 BL12
 '@T6G_MB_LIB.T6G(SCH_1):PAGE17_I159@PURE_QUANTA.GENOA_SP5(CHIPS)':
 'MHB1_CS_L0': CDS_PINID='MHB1_CS_L0';
NODE_NAME     U25 BM13
 '@T6G_MB_LIB.T6G(SCH_1):PAGE17_I159@PURE_QUANTA.GENOA_SP5(CHIPS)':
 'MHB1_CS_L1': CDS_PINID='MHB1_CS_L1';
NODE_NAME     U25 BR12
 '@T6G_MB_LIB.T6G(SCH_1):PAGE17_I159@PURE_QUANTA.GENOA_SP5(CHIPS)':
 'MHB1_RSP_L': CDS_PINID='MHB1_RSP_L';
NODE_NAME     U25 BF20
 '@T6G_MB_LIB.T6G(SCH_1):PAGE18_I159@PURE_QUANTA.GENOA_SP5(CHIPS)':
 'MI1_CLK_H': CDS_PINID='MI1_CLK_H';
NODE_NAME     U25 BG19
 '@T6G_MB_LIB.T6G(SCH_1):PAGE18_I159@PURE_QUANTA.GENOA_SP5(CHIPS)':
 'MI1_CLK_L': CDS_PINID='MI1_CLK_L';
NODE_NAME     U25 AV20
 '@T6G_MB_LIB.T6G(SCH_1):PAGE18_I159@PURE_QUANTA.GENOA_SP5(CHIPS)':
 'MIA1_CS_L0': CDS_PINID='MIA1_CS_L0';
NODE_NAME     U25 AW21
 '@T6G_MB_LIB.T6G(SCH_1):PAGE18_I159@PURE_QUANTA.GENOA_SP5(CHIPS)':
 'MIA1_CS_L1': CDS_PINID='MIA1_CS_L1';
NODE_NAME     U25 BP21
 '@T6G_MB_LIB.T6G(SCH_1):PAGE18_I159@PURE_QUANTA.GENOA_SP5(CHIPS)':
 'MIA1_RSP_L': CDS_PINID='MIA1_RSP_L';
NODE_NAME     U25 BL19
 '@T6G_MB_LIB.T6G(SCH_1):PAGE18_I159@PURE_QUANTA.GENOA_SP5(CHIPS)':
 'MIB1_CS_L0': CDS_PINID='MIB1_CS_L0';
NODE_NAME     U25 BM20
 '@T6G_MB_LIB.T6G(SCH_1):PAGE18_I159@PURE_QUANTA.GENOA_SP5(CHIPS)':
 'MIB1_CS_L1': CDS_PINID='MIB1_CS_L1';
NODE_NAME     U25 BR19
 '@T6G_MB_LIB.T6G(SCH_1):PAGE18_I159@PURE_QUANTA.GENOA_SP5(CHIPS)':
 'MIB1_RSP_L': CDS_PINID='MIB1_RSP_L';
NODE_NAME     U25 BF16
 '@T6G_MB_LIB.T6G(SCH_1):PAGE19_I159@PURE_QUANTA.GENOA_SP5(CHIPS)':
 'MJ1_CLK_H': CDS_PINID='MJ1_CLK_H';
NODE_NAME     U25 BG16
 '@T6G_MB_LIB.T6G(SCH_1):PAGE19_I159@PURE_QUANTA.GENOA_SP5(CHIPS)':
 'MJ1_CLK_L': CDS_PINID='MJ1_CLK_L';
NODE_NAME     U25 AV16
 '@T6G_MB_LIB.T6G(SCH_1):PAGE19_I159@PURE_QUANTA.GENOA_SP5(CHIPS)':
 'MJA1_CS_L0': CDS_PINID='MJA1_CS_L0';
NODE_NAME     U25 AW17
 '@T6G_MB_LIB.T6G(SCH_1):PAGE19_I159@PURE_QUANTA.GENOA_SP5(CHIPS)':
 'MJA1_CS_L1': CDS_PINID='MJA1_CS_L1';
NODE_NAME     U25 BP18
 '@T6G_MB_LIB.T6G(SCH_1):PAGE19_I159@PURE_QUANTA.GENOA_SP5(CHIPS)':
 'MJA1_RSP_L': CDS_PINID='MJA1_RSP_L';
NODE_NAME     U25 BL16
 '@T6G_MB_LIB.T6G(SCH_1):PAGE19_I159@PURE_QUANTA.GENOA_SP5(CHIPS)':
 'MJB1_CS_L0': CDS_PINID='MJB1_CS_L0';
NODE_NAME     U25 BM16
 '@T6G_MB_LIB.T6G(SCH_1):PAGE19_I159@PURE_QUANTA.GENOA_SP5(CHIPS)':
 'MJB1_CS_L1': CDS_PINID='MJB1_CS_L1';
NODE_NAME     U25 BR16
 '@T6G_MB_LIB.T6G(SCH_1):PAGE19_I159@PURE_QUANTA.GENOA_SP5(CHIPS)':
 'MJB1_RSP_L': CDS_PINID='MJB1_RSP_L';
NODE_NAME     U25 BF6
 '@T6G_MB_LIB.T6G(SCH_1):PAGE20_I159@PURE_QUANTA.GENOA_SP5(CHIPS)':
 'MK1_CLK_H': CDS_PINID='MK1_CLK_H';
NODE_NAME     U25 BG5
 '@T6G_MB_LIB.T6G(SCH_1):PAGE20_I159@PURE_QUANTA.GENOA_SP5(CHIPS)':
 'MK1_CLK_L': CDS_PINID='MK1_CLK_L';
NODE_NAME     U25 AV6
 '@T6G_MB_LIB.T6G(SCH_1):PAGE20_I159@PURE_QUANTA.GENOA_SP5(CHIPS)':
 'MKA1_CS_L0': CDS_PINID='MKA1_CS_L0';
NODE_NAME     U25 AW7
 '@T6G_MB_LIB.T6G(SCH_1):PAGE20_I159@PURE_QUANTA.GENOA_SP5(CHIPS)':
 'MKA1_CS_L1': CDS_PINID='MKA1_CS_L1';
NODE_NAME     U25 BP7
 '@T6G_MB_LIB.T6G(SCH_1):PAGE20_I159@PURE_QUANTA.GENOA_SP5(CHIPS)':
 'MKA1_RSP_L': CDS_PINID='MKA1_RSP_L';
NODE_NAME     U25 BL5
 '@T6G_MB_LIB.T6G(SCH_1):PAGE20_I159@PURE_QUANTA.GENOA_SP5(CHIPS)':
 'MKB1_CS_L0': CDS_PINID='MKB1_CS_L0';
NODE_NAME     U25 BM6
 '@T6G_MB_LIB.T6G(SCH_1):PAGE20_I159@PURE_QUANTA.GENOA_SP5(CHIPS)':
 'MKB1_CS_L1': CDS_PINID='MKB1_CS_L1';
NODE_NAME     U25 BR5
 '@T6G_MB_LIB.T6G(SCH_1):PAGE20_I159@PURE_QUANTA.GENOA_SP5(CHIPS)':
 'MKB1_RSP_L': CDS_PINID='MKB1_RSP_L';
NODE_NAME     U25 BF9
 '@T6G_MB_LIB.T6G(SCH_1):PAGE21_I159@PURE_QUANTA.GENOA_SP5(CHIPS)':
 'ML1_CLK_H': CDS_PINID='ML1_CLK_H';
NODE_NAME     U25 BG9
 '@T6G_MB_LIB.T6G(SCH_1):PAGE21_I159@PURE_QUANTA.GENOA_SP5(CHIPS)':
 'ML1_CLK_L': CDS_PINID='ML1_CLK_L';
NODE_NAME     U25 AV9
 '@T6G_MB_LIB.T6G(SCH_1):PAGE21_I159@PURE_QUANTA.GENOA_SP5(CHIPS)':
 'MLA1_CS_L0': CDS_PINID='MLA1_CS_L0';
NODE_NAME     U25 AW10
 '@T6G_MB_LIB.T6G(SCH_1):PAGE21_I159@PURE_QUANTA.GENOA_SP5(CHIPS)':
 'MLA1_CS_L1': CDS_PINID='MLA1_CS_L1';
NODE_NAME     U25 BP11
 '@T6G_MB_LIB.T6G(SCH_1):PAGE21_I159@PURE_QUANTA.GENOA_SP5(CHIPS)':
 'MLA1_RSP_L': CDS_PINID='MLA1_RSP_L';
NODE_NAME     U25 BL9
 '@T6G_MB_LIB.T6G(SCH_1):PAGE21_I159@PURE_QUANTA.GENOA_SP5(CHIPS)':
 'MLB1_CS_L0': CDS_PINID='MLB1_CS_L0';
NODE_NAME     U25 BM9
 '@T6G_MB_LIB.T6G(SCH_1):PAGE21_I159@PURE_QUANTA.GENOA_SP5(CHIPS)':
 'MLB1_CS_L1': CDS_PINID='MLB1_CS_L1';
NODE_NAME     U25 BR9
 '@T6G_MB_LIB.T6G(SCH_1):PAGE21_I159@PURE_QUANTA.GENOA_SP5(CHIPS)':
 'MLB1_RSP_L': CDS_PINID='MLB1_RSP_L';
NODE_NAME     U25 E41
 '@T6G_MB_LIB.T6G(SCH_1):PAGE26_I59@PURE_QUANTA.GENOA_SP5(CHIPS)':
 'P5_RXN3': CDS_PINID='P5_RXN3';
NODE_NAME     U25 E40
 '@T6G_MB_LIB.T6G(SCH_1):PAGE26_I59@PURE_QUANTA.GENOA_SP5(CHIPS)':
 'P5_RXP3': CDS_PINID='P5_RXP3';
NODE_NAME     U25 C42
 '@T6G_MB_LIB.T6G(SCH_1):PAGE26_I59@PURE_QUANTA.GENOA_SP5(CHIPS)':
 'P5_TXN3': CDS_PINID='P5_TXN3';
NODE_NAME     U25 C41
 '@T6G_MB_LIB.T6G(SCH_1):PAGE26_I59@PURE_QUANTA.GENOA_SP5(CHIPS)':
 'P5_TXP3': CDS_PINID='P5_TXP3';
NODE_NAME     U25 E47
 '@T6G_MB_LIB.T6G(SCH_1):PAGE26_I59@PURE_QUANTA.GENOA_SP5(CHIPS)':
 'WAFL_RXN1||P5_RXN1': CDS_PINID='\wafl_rxn1||p5_rxn1\';
NODE_NAME     U25 E46
 '@T6G_MB_LIB.T6G(SCH_1):PAGE26_I59@PURE_QUANTA.GENOA_SP5(CHIPS)':
 'WAFL_RXP1||P5_RXP1': CDS_PINID='\wafl_rxp1||p5_rxp1\';
NODE_NAME     U25 C48
 '@T6G_MB_LIB.T6G(SCH_1):PAGE26_I59@PURE_QUANTA.GENOA_SP5(CHIPS)':
 'WAFL_TXN1||P5_TXN1': CDS_PINID='\wafl_txn1||p5_txn1\';
NODE_NAME     U25 C47
 '@T6G_MB_LIB.T6G(SCH_1):PAGE26_I59@PURE_QUANTA.GENOA_SP5(CHIPS)':
 'WAFL_TXP1||P5_TXP1': CDS_PINID='\wafl_txp1||p5_txp1\';
NODE_NAME     U25 E24
 '@T6G_MB_LIB.T6G(SCH_1):PAGE29_I287@PURE_QUANTA.GENOA_SP5(CHIPS)':
 'USB01_OC_L||AGPIO265': CDS_PINID='\usb01_oc_l||agpio265\';
NODE_NAME     U25 C28
 '@T6G_MB_LIB.T6G(SCH_1):PAGE29_I287@PURE_QUANTA.GENOA_SP5(CHIPS)':
 'USB01_RXN': CDS_PINID='USB01_RXN';
NODE_NAME     U25 C29
 '@T6G_MB_LIB.T6G(SCH_1):PAGE29_I287@PURE_QUANTA.GENOA_SP5(CHIPS)':
 'USB01_RXP': CDS_PINID='USB01_RXP';
NODE_NAME     U25 E29
 '@T6G_MB_LIB.T6G(SCH_1):PAGE29_I287@PURE_QUANTA.GENOA_SP5(CHIPS)':
 'USB01_TXN': CDS_PINID='USB01_TXN';
NODE_NAME     U25 E30
 '@T6G_MB_LIB.T6G(SCH_1):PAGE29_I287@PURE_QUANTA.GENOA_SP5(CHIPS)':
 'USB01_TXP': CDS_PINID='USB01_TXP';
NODE_NAME     U25 DG40
 '@T6G_MB_LIB.T6G(SCH_1):PAGE29_I287@PURE_QUANTA.GENOA_SP5(CHIPS)':
 'USB10_OC_L||AGPIO16': CDS_PINID='\usb10_oc_l||agpio16\';
NODE_NAME     U25 DH65
 '@T6G_MB_LIB.T6G(SCH_1):PAGE29_I287@PURE_QUANTA.GENOA_SP5(CHIPS)':
 'USB10_RXN': CDS_PINID='USB10_RXN';
NODE_NAME     U25 DJ65
 '@T6G_MB_LIB.T6G(SCH_1):PAGE29_I287@PURE_QUANTA.GENOA_SP5(CHIPS)':
 'USB10_RXP': CDS_PINID='USB10_RXP';
NODE_NAME     U25 DJ69
 '@T6G_MB_LIB.T6G(SCH_1):PAGE29_I287@PURE_QUANTA.GENOA_SP5(CHIPS)':
 'USB10_TXN': CDS_PINID='USB10_TXN';
NODE_NAME     U25 DH69
 '@T6G_MB_LIB.T6G(SCH_1):PAGE29_I287@PURE_QUANTA.GENOA_SP5(CHIPS)':
 'USB10_TXP': CDS_PINID='USB10_TXP';
NODE_NAME     U25 DH40
 '@T6G_MB_LIB.T6G(SCH_1):PAGE29_I287@PURE_QUANTA.GENOA_SP5(CHIPS)':
 'USB11_OC_L||AGPIO17': CDS_PINID='\usb11_oc_l||agpio17\';
NODE_NAME     U25 DH62
 '@T6G_MB_LIB.T6G(SCH_1):PAGE29_I287@PURE_QUANTA.GENOA_SP5(CHIPS)':
 'USB11_RXN': CDS_PINID='USB11_RXN';
NODE_NAME     U25 DJ62
 '@T6G_MB_LIB.T6G(SCH_1):PAGE29_I287@PURE_QUANTA.GENOA_SP5(CHIPS)':
 'USB11_RXP': CDS_PINID='USB11_RXP';
NODE_NAME     U25 DH58
 '@T6G_MB_LIB.T6G(SCH_1):PAGE29_I287@PURE_QUANTA.GENOA_SP5(CHIPS)':
 'USB11_TXN': CDS_PINID='USB11_TXN';
NODE_NAME     U25 DG58
 '@T6G_MB_LIB.T6G(SCH_1):PAGE29_I287@PURE_QUANTA.GENOA_SP5(CHIPS)':
 'USB11_TXP': CDS_PINID='USB11_TXP';
NODE_NAME     U3 1
 '@T6G_MB_LIB.T6G(SCH_1):PAGE29_I373@PURE_QUANTA.SN74LVC1G07DBVR(CHIPS)':
 'NC': CDS_PINID='NC';
NODE_NAME     U25 A31
 '@T6G_MB_LIB.T6G(SCH_1):PAGE30_I29@PURE_QUANTA.GENOA_SP5(CHIPS)':
 'RSVD_A31': CDS_PINID='RSVD_A31';
NODE_NAME     U25 A35
 '@T6G_MB_LIB.T6G(SCH_1):PAGE30_I29@PURE_QUANTA.GENOA_SP5(CHIPS)':
 'RSVD_A35': CDS_PINID='RSVD_A35';
NODE_NAME     U25 A41
 '@T6G_MB_LIB.T6G(SCH_1):PAGE30_I29@PURE_QUANTA.GENOA_SP5(CHIPS)':
 'RSVD_A41': CDS_PINID='RSVD_A41';
NODE_NAME     U25 A42
 '@T6G_MB_LIB.T6G(SCH_1):PAGE30_I29@PURE_QUANTA.GENOA_SP5(CHIPS)':
 'RSVD_A42': CDS_PINID='RSVD_A42';
NODE_NAME     U25 A45
 '@T6G_MB_LIB.T6G(SCH_1):PAGE30_I29@PURE_QUANTA.GENOA_SP5(CHIPS)':
 'RSVD_A45': CDS_PINID='RSVD_A45';
NODE_NAME     U25 A48
 '@T6G_MB_LIB.T6G(SCH_1):PAGE30_I29@PURE_QUANTA.GENOA_SP5(CHIPS)':
 'RSVD_A48': CDS_PINID='RSVD_A48';
NODE_NAME     U25 A50
 '@T6G_MB_LIB.T6G(SCH_1):PAGE30_I29@PURE_QUANTA.GENOA_SP5(CHIPS)':
 'RSVD_A50': CDS_PINID='RSVD_A50';
NODE_NAME     U25 A51
 '@T6G_MB_LIB.T6G(SCH_1):PAGE30_I29@PURE_QUANTA.GENOA_SP5(CHIPS)':
 'RSVD_A51': CDS_PINID='RSVD_A51';
NODE_NAME     U25 A54
 '@T6G_MB_LIB.T6G(SCH_1):PAGE30_I29@PURE_QUANTA.GENOA_SP5(CHIPS)':
 'RSVD_A54': CDS_PINID='RSVD_A54';
NODE_NAME     U25 A55
 '@T6G_MB_LIB.T6G(SCH_1):PAGE30_I29@PURE_QUANTA.GENOA_SP5(CHIPS)':
 'RSVD_A55': CDS_PINID='RSVD_A55';
NODE_NAME     U25 A56
 '@T6G_MB_LIB.T6G(SCH_1):PAGE30_I29@PURE_QUANTA.GENOA_SP5(CHIPS)':
 'RSVD_A56': CDS_PINID='RSVD_A56';
NODE_NAME     U25 A57
 '@T6G_MB_LIB.T6G(SCH_1):PAGE30_I29@PURE_QUANTA.GENOA_SP5(CHIPS)':
 'RSVD_A57': CDS_PINID='RSVD_A57';
NODE_NAME     U25 A59
 '@T6G_MB_LIB.T6G(SCH_1):PAGE30_I29@PURE_QUANTA.GENOA_SP5(CHIPS)':
 'RSVD_A59': CDS_PINID='RSVD_A59';
NODE_NAME     U25 A60
 '@T6G_MB_LIB.T6G(SCH_1):PAGE30_I29@PURE_QUANTA.GENOA_SP5(CHIPS)':
 'RSVD_A60': CDS_PINID='RSVD_A60';
NODE_NAME     U25 B40
 '@T6G_MB_LIB.T6G(SCH_1):PAGE30_I29@PURE_QUANTA.GENOA_SP5(CHIPS)':
 'RSVD_B40': CDS_PINID='RSVD_B40';
NODE_NAME     U25 BD4
 '@T6G_MB_LIB.T6G(SCH_1):PAGE30_I29@PURE_QUANTA.GENOA_SP5(CHIPS)':
 'RSVD_BD4': CDS_PINID='RSVD_BD4';
NODE_NAME     U25 BD7
 '@T6G_MB_LIB.T6G(SCH_1):PAGE30_I29@PURE_QUANTA.GENOA_SP5(CHIPS)':
 'RSVD_BD7': CDS_PINID='RSVD_BD7';
NODE_NAME     U25 BD11
 '@T6G_MB_LIB.T6G(SCH_1):PAGE30_I29@PURE_QUANTA.GENOA_SP5(CHIPS)':
 'RSVD_BD11': CDS_PINID='RSVD_BD11';
NODE_NAME     U25 BD14
 '@T6G_MB_LIB.T6G(SCH_1):PAGE30_I29@PURE_QUANTA.GENOA_SP5(CHIPS)':
 'RSVD_BD14': CDS_PINID='RSVD_BD14';
NODE_NAME     U25 BD18
 '@T6G_MB_LIB.T6G(SCH_1):PAGE30_I29@PURE_QUANTA.GENOA_SP5(CHIPS)':
 'RSVD_BD18': CDS_PINID='RSVD_BD18';
NODE_NAME     U25 BD21
 '@T6G_MB_LIB.T6G(SCH_1):PAGE30_I29@PURE_QUANTA.GENOA_SP5(CHIPS)':
 'RSVD_BD21': CDS_PINID='RSVD_BD21';
NODE_NAME     U25 BD55
 '@T6G_MB_LIB.T6G(SCH_1):PAGE30_I29@PURE_QUANTA.GENOA_SP5(CHIPS)':
 'RSVD_BD55': CDS_PINID='RSVD_BD55';
NODE_NAME     U25 BD58
 '@T6G_MB_LIB.T6G(SCH_1):PAGE30_I29@PURE_QUANTA.GENOA_SP5(CHIPS)':
 'RSVD_BD58': CDS_PINID='RSVD_BD58';
NODE_NAME     U25 BD62
 '@T6G_MB_LIB.T6G(SCH_1):PAGE30_I29@PURE_QUANTA.GENOA_SP5(CHIPS)':
 'RSVD_BD62': CDS_PINID='RSVD_BD62';
NODE_NAME     U25 BD65
 '@T6G_MB_LIB.T6G(SCH_1):PAGE30_I29@PURE_QUANTA.GENOA_SP5(CHIPS)':
 'RSVD_BD65': CDS_PINID='RSVD_BD65';
NODE_NAME     U25 BD69
 '@T6G_MB_LIB.T6G(SCH_1):PAGE30_I29@PURE_QUANTA.GENOA_SP5(CHIPS)':
 'RSVD_BD69': CDS_PINID='RSVD_BD69';
NODE_NAME     U25 BD72
 '@T6G_MB_LIB.T6G(SCH_1):PAGE30_I29@PURE_QUANTA.GENOA_SP5(CHIPS)':
 'RSVD_BD72': CDS_PINID='RSVD_BD72';
NODE_NAME     U25 C31
 '@T6G_MB_LIB.T6G(SCH_1):PAGE30_I29@PURE_QUANTA.GENOA_SP5(CHIPS)':
 'RSVD_C31': CDS_PINID='RSVD_C31';
NODE_NAME     U25 C34
 '@T6G_MB_LIB.T6G(SCH_1):PAGE30_I29@PURE_QUANTA.GENOA_SP5(CHIPS)':
 'RSVD_C34': CDS_PINID='RSVD_C34';
NODE_NAME     U25 C35
 '@T6G_MB_LIB.T6G(SCH_1):PAGE30_I29@PURE_QUANTA.GENOA_SP5(CHIPS)':
 'RSVD_C35': CDS_PINID='RSVD_C35';
NODE_NAME     U25 C53
 '@T6G_MB_LIB.T6G(SCH_1):PAGE30_I29@PURE_QUANTA.GENOA_SP5(CHIPS)':
 'RSVD_C53': CDS_PINID='RSVD_C53';
NODE_NAME     U25 C54
 '@T6G_MB_LIB.T6G(SCH_1):PAGE30_I29@PURE_QUANTA.GENOA_SP5(CHIPS)':
 'RSVD_C54': CDS_PINID='RSVD_C54';
NODE_NAME     U25 D4
 '@T6G_MB_LIB.T6G(SCH_1):PAGE30_I29@PURE_QUANTA.GENOA_SP5(CHIPS)':
 'RSVD_D4': CDS_PINID='RSVD_D4';
NODE_NAME     U25 D8
 '@T6G_MB_LIB.T6G(SCH_1):PAGE30_I29@PURE_QUANTA.GENOA_SP5(CHIPS)':
 'RSVD_D8': CDS_PINID='RSVD_D8';
NODE_NAME     U25 D11
 '@T6G_MB_LIB.T6G(SCH_1):PAGE30_I29@PURE_QUANTA.GENOA_SP5(CHIPS)':
 'RSVD_D11': CDS_PINID='RSVD_D11';
NODE_NAME     U25 D22
 '@T6G_MB_LIB.T6G(SCH_1):PAGE30_I29@PURE_QUANTA.GENOA_SP5(CHIPS)':
 'RSVD_D22': CDS_PINID='RSVD_D22';
NODE_NAME     U25 D34
 '@T6G_MB_LIB.T6G(SCH_1):PAGE30_I29@PURE_QUANTA.GENOA_SP5(CHIPS)':
 'RSVD_D34': CDS_PINID='RSVD_D34';
NODE_NAME     U25 D36
 '@T6G_MB_LIB.T6G(SCH_1):PAGE30_I29@PURE_QUANTA.GENOA_SP5(CHIPS)':
 'RSVD_D36': CDS_PINID='RSVD_D36';
NODE_NAME     U25 D58
 '@T6G_MB_LIB.T6G(SCH_1):PAGE30_I29@PURE_QUANTA.GENOA_SP5(CHIPS)':
 'RSVD_D58': CDS_PINID='RSVD_D58';
NODE_NAME     U25 D62
 '@T6G_MB_LIB.T6G(SCH_1):PAGE30_I29@PURE_QUANTA.GENOA_SP5(CHIPS)':
 'RSVD_D62': CDS_PINID='RSVD_D62';
NODE_NAME     U25 D65
 '@T6G_MB_LIB.T6G(SCH_1):PAGE30_I29@PURE_QUANTA.GENOA_SP5(CHIPS)':
 'RSVD_D65': CDS_PINID='RSVD_D65';
NODE_NAME     U25 D72
 '@T6G_MB_LIB.T6G(SCH_1):PAGE30_I29@PURE_QUANTA.GENOA_SP5(CHIPS)':
 'RSVD_D72': CDS_PINID='RSVD_D72';
NODE_NAME     U25 DG17
 '@T6G_MB_LIB.T6G(SCH_1):PAGE30_I29@PURE_QUANTA.GENOA_SP5(CHIPS)':
 'RSVD_DG17': CDS_PINID='RSVD_DG17';
NODE_NAME     U25 DH17
 '@T6G_MB_LIB.T6G(SCH_1):PAGE30_I29@PURE_QUANTA.GENOA_SP5(CHIPS)':
 'RSVD_DH17': CDS_PINID='RSVD_DH17';
NODE_NAME     U25 DH21
 '@T6G_MB_LIB.T6G(SCH_1):PAGE30_I29@PURE_QUANTA.GENOA_SP5(CHIPS)':
 'RSVD_DH21': CDS_PINID='RSVD_DH21';
NODE_NAME     U25 DJ4
 '@T6G_MB_LIB.T6G(SCH_1):PAGE30_I29@PURE_QUANTA.GENOA_SP5(CHIPS)':
 'RSVD_DJ4': CDS_PINID='RSVD_DJ4';
NODE_NAME     U25 E33
 '@T6G_MB_LIB.T6G(SCH_1):PAGE30_I29@PURE_QUANTA.GENOA_SP5(CHIPS)':
 'RSVD_E33': CDS_PINID='RSVD_E33';
NODE_NAME     U25 E36
 '@T6G_MB_LIB.T6G(SCH_1):PAGE30_I29@PURE_QUANTA.GENOA_SP5(CHIPS)':
 'RSVD_E36': CDS_PINID='RSVD_E36';
NODE_NAME     U25 C58
 '@T6G_MB_LIB.T6G(SCH_1):PAGE30_I29@PURE_QUANTA.GENOA_SP5(CHIPS)':
 'TEST4_CCD12': CDS_PINID='TEST4_CCD12';
NODE_NAME     U25 DH13
 '@T6G_MB_LIB.T6G(SCH_1):PAGE30_I29@PURE_QUANTA.GENOA_SP5(CHIPS)':
 'TEST4_CCD13': CDS_PINID='TEST4_CCD13';
NODE_NAME     U25 DF41
 '@T6G_MB_LIB.T6G(SCH_1):PAGE30_I29@PURE_QUANTA.GENOA_SP5(CHIPS)':
 'TEST4_CCD14': CDS_PINID='TEST4_CCD14';
NODE_NAME     U25 C23
 '@T6G_MB_LIB.T6G(SCH_1):PAGE30_I29@PURE_QUANTA.GENOA_SP5(CHIPS)':
 'TEST4_CCD15': CDS_PINID='TEST4_CCD15';
NODE_NAME     U25 C59
 '@T6G_MB_LIB.T6G(SCH_1):PAGE30_I29@PURE_QUANTA.GENOA_SP5(CHIPS)':
 'TEST5_CCD12': CDS_PINID='TEST5_CCD12';
NODE_NAME     U25 DH14
 '@T6G_MB_LIB.T6G(SCH_1):PAGE30_I29@PURE_QUANTA.GENOA_SP5(CHIPS)':
 'TEST5_CCD13': CDS_PINID='TEST5_CCD13';
NODE_NAME     U25 DG42
 '@T6G_MB_LIB.T6G(SCH_1):PAGE30_I29@PURE_QUANTA.GENOA_SP5(CHIPS)':
 'TEST5_CCD14': CDS_PINID='TEST5_CCD14';
NODE_NAME     U25 D23
 '@T6G_MB_LIB.T6G(SCH_1):PAGE30_I29@PURE_QUANTA.GENOA_SP5(CHIPS)':
 'TEST5_CCD15': CDS_PINID='TEST5_CCD15';
NODE_NAME     U25 B36
 '@T6G_MB_LIB.T6G(SCH_1):PAGE30_I29@PURE_QUANTA.GENOA_SP5(CHIPS)':
 'TEST6_X3D6': CDS_PINID='TEST6_X3D6';
NODE_NAME     U25 DJ57
 '@T6G_MB_LIB.T6G(SCH_1):PAGE30_I29@PURE_QUANTA.GENOA_SP5(CHIPS)':
 'TEST6_X3D7': CDS_PINID='TEST6_X3D7';
NODE_NAME     U101 1
 '@T6G_MB_LIB.T6G(SCH_1):PAGE34_I55@PURE_QUANTA.SN74LVC1G07DBVR(CHIPS)':
 'NC': CDS_PINID='NC';
NODE_NAME     U26 BF74
 '@T6G_MB_LIB.T6G(SCH_1):PAGE37_I167@PURE_QUANTA.GENOA_SP5(CHIPS)':
 'MA1_CLK_H': CDS_PINID='MA1_CLK_H';
NODE_NAME     U26 BG74
 '@T6G_MB_LIB.T6G(SCH_1):PAGE37_I167@PURE_QUANTA.GENOA_SP5(CHIPS)':
 'MA1_CLK_L': CDS_PINID='MA1_CLK_L';
NODE_NAME     U26 AU74
 '@T6G_MB_LIB.T6G(SCH_1):PAGE37_I167@PURE_QUANTA.GENOA_SP5(CHIPS)':
 'MAA1_CS_L0': CDS_PINID='MAA1_CS_L0';
NODE_NAME     U26 AV72
 '@T6G_MB_LIB.T6G(SCH_1):PAGE37_I167@PURE_QUANTA.GENOA_SP5(CHIPS)':
 'MAA1_CS_L1': CDS_PINID='MAA1_CS_L1';
NODE_NAME     U26 BP72
 '@T6G_MB_LIB.T6G(SCH_1):PAGE37_I167@PURE_QUANTA.GENOA_SP5(CHIPS)':
 'MAA1_RSP_L': CDS_PINID='MAA1_RSP_L';
NODE_NAME     U26 BL73
 '@T6G_MB_LIB.T6G(SCH_1):PAGE37_I167@PURE_QUANTA.GENOA_SP5(CHIPS)':
 'MAB1_CS_L0': CDS_PINID='MAB1_CS_L0';
NODE_NAME     U26 BM74
 '@T6G_MB_LIB.T6G(SCH_1):PAGE37_I167@PURE_QUANTA.GENOA_SP5(CHIPS)':
 'MAB1_CS_L1': CDS_PINID='MAB1_CS_L1';
NODE_NAME     U26 BR74
 '@T6G_MB_LIB.T6G(SCH_1):PAGE37_I167@PURE_QUANTA.GENOA_SP5(CHIPS)':
 'MAB1_RSP_L': CDS_PINID='MAB1_RSP_L';
NODE_NAME     U26 BF63
 '@T6G_MB_LIB.T6G(SCH_1):PAGE38_I159@PURE_QUANTA.GENOA_SP5(CHIPS)':
 'MB1_CLK_H': CDS_PINID='MB1_CLK_H';
NODE_NAME     U26 BG64
 '@T6G_MB_LIB.T6G(SCH_1):PAGE38_I159@PURE_QUANTA.GENOA_SP5(CHIPS)':
 'MB1_CLK_L': CDS_PINID='MB1_CLK_L';
NODE_NAME     U26 AU64
 '@T6G_MB_LIB.T6G(SCH_1):PAGE38_I159@PURE_QUANTA.GENOA_SP5(CHIPS)':
 'MBA1_CS_L0': CDS_PINID='MBA1_CS_L0';
NODE_NAME     U26 AV62
 '@T6G_MB_LIB.T6G(SCH_1):PAGE38_I159@PURE_QUANTA.GENOA_SP5(CHIPS)':
 'MBA1_CS_L1': CDS_PINID='MBA1_CS_L1';
NODE_NAME     U26 BP62
 '@T6G_MB_LIB.T6G(SCH_1):PAGE38_I159@PURE_QUANTA.GENOA_SP5(CHIPS)':
 'MBA1_RSP_L': CDS_PINID='MBA1_RSP_L';
NODE_NAME     U26 BL62
 '@T6G_MB_LIB.T6G(SCH_1):PAGE38_I159@PURE_QUANTA.GENOA_SP5(CHIPS)':
 'MBB1_CS_L0': CDS_PINID='MBB1_CS_L0';
NODE_NAME     U26 BM63
 '@T6G_MB_LIB.T6G(SCH_1):PAGE38_I159@PURE_QUANTA.GENOA_SP5(CHIPS)':
 'MBB1_CS_L1': CDS_PINID='MBB1_CS_L1';
NODE_NAME     U26 BR64
 '@T6G_MB_LIB.T6G(SCH_1):PAGE38_I159@PURE_QUANTA.GENOA_SP5(CHIPS)':
 'MBB1_RSP_L': CDS_PINID='MBB1_RSP_L';
NODE_NAME     U26 BF56
 '@T6G_MB_LIB.T6G(SCH_1):PAGE39_I159@PURE_QUANTA.GENOA_SP5(CHIPS)':
 'MC1_CLK_H': CDS_PINID='MC1_CLK_H';
NODE_NAME     U26 BG57
 '@T6G_MB_LIB.T6G(SCH_1):PAGE39_I159@PURE_QUANTA.GENOA_SP5(CHIPS)':
 'MC1_CLK_L': CDS_PINID='MC1_CLK_L';
NODE_NAME     U26 AU57
 '@T6G_MB_LIB.T6G(SCH_1):PAGE39_I159@PURE_QUANTA.GENOA_SP5(CHIPS)':
 'MCA1_CS_L0': CDS_PINID='MCA1_CS_L0';
NODE_NAME     U26 AV55
 '@T6G_MB_LIB.T6G(SCH_1):PAGE39_I159@PURE_QUANTA.GENOA_SP5(CHIPS)':
 'MCA1_CS_L1': CDS_PINID='MCA1_CS_L1';
NODE_NAME     U26 BP55
 '@T6G_MB_LIB.T6G(SCH_1):PAGE39_I159@PURE_QUANTA.GENOA_SP5(CHIPS)':
 'MCA1_RSP_L': CDS_PINID='MCA1_RSP_L';
NODE_NAME     U26 BL55
 '@T6G_MB_LIB.T6G(SCH_1):PAGE39_I159@PURE_QUANTA.GENOA_SP5(CHIPS)':
 'MCB1_CS_L0': CDS_PINID='MCB1_CS_L0';
NODE_NAME     U26 BM56
 '@T6G_MB_LIB.T6G(SCH_1):PAGE39_I159@PURE_QUANTA.GENOA_SP5(CHIPS)':
 'MCB1_CS_L1': CDS_PINID='MCB1_CS_L1';
NODE_NAME     U26 BR57
 '@T6G_MB_LIB.T6G(SCH_1):PAGE39_I159@PURE_QUANTA.GENOA_SP5(CHIPS)':
 'MCB1_RSP_L': CDS_PINID='MCB1_RSP_L';
NODE_NAME     U26 BF60
 '@T6G_MB_LIB.T6G(SCH_1):PAGE40_I159@PURE_QUANTA.GENOA_SP5(CHIPS)':
 'MD1_CLK_H': CDS_PINID='MD1_CLK_H';
NODE_NAME     U26 BG60
 '@T6G_MB_LIB.T6G(SCH_1):PAGE40_I159@PURE_QUANTA.GENOA_SP5(CHIPS)':
 'MD1_CLK_L': CDS_PINID='MD1_CLK_L';
NODE_NAME     U26 AU60
 '@T6G_MB_LIB.T6G(SCH_1):PAGE40_I159@PURE_QUANTA.GENOA_SP5(CHIPS)':
 'MDA1_CS_L0': CDS_PINID='MDA1_CS_L0';
NODE_NAME     U26 AV58
 '@T6G_MB_LIB.T6G(SCH_1):PAGE40_I159@PURE_QUANTA.GENOA_SP5(CHIPS)':
 'MDA1_CS_L1': CDS_PINID='MDA1_CS_L1';
NODE_NAME     U26 BP58
 '@T6G_MB_LIB.T6G(SCH_1):PAGE40_I159@PURE_QUANTA.GENOA_SP5(CHIPS)':
 'MDA1_RSP_L': CDS_PINID='MDA1_RSP_L';
NODE_NAME     U26 BL59
 '@T6G_MB_LIB.T6G(SCH_1):PAGE40_I159@PURE_QUANTA.GENOA_SP5(CHIPS)':
 'MDB1_CS_L0': CDS_PINID='MDB1_CS_L0';
NODE_NAME     U26 BM60
 '@T6G_MB_LIB.T6G(SCH_1):PAGE40_I159@PURE_QUANTA.GENOA_SP5(CHIPS)':
 'MDB1_CS_L1': CDS_PINID='MDB1_CS_L1';
NODE_NAME     U26 BR60
 '@T6G_MB_LIB.T6G(SCH_1):PAGE40_I159@PURE_QUANTA.GENOA_SP5(CHIPS)':
 'MDB1_RSP_L': CDS_PINID='MDB1_RSP_L';
NODE_NAME     U26 BF70
 '@T6G_MB_LIB.T6G(SCH_1):PAGE41_I159@PURE_QUANTA.GENOA_SP5(CHIPS)':
 'ME1_CLK_H': CDS_PINID='ME1_CLK_H';
NODE_NAME     U26 BG71
 '@T6G_MB_LIB.T6G(SCH_1):PAGE41_I159@PURE_QUANTA.GENOA_SP5(CHIPS)':
 'ME1_CLK_L': CDS_PINID='ME1_CLK_L';
NODE_NAME     U26 AU71
 '@T6G_MB_LIB.T6G(SCH_1):PAGE41_I159@PURE_QUANTA.GENOA_SP5(CHIPS)':
 'MEA1_CS_L0': CDS_PINID='MEA1_CS_L0';
NODE_NAME     U26 AV69
 '@T6G_MB_LIB.T6G(SCH_1):PAGE41_I159@PURE_QUANTA.GENOA_SP5(CHIPS)':
 'MEA1_CS_L1': CDS_PINID='MEA1_CS_L1';
NODE_NAME     U26 BP69
 '@T6G_MB_LIB.T6G(SCH_1):PAGE41_I159@PURE_QUANTA.GENOA_SP5(CHIPS)':
 'MEA1_RSP_L': CDS_PINID='MEA1_RSP_L';
NODE_NAME     U26 BL69
 '@T6G_MB_LIB.T6G(SCH_1):PAGE41_I159@PURE_QUANTA.GENOA_SP5(CHIPS)':
 'MEB1_CS_L0': CDS_PINID='MEB1_CS_L0';
NODE_NAME     U26 BM70
 '@T6G_MB_LIB.T6G(SCH_1):PAGE41_I159@PURE_QUANTA.GENOA_SP5(CHIPS)':
 'MEB1_CS_L1': CDS_PINID='MEB1_CS_L1';
NODE_NAME     U26 BR71
 '@T6G_MB_LIB.T6G(SCH_1):PAGE41_I159@PURE_QUANTA.GENOA_SP5(CHIPS)':
 'MEB1_RSP_L': CDS_PINID='MEB1_RSP_L';
NODE_NAME     U26 BF67
 '@T6G_MB_LIB.T6G(SCH_1):PAGE42_I159@PURE_QUANTA.GENOA_SP5(CHIPS)':
 'MF1_CLK_H': CDS_PINID='MF1_CLK_H';
NODE_NAME     U26 BG67
 '@T6G_MB_LIB.T6G(SCH_1):PAGE42_I159@PURE_QUANTA.GENOA_SP5(CHIPS)':
 'MF1_CLK_L': CDS_PINID='MF1_CLK_L';
NODE_NAME     U26 AU67
 '@T6G_MB_LIB.T6G(SCH_1):PAGE42_I159@PURE_QUANTA.GENOA_SP5(CHIPS)':
 'MFA1_CS_L0': CDS_PINID='MFA1_CS_L0';
NODE_NAME     U26 AV65
 '@T6G_MB_LIB.T6G(SCH_1):PAGE42_I159@PURE_QUANTA.GENOA_SP5(CHIPS)':
 'MFA1_CS_L1': CDS_PINID='MFA1_CS_L1';
NODE_NAME     U26 BP65
 '@T6G_MB_LIB.T6G(SCH_1):PAGE42_I159@PURE_QUANTA.GENOA_SP5(CHIPS)':
 'MFA1_RSP_L': CDS_PINID='MFA1_RSP_L';
NODE_NAME     U26 BL66
 '@T6G_MB_LIB.T6G(SCH_1):PAGE42_I159@PURE_QUANTA.GENOA_SP5(CHIPS)':
 'MFB1_CS_L0': CDS_PINID='MFB1_CS_L0';
NODE_NAME     U26 BM67
 '@T6G_MB_LIB.T6G(SCH_1):PAGE42_I159@PURE_QUANTA.GENOA_SP5(CHIPS)':
 'MFB1_CS_L1': CDS_PINID='MFB1_CS_L1';
NODE_NAME     U26 BR67
 '@T6G_MB_LIB.T6G(SCH_1):PAGE42_I159@PURE_QUANTA.GENOA_SP5(CHIPS)':
 'MFB1_RSP_L': CDS_PINID='MFB1_RSP_L';
NODE_NAME     U26 BF2
 '@T6G_MB_LIB.T6G(SCH_1):PAGE43_I167@PURE_QUANTA.GENOA_SP5(CHIPS)':
 'MG1_CLK_H': CDS_PINID='MG1_CLK_H';
NODE_NAME     U26 BG2
 '@T6G_MB_LIB.T6G(SCH_1):PAGE43_I167@PURE_QUANTA.GENOA_SP5(CHIPS)':
 'MG1_CLK_L': CDS_PINID='MG1_CLK_L';
NODE_NAME     U26 AV2
 '@T6G_MB_LIB.T6G(SCH_1):PAGE43_I167@PURE_QUANTA.GENOA_SP5(CHIPS)':
 'MGA1_CS_L0': CDS_PINID='MGA1_CS_L0';
NODE_NAME     U26 AW3
 '@T6G_MB_LIB.T6G(SCH_1):PAGE43_I167@PURE_QUANTA.GENOA_SP5(CHIPS)':
 'MGA1_CS_L1': CDS_PINID='MGA1_CS_L1';
NODE_NAME     U26 BP4
 '@T6G_MB_LIB.T6G(SCH_1):PAGE43_I167@PURE_QUANTA.GENOA_SP5(CHIPS)':
 'MGA1_RSP_L': CDS_PINID='MGA1_RSP_L';
NODE_NAME     U26 BL2
 '@T6G_MB_LIB.T6G(SCH_1):PAGE43_I167@PURE_QUANTA.GENOA_SP5(CHIPS)':
 'MGB1_CS_L0': CDS_PINID='MGB1_CS_L0';
NODE_NAME     U26 BM2
 '@T6G_MB_LIB.T6G(SCH_1):PAGE43_I167@PURE_QUANTA.GENOA_SP5(CHIPS)':
 'MGB1_CS_L1': CDS_PINID='MGB1_CS_L1';
NODE_NAME     U26 BR2
 '@T6G_MB_LIB.T6G(SCH_1):PAGE43_I167@PURE_QUANTA.GENOA_SP5(CHIPS)':
 'MGB1_RSP_L': CDS_PINID='MGB1_RSP_L';
NODE_NAME     U26 BF13
 '@T6G_MB_LIB.T6G(SCH_1):PAGE44_I159@PURE_QUANTA.GENOA_SP5(CHIPS)':
 'MH1_CLK_H': CDS_PINID='MH1_CLK_H';
NODE_NAME     U26 BG12
 '@T6G_MB_LIB.T6G(SCH_1):PAGE44_I159@PURE_QUANTA.GENOA_SP5(CHIPS)':
 'MH1_CLK_L': CDS_PINID='MH1_CLK_L';
NODE_NAME     U26 AV13
 '@T6G_MB_LIB.T6G(SCH_1):PAGE44_I159@PURE_QUANTA.GENOA_SP5(CHIPS)':
 'MHA1_CS_L0': CDS_PINID='MHA1_CS_L0';
NODE_NAME     U26 AW14
 '@T6G_MB_LIB.T6G(SCH_1):PAGE44_I159@PURE_QUANTA.GENOA_SP5(CHIPS)':
 'MHA1_CS_L1': CDS_PINID='MHA1_CS_L1';
NODE_NAME     U26 BP14
 '@T6G_MB_LIB.T6G(SCH_1):PAGE44_I159@PURE_QUANTA.GENOA_SP5(CHIPS)':
 'MHA1_RSP_L': CDS_PINID='MHA1_RSP_L';
NODE_NAME     U26 BL12
 '@T6G_MB_LIB.T6G(SCH_1):PAGE44_I159@PURE_QUANTA.GENOA_SP5(CHIPS)':
 'MHB1_CS_L0': CDS_PINID='MHB1_CS_L0';
NODE_NAME     U26 BM13
 '@T6G_MB_LIB.T6G(SCH_1):PAGE44_I159@PURE_QUANTA.GENOA_SP5(CHIPS)':
 'MHB1_CS_L1': CDS_PINID='MHB1_CS_L1';
NODE_NAME     U26 BR12
 '@T6G_MB_LIB.T6G(SCH_1):PAGE44_I159@PURE_QUANTA.GENOA_SP5(CHIPS)':
 'MHB1_RSP_L': CDS_PINID='MHB1_RSP_L';
NODE_NAME     U26 BF20
 '@T6G_MB_LIB.T6G(SCH_1):PAGE45_I159@PURE_QUANTA.GENOA_SP5(CHIPS)':
 'MI1_CLK_H': CDS_PINID='MI1_CLK_H';
NODE_NAME     U26 BG19
 '@T6G_MB_LIB.T6G(SCH_1):PAGE45_I159@PURE_QUANTA.GENOA_SP5(CHIPS)':
 'MI1_CLK_L': CDS_PINID='MI1_CLK_L';
NODE_NAME     U26 AV20
 '@T6G_MB_LIB.T6G(SCH_1):PAGE45_I159@PURE_QUANTA.GENOA_SP5(CHIPS)':
 'MIA1_CS_L0': CDS_PINID='MIA1_CS_L0';
NODE_NAME     U26 AW21
 '@T6G_MB_LIB.T6G(SCH_1):PAGE45_I159@PURE_QUANTA.GENOA_SP5(CHIPS)':
 'MIA1_CS_L1': CDS_PINID='MIA1_CS_L1';
NODE_NAME     U26 BP21
 '@T6G_MB_LIB.T6G(SCH_1):PAGE45_I159@PURE_QUANTA.GENOA_SP5(CHIPS)':
 'MIA1_RSP_L': CDS_PINID='MIA1_RSP_L';
NODE_NAME     U26 BL19
 '@T6G_MB_LIB.T6G(SCH_1):PAGE45_I159@PURE_QUANTA.GENOA_SP5(CHIPS)':
 'MIB1_CS_L0': CDS_PINID='MIB1_CS_L0';
NODE_NAME     U26 BM20
 '@T6G_MB_LIB.T6G(SCH_1):PAGE45_I159@PURE_QUANTA.GENOA_SP5(CHIPS)':
 'MIB1_CS_L1': CDS_PINID='MIB1_CS_L1';
NODE_NAME     U26 BR19
 '@T6G_MB_LIB.T6G(SCH_1):PAGE45_I159@PURE_QUANTA.GENOA_SP5(CHIPS)':
 'MIB1_RSP_L': CDS_PINID='MIB1_RSP_L';
NODE_NAME     U26 BF16
 '@T6G_MB_LIB.T6G(SCH_1):PAGE46_I159@PURE_QUANTA.GENOA_SP5(CHIPS)':
 'MJ1_CLK_H': CDS_PINID='MJ1_CLK_H';
NODE_NAME     U26 BG16
 '@T6G_MB_LIB.T6G(SCH_1):PAGE46_I159@PURE_QUANTA.GENOA_SP5(CHIPS)':
 'MJ1_CLK_L': CDS_PINID='MJ1_CLK_L';
NODE_NAME     U26 AV16
 '@T6G_MB_LIB.T6G(SCH_1):PAGE46_I159@PURE_QUANTA.GENOA_SP5(CHIPS)':
 'MJA1_CS_L0': CDS_PINID='MJA1_CS_L0';
NODE_NAME     U26 AW17
 '@T6G_MB_LIB.T6G(SCH_1):PAGE46_I159@PURE_QUANTA.GENOA_SP5(CHIPS)':
 'MJA1_CS_L1': CDS_PINID='MJA1_CS_L1';
NODE_NAME     U26 BP18
 '@T6G_MB_LIB.T6G(SCH_1):PAGE46_I159@PURE_QUANTA.GENOA_SP5(CHIPS)':
 'MJA1_RSP_L': CDS_PINID='MJA1_RSP_L';
NODE_NAME     U26 BL16
 '@T6G_MB_LIB.T6G(SCH_1):PAGE46_I159@PURE_QUANTA.GENOA_SP5(CHIPS)':
 'MJB1_CS_L0': CDS_PINID='MJB1_CS_L0';
NODE_NAME     U26 BM16
 '@T6G_MB_LIB.T6G(SCH_1):PAGE46_I159@PURE_QUANTA.GENOA_SP5(CHIPS)':
 'MJB1_CS_L1': CDS_PINID='MJB1_CS_L1';
NODE_NAME     U26 BR16
 '@T6G_MB_LIB.T6G(SCH_1):PAGE46_I159@PURE_QUANTA.GENOA_SP5(CHIPS)':
 'MJB1_RSP_L': CDS_PINID='MJB1_RSP_L';
NODE_NAME     U26 BF6
 '@T6G_MB_LIB.T6G(SCH_1):PAGE47_I159@PURE_QUANTA.GENOA_SP5(CHIPS)':
 'MK1_CLK_H': CDS_PINID='MK1_CLK_H';
NODE_NAME     U26 BG5
 '@T6G_MB_LIB.T6G(SCH_1):PAGE47_I159@PURE_QUANTA.GENOA_SP5(CHIPS)':
 'MK1_CLK_L': CDS_PINID='MK1_CLK_L';
NODE_NAME     U26 AV6
 '@T6G_MB_LIB.T6G(SCH_1):PAGE47_I159@PURE_QUANTA.GENOA_SP5(CHIPS)':
 'MKA1_CS_L0': CDS_PINID='MKA1_CS_L0';
NODE_NAME     U26 AW7
 '@T6G_MB_LIB.T6G(SCH_1):PAGE47_I159@PURE_QUANTA.GENOA_SP5(CHIPS)':
 'MKA1_CS_L1': CDS_PINID='MKA1_CS_L1';
NODE_NAME     U26 BP7
 '@T6G_MB_LIB.T6G(SCH_1):PAGE47_I159@PURE_QUANTA.GENOA_SP5(CHIPS)':
 'MKA1_RSP_L': CDS_PINID='MKA1_RSP_L';
NODE_NAME     U26 BL5
 '@T6G_MB_LIB.T6G(SCH_1):PAGE47_I159@PURE_QUANTA.GENOA_SP5(CHIPS)':
 'MKB1_CS_L0': CDS_PINID='MKB1_CS_L0';
NODE_NAME     U26 BM6
 '@T6G_MB_LIB.T6G(SCH_1):PAGE47_I159@PURE_QUANTA.GENOA_SP5(CHIPS)':
 'MKB1_CS_L1': CDS_PINID='MKB1_CS_L1';
NODE_NAME     U26 BR5
 '@T6G_MB_LIB.T6G(SCH_1):PAGE47_I159@PURE_QUANTA.GENOA_SP5(CHIPS)':
 'MKB1_RSP_L': CDS_PINID='MKB1_RSP_L';
NODE_NAME     U26 BF9
 '@T6G_MB_LIB.T6G(SCH_1):PAGE48_I159@PURE_QUANTA.GENOA_SP5(CHIPS)':
 'ML1_CLK_H': CDS_PINID='ML1_CLK_H';
NODE_NAME     U26 BG9
 '@T6G_MB_LIB.T6G(SCH_1):PAGE48_I159@PURE_QUANTA.GENOA_SP5(CHIPS)':
 'ML1_CLK_L': CDS_PINID='ML1_CLK_L';
NODE_NAME     U26 AV9
 '@T6G_MB_LIB.T6G(SCH_1):PAGE48_I159@PURE_QUANTA.GENOA_SP5(CHIPS)':
 'MLA1_CS_L0': CDS_PINID='MLA1_CS_L0';
NODE_NAME     U26 AW10
 '@T6G_MB_LIB.T6G(SCH_1):PAGE48_I159@PURE_QUANTA.GENOA_SP5(CHIPS)':
 'MLA1_CS_L1': CDS_PINID='MLA1_CS_L1';
NODE_NAME     U26 BP11
 '@T6G_MB_LIB.T6G(SCH_1):PAGE48_I159@PURE_QUANTA.GENOA_SP5(CHIPS)':
 'MLA1_RSP_L': CDS_PINID='MLA1_RSP_L';
NODE_NAME     U26 BL9
 '@T6G_MB_LIB.T6G(SCH_1):PAGE48_I159@PURE_QUANTA.GENOA_SP5(CHIPS)':
 'MLB1_CS_L0': CDS_PINID='MLB1_CS_L0';
NODE_NAME     U26 BM9
 '@T6G_MB_LIB.T6G(SCH_1):PAGE48_I159@PURE_QUANTA.GENOA_SP5(CHIPS)':
 'MLB1_CS_L1': CDS_PINID='MLB1_CS_L1';
NODE_NAME     U26 BR9
 '@T6G_MB_LIB.T6G(SCH_1):PAGE48_I159@PURE_QUANTA.GENOA_SP5(CHIPS)':
 'MLB1_RSP_L': CDS_PINID='MLB1_RSP_L';
NODE_NAME     U26 DJ32
 '@T6G_MB_LIB.T6G(SCH_1):PAGE54_I190@PURE_QUANTA.GENOA_SP5(CHIPS)':
 'UART1_TXD||AGPIO142': CDS_PINID='\uart1_txd||agpio142\';
NODE_NAME     U26 DF36
 '@T6G_MB_LIB.T6G(SCH_1):PAGE55_I182@PURE_QUANTA.GENOA_SP5(CHIPS)':
 'AGPIO4||SATA_ACT_L': CDS_PINID='\agpio4||sata_act_l\';
NODE_NAME     U26 DH4
 '@T6G_MB_LIB.T6G(SCH_1):PAGE55_I182@PURE_QUANTA.GENOA_SP5(CHIPS)':
 'AGPIO7': CDS_PINID='AGPIO7';
NODE_NAME     U26 DG11
 '@T6G_MB_LIB.T6G(SCH_1):PAGE55_I182@PURE_QUANTA.GENOA_SP5(CHIPS)':
 'AGPIO87': CDS_PINID='AGPIO87';
NODE_NAME     U26 DJ29
 '@T6G_MB_LIB.T6G(SCH_1):PAGE55_I182@PURE_QUANTA.GENOA_SP5(CHIPS)':
 'AGPIO88': CDS_PINID='AGPIO88';
NODE_NAME     U26 DH30
 '@T6G_MB_LIB.T6G(SCH_1):PAGE55_I182@PURE_QUANTA.GENOA_SP5(CHIPS)':
 'AGPIO104': CDS_PINID='AGPIO104';
NODE_NAME     U26 DE30
 '@T6G_MB_LIB.T6G(SCH_1):PAGE55_I182@PURE_QUANTA.GENOA_SP5(CHIPS)':
 'AGPIO105': CDS_PINID='AGPIO105';
NODE_NAME     U26 DF31
 '@T6G_MB_LIB.T6G(SCH_1):PAGE55_I182@PURE_QUANTA.GENOA_SP5(CHIPS)':
 'AGPIO106': CDS_PINID='AGPIO106';
NODE_NAME     U26 DG31
 '@T6G_MB_LIB.T6G(SCH_1):PAGE55_I182@PURE_QUANTA.GENOA_SP5(CHIPS)':
 'AGPIO107': CDS_PINID='AGPIO107';
NODE_NAME     U26 DG32
 '@T6G_MB_LIB.T6G(SCH_1):PAGE55_I182@PURE_QUANTA.GENOA_SP5(CHIPS)':
 'AGPIO109': CDS_PINID='AGPIO109';
NODE_NAME     U26 A14
 '@T6G_MB_LIB.T6G(SCH_1):PAGE55_I182@PURE_QUANTA.GENOA_SP5(CHIPS)':
 'AGPIO256||SGPIO0_CLK': CDS_PINID='\agpio256||sgpio0_clk\';
NODE_NAME     U26 C14
 '@T6G_MB_LIB.T6G(SCH_1):PAGE55_I182@PURE_QUANTA.GENOA_SP5(CHIPS)':
 'AGPIO257||SGPIO1_CLK||CLK_REQ01_L': CDS_PINID='\agpio257||sgpio1_clk||clk_req01_l\';
NODE_NAME     U26 A13
 '@T6G_MB_LIB.T6G(SCH_1):PAGE55_I182@PURE_QUANTA.GENOA_SP5(CHIPS)':
 'AGPIO258||SGPIO2_CLK||CLK_REQ02_L': CDS_PINID='\agpio258||sgpio2_clk||clk_req02_l\';
NODE_NAME     U26 B16
 '@T6G_MB_LIB.T6G(SCH_1):PAGE55_I182@PURE_QUANTA.GENOA_SP5(CHIPS)':
 'AGPIO259||SGPIO3_CLK': CDS_PINID='\agpio259||sgpio3_clk\';
NODE_NAME     U26 DJ47
 '@T6G_MB_LIB.T6G(SCH_1):PAGE55_I182@PURE_QUANTA.GENOA_SP5(CHIPS)':
 'GPP_CLK14N': CDS_PINID='GPP_CLK14N';
NODE_NAME     U26 DJ48
 '@T6G_MB_LIB.T6G(SCH_1):PAGE55_I182@PURE_QUANTA.GENOA_SP5(CHIPS)':
 'GPP_CLK14P': CDS_PINID='GPP_CLK14P';
NODE_NAME     U26 DJ50
 '@T6G_MB_LIB.T6G(SCH_1):PAGE55_I182@PURE_QUANTA.GENOA_SP5(CHIPS)':
 'GPP_CLK15N': CDS_PINID='GPP_CLK15N';
NODE_NAME     U26 DJ51
 '@T6G_MB_LIB.T6G(SCH_1):PAGE55_I182@PURE_QUANTA.GENOA_SP5(CHIPS)':
 'GPP_CLK15P': CDS_PINID='GPP_CLK15P';
NODE_NAME     U26 DG12
 '@T6G_MB_LIB.T6G(SCH_1):PAGE55_I182@PURE_QUANTA.GENOA_SP5(CHIPS)':
 'I2C4_SCL||HP_SCL||UBM_SCL||AGPIO13': CDS_PINID='\i2c4_scl||hp_scl||ubm_scl||agpio13\';
NODE_NAME     U26 DH12
 '@T6G_MB_LIB.T6G(SCH_1):PAGE55_I182@PURE_QUANTA.GENOA_SP5(CHIPS)':
 'I2C4_SDA||HP_SDA||UBM_SDA||AGPIO14': CDS_PINID='\i2c4_sda||hp_sda||ubm_sda||agpio14\';
NODE_NAME     U26 DJ21
 '@T6G_MB_LIB.T6G(SCH_1):PAGE55_I182@PURE_QUANTA.GENOA_SP5(CHIPS)':
 'I2C5_SCL||BMC_SCL||SMBUS1_SCL||AGPIO19': CDS_PINID='\i2c5_scl||bmc_scl||smbus1_scl||agpio19\';
NODE_NAME     U26 DJ20
 '@T6G_MB_LIB.T6G(SCH_1):PAGE55_I182@PURE_QUANTA.GENOA_SP5(CHIPS)':
 'I2C5_SDA||BMC_SDA||SMBUS1_SDA||AGPIO20': CDS_PINID='\i2c5_sda||bmc_sda||smbus1_sda||agpio20\';
NODE_NAME     U26 C72
 '@T6G_MB_LIB.T6G(SCH_1):PAGE55_I182@PURE_QUANTA.GENOA_SP5(CHIPS)':
 'I3C2_SCL||I2C2_SCL||SPD2_SCL||AGPIO149': CDS_PINID='\i3c2_scl||i2c2_scl||spd2_scl||agpio149\';
NODE_NAME     U26 B72
 '@T6G_MB_LIB.T6G(SCH_1):PAGE55_I182@PURE_QUANTA.GENOA_SP5(CHIPS)':
 'I3C2_SDA||I2C2_SDA||SPD2_SDA||AGPIO150': CDS_PINID='\i3c2_sda||i2c2_sda||spd2_sda||agpio150\';
NODE_NAME     U26 A4
 '@T6G_MB_LIB.T6G(SCH_1):PAGE55_I182@PURE_QUANTA.GENOA_SP5(CHIPS)':
 'I3C3_SCL||I2C3_SCL||SPD3_SCL||AGPIO151': CDS_PINID='\i3c3_scl||i2c3_scl||spd3_scl||agpio151\';
NODE_NAME     U26 B4
 '@T6G_MB_LIB.T6G(SCH_1):PAGE55_I182@PURE_QUANTA.GENOA_SP5(CHIPS)':
 'I3C3_SDA||I2C3_SDA||SPD3_SDA||AGPIO152': CDS_PINID='\i3c3_sda||i2c3_sda||spd3_sda||agpio152\';
NODE_NAME     U26 D15
 '@T6G_MB_LIB.T6G(SCH_1):PAGE55_I182@PURE_QUANTA.GENOA_SP5(CHIPS)':
 'SGPIO_DATAOUT||AGPIO260': CDS_PINID='\sgpio_dataout||agpio260\';
NODE_NAME     U26 B15
 '@T6G_MB_LIB.T6G(SCH_1):PAGE55_I182@PURE_QUANTA.GENOA_SP5(CHIPS)':
 'SGPIO_LOAD||AGPIO261': CDS_PINID='\sgpio_load||agpio261\';
NODE_NAME     U26 DJ25
 '@T6G_MB_LIB.T6G(SCH_1):PAGE56_I8@PURE_QUANTA.GENOA_SP5(CHIPS)':
 'AGPIO76||SPI_TPM_CS_L': CDS_PINID='\agpio76||spi_tpm_cs_l\';
NODE_NAME     U26 DJ22
 '@T6G_MB_LIB.T6G(SCH_1):PAGE56_I8@PURE_QUANTA.GENOA_SP5(CHIPS)':
 'ESPI0_ALERT_L||AGPIO108': CDS_PINID='\espi0_alert_l||agpio108\';
NODE_NAME     U26 DF28
 '@T6G_MB_LIB.T6G(SCH_1):PAGE56_I8@PURE_QUANTA.GENOA_SP5(CHIPS)':
 'ESPI0_DAT0||SPI0_DAT0||AGPIO120': CDS_PINID='\espi0_dat0||spi0_dat0||agpio120\';
NODE_NAME     U26 DG22
 '@T6G_MB_LIB.T6G(SCH_1):PAGE56_I8@PURE_QUANTA.GENOA_SP5(CHIPS)':
 'ESPI0_DAT1||SPI0_DAT1||AGPIO121': CDS_PINID='\espi0_dat1||spi0_dat1||agpio121\';
NODE_NAME     U26 DJ28
 '@T6G_MB_LIB.T6G(SCH_1):PAGE56_I8@PURE_QUANTA.GENOA_SP5(CHIPS)':
 'ESPI0_DAT2||SPI0_DAT2||AGPIO122': CDS_PINID='\espi0_dat2||spi0_dat2||agpio122\';
NODE_NAME     U26 DG29
 '@T6G_MB_LIB.T6G(SCH_1):PAGE56_I8@PURE_QUANTA.GENOA_SP5(CHIPS)':
 'ESPI0_DAT3||SPI0_DAT3||AGPIO123': CDS_PINID='\espi0_dat3||spi0_dat3||agpio123\';
NODE_NAME     U26 DF24
 '@T6G_MB_LIB.T6G(SCH_1):PAGE56_I8@PURE_QUANTA.GENOA_SP5(CHIPS)':
 'ESPI1_ALERT_L||AGPIO110': CDS_PINID='\espi1_alert_l||agpio110\';
NODE_NAME     U26 DH24
 '@T6G_MB_LIB.T6G(SCH_1):PAGE56_I8@PURE_QUANTA.GENOA_SP5(CHIPS)':
 'ESPI1_DAT0||SPI1_DAT0||AGPIO131': CDS_PINID='\espi1_dat0||spi1_dat0||agpio131\';
NODE_NAME     U26 DE24
 '@T6G_MB_LIB.T6G(SCH_1):PAGE56_I8@PURE_QUANTA.GENOA_SP5(CHIPS)':
 'ESPI1_DAT1||SPI1_DAT1||AGPIO132': CDS_PINID='\espi1_dat1||spi1_dat1||agpio132\';
NODE_NAME     U26 DF25
 '@T6G_MB_LIB.T6G(SCH_1):PAGE56_I8@PURE_QUANTA.GENOA_SP5(CHIPS)':
 'ESPI1_DAT2||SPI1_DAT2||AGPIO133': CDS_PINID='\espi1_dat2||spi1_dat2||agpio133\';
NODE_NAME     U26 DG25
 '@T6G_MB_LIB.T6G(SCH_1):PAGE56_I8@PURE_QUANTA.GENOA_SP5(CHIPS)':
 'ESPI1_DAT3||SPI1_DAT3||AGPIO134': CDS_PINID='\espi1_dat3||spi1_dat3||agpio134\';
NODE_NAME     U26 DG23
 '@T6G_MB_LIB.T6G(SCH_1):PAGE56_I8@PURE_QUANTA.GENOA_SP5(CHIPS)':
 'ESPI_CLK1||SPI_CLK1||AGPIO75': CDS_PINID='\espi_clk1||spi_clk1||agpio75\';
NODE_NAME     U26 DG28
 '@T6G_MB_LIB.T6G(SCH_1):PAGE56_I8@PURE_QUANTA.GENOA_SP5(CHIPS)':
 'ESPI_CS0_L||AGPIO124': CDS_PINID='\espi_cs0_l||agpio124\';
NODE_NAME     U26 DJ23
 '@T6G_MB_LIB.T6G(SCH_1):PAGE56_I8@PURE_QUANTA.GENOA_SP5(CHIPS)':
 'ESPI_CS1_L||AGPIO125': CDS_PINID='\espi_cs1_l||agpio125\';
NODE_NAME     U26 DJ26
 '@T6G_MB_LIB.T6G(SCH_1):PAGE56_I8@PURE_QUANTA.GENOA_SP5(CHIPS)':
 'ESPI_RSTIN_L||KBRST_L||AGPIO129': CDS_PINID='\espi_rstin_l||kbrst_l||agpio129\';
NODE_NAME     U26 DE27
 '@T6G_MB_LIB.T6G(SCH_1):PAGE56_I8@PURE_QUANTA.GENOA_SP5(CHIPS)':
 'ESPI_RSTOUT_L||AGPIO23': CDS_PINID='\espi_rstout_l||agpio23\';
NODE_NAME     U26 DF30
 '@T6G_MB_LIB.T6G(SCH_1):PAGE56_I8@PURE_QUANTA.GENOA_SP5(CHIPS)':
 'SPI_CS0_L||AGPIO118': CDS_PINID='\spi_cs0_l||agpio118\';
NODE_NAME     U26 DG26
 '@T6G_MB_LIB.T6G(SCH_1):PAGE56_I8@PURE_QUANTA.GENOA_SP5(CHIPS)':
 'SPI_CS1_L||AGPIO119': CDS_PINID='\spi_cs1_l||agpio119\';
NODE_NAME     U26 DH27
 '@T6G_MB_LIB.T6G(SCH_1):PAGE56_I8@PURE_QUANTA.GENOA_SP5(CHIPS)':
 'SPI_CS2_L||AGPIO126': CDS_PINID='\spi_cs2_l||agpio126\';
NODE_NAME     U26 A31
 '@T6G_MB_LIB.T6G(SCH_1):PAGE57_I46@PURE_QUANTA.GENOA_SP5(CHIPS)':
 'RSVD_A31': CDS_PINID='RSVD_A31';
NODE_NAME     U26 A35
 '@T6G_MB_LIB.T6G(SCH_1):PAGE57_I46@PURE_QUANTA.GENOA_SP5(CHIPS)':
 'RSVD_A35': CDS_PINID='RSVD_A35';
NODE_NAME     U26 A41
 '@T6G_MB_LIB.T6G(SCH_1):PAGE57_I46@PURE_QUANTA.GENOA_SP5(CHIPS)':
 'RSVD_A41': CDS_PINID='RSVD_A41';
NODE_NAME     U26 A42
 '@T6G_MB_LIB.T6G(SCH_1):PAGE57_I46@PURE_QUANTA.GENOA_SP5(CHIPS)':
 'RSVD_A42': CDS_PINID='RSVD_A42';
NODE_NAME     U26 A45
 '@T6G_MB_LIB.T6G(SCH_1):PAGE57_I46@PURE_QUANTA.GENOA_SP5(CHIPS)':
 'RSVD_A45': CDS_PINID='RSVD_A45';
NODE_NAME     U26 A48
 '@T6G_MB_LIB.T6G(SCH_1):PAGE57_I46@PURE_QUANTA.GENOA_SP5(CHIPS)':
 'RSVD_A48': CDS_PINID='RSVD_A48';
NODE_NAME     U26 A50
 '@T6G_MB_LIB.T6G(SCH_1):PAGE57_I46@PURE_QUANTA.GENOA_SP5(CHIPS)':
 'RSVD_A50': CDS_PINID='RSVD_A50';
NODE_NAME     U26 A51
 '@T6G_MB_LIB.T6G(SCH_1):PAGE57_I46@PURE_QUANTA.GENOA_SP5(CHIPS)':
 'RSVD_A51': CDS_PINID='RSVD_A51';
NODE_NAME     U26 A54
 '@T6G_MB_LIB.T6G(SCH_1):PAGE57_I46@PURE_QUANTA.GENOA_SP5(CHIPS)':
 'RSVD_A54': CDS_PINID='RSVD_A54';
NODE_NAME     U26 A55
 '@T6G_MB_LIB.T6G(SCH_1):PAGE57_I46@PURE_QUANTA.GENOA_SP5(CHIPS)':
 'RSVD_A55': CDS_PINID='RSVD_A55';
NODE_NAME     U26 A56
 '@T6G_MB_LIB.T6G(SCH_1):PAGE57_I46@PURE_QUANTA.GENOA_SP5(CHIPS)':
 'RSVD_A56': CDS_PINID='RSVD_A56';
NODE_NAME     U26 A57
 '@T6G_MB_LIB.T6G(SCH_1):PAGE57_I46@PURE_QUANTA.GENOA_SP5(CHIPS)':
 'RSVD_A57': CDS_PINID='RSVD_A57';
NODE_NAME     U26 A59
 '@T6G_MB_LIB.T6G(SCH_1):PAGE57_I46@PURE_QUANTA.GENOA_SP5(CHIPS)':
 'RSVD_A59': CDS_PINID='RSVD_A59';
NODE_NAME     U26 A60
 '@T6G_MB_LIB.T6G(SCH_1):PAGE57_I46@PURE_QUANTA.GENOA_SP5(CHIPS)':
 'RSVD_A60': CDS_PINID='RSVD_A60';
NODE_NAME     U26 B40
 '@T6G_MB_LIB.T6G(SCH_1):PAGE57_I46@PURE_QUANTA.GENOA_SP5(CHIPS)':
 'RSVD_B40': CDS_PINID='RSVD_B40';
NODE_NAME     U26 BD4
 '@T6G_MB_LIB.T6G(SCH_1):PAGE57_I46@PURE_QUANTA.GENOA_SP5(CHIPS)':
 'RSVD_BD4': CDS_PINID='RSVD_BD4';
NODE_NAME     U26 BD7
 '@T6G_MB_LIB.T6G(SCH_1):PAGE57_I46@PURE_QUANTA.GENOA_SP5(CHIPS)':
 'RSVD_BD7': CDS_PINID='RSVD_BD7';
NODE_NAME     U26 BD11
 '@T6G_MB_LIB.T6G(SCH_1):PAGE57_I46@PURE_QUANTA.GENOA_SP5(CHIPS)':
 'RSVD_BD11': CDS_PINID='RSVD_BD11';
NODE_NAME     U26 BD14
 '@T6G_MB_LIB.T6G(SCH_1):PAGE57_I46@PURE_QUANTA.GENOA_SP5(CHIPS)':
 'RSVD_BD14': CDS_PINID='RSVD_BD14';
NODE_NAME     U26 BD18
 '@T6G_MB_LIB.T6G(SCH_1):PAGE57_I46@PURE_QUANTA.GENOA_SP5(CHIPS)':
 'RSVD_BD18': CDS_PINID='RSVD_BD18';
NODE_NAME     U26 BD21
 '@T6G_MB_LIB.T6G(SCH_1):PAGE57_I46@PURE_QUANTA.GENOA_SP5(CHIPS)':
 'RSVD_BD21': CDS_PINID='RSVD_BD21';
NODE_NAME     U26 BD55
 '@T6G_MB_LIB.T6G(SCH_1):PAGE57_I46@PURE_QUANTA.GENOA_SP5(CHIPS)':
 'RSVD_BD55': CDS_PINID='RSVD_BD55';
NODE_NAME     U26 BD58
 '@T6G_MB_LIB.T6G(SCH_1):PAGE57_I46@PURE_QUANTA.GENOA_SP5(CHIPS)':
 'RSVD_BD58': CDS_PINID='RSVD_BD58';
NODE_NAME     U26 BD62
 '@T6G_MB_LIB.T6G(SCH_1):PAGE57_I46@PURE_QUANTA.GENOA_SP5(CHIPS)':
 'RSVD_BD62': CDS_PINID='RSVD_BD62';
NODE_NAME     U26 BD65
 '@T6G_MB_LIB.T6G(SCH_1):PAGE57_I46@PURE_QUANTA.GENOA_SP5(CHIPS)':
 'RSVD_BD65': CDS_PINID='RSVD_BD65';
NODE_NAME     U26 BD69
 '@T6G_MB_LIB.T6G(SCH_1):PAGE57_I46@PURE_QUANTA.GENOA_SP5(CHIPS)':
 'RSVD_BD69': CDS_PINID='RSVD_BD69';
NODE_NAME     U26 BD72
 '@T6G_MB_LIB.T6G(SCH_1):PAGE57_I46@PURE_QUANTA.GENOA_SP5(CHIPS)':
 'RSVD_BD72': CDS_PINID='RSVD_BD72';
NODE_NAME     U26 C31
 '@T6G_MB_LIB.T6G(SCH_1):PAGE57_I46@PURE_QUANTA.GENOA_SP5(CHIPS)':
 'RSVD_C31': CDS_PINID='RSVD_C31';
NODE_NAME     U26 C34
 '@T6G_MB_LIB.T6G(SCH_1):PAGE57_I46@PURE_QUANTA.GENOA_SP5(CHIPS)':
 'RSVD_C34': CDS_PINID='RSVD_C34';
NODE_NAME     U26 C35
 '@T6G_MB_LIB.T6G(SCH_1):PAGE57_I46@PURE_QUANTA.GENOA_SP5(CHIPS)':
 'RSVD_C35': CDS_PINID='RSVD_C35';
NODE_NAME     U26 C53
 '@T6G_MB_LIB.T6G(SCH_1):PAGE57_I46@PURE_QUANTA.GENOA_SP5(CHIPS)':
 'RSVD_C53': CDS_PINID='RSVD_C53';
NODE_NAME     U26 C54
 '@T6G_MB_LIB.T6G(SCH_1):PAGE57_I46@PURE_QUANTA.GENOA_SP5(CHIPS)':
 'RSVD_C54': CDS_PINID='RSVD_C54';
NODE_NAME     U26 D4
 '@T6G_MB_LIB.T6G(SCH_1):PAGE57_I46@PURE_QUANTA.GENOA_SP5(CHIPS)':
 'RSVD_D4': CDS_PINID='RSVD_D4';
NODE_NAME     U26 D8
 '@T6G_MB_LIB.T6G(SCH_1):PAGE57_I46@PURE_QUANTA.GENOA_SP5(CHIPS)':
 'RSVD_D8': CDS_PINID='RSVD_D8';
NODE_NAME     U26 D11
 '@T6G_MB_LIB.T6G(SCH_1):PAGE57_I46@PURE_QUANTA.GENOA_SP5(CHIPS)':
 'RSVD_D11': CDS_PINID='RSVD_D11';
NODE_NAME     U26 D22
 '@T6G_MB_LIB.T6G(SCH_1):PAGE57_I46@PURE_QUANTA.GENOA_SP5(CHIPS)':
 'RSVD_D22': CDS_PINID='RSVD_D22';
NODE_NAME     U26 D34
 '@T6G_MB_LIB.T6G(SCH_1):PAGE57_I46@PURE_QUANTA.GENOA_SP5(CHIPS)':
 'RSVD_D34': CDS_PINID='RSVD_D34';
NODE_NAME     U26 D36
 '@T6G_MB_LIB.T6G(SCH_1):PAGE57_I46@PURE_QUANTA.GENOA_SP5(CHIPS)':
 'RSVD_D36': CDS_PINID='RSVD_D36';
NODE_NAME     U26 D58
 '@T6G_MB_LIB.T6G(SCH_1):PAGE57_I46@PURE_QUANTA.GENOA_SP5(CHIPS)':
 'RSVD_D58': CDS_PINID='RSVD_D58';
NODE_NAME     U26 D62
 '@T6G_MB_LIB.T6G(SCH_1):PAGE57_I46@PURE_QUANTA.GENOA_SP5(CHIPS)':
 'RSVD_D62': CDS_PINID='RSVD_D62';
NODE_NAME     U26 D65
 '@T6G_MB_LIB.T6G(SCH_1):PAGE57_I46@PURE_QUANTA.GENOA_SP5(CHIPS)':
 'RSVD_D65': CDS_PINID='RSVD_D65';
NODE_NAME     U26 D72
 '@T6G_MB_LIB.T6G(SCH_1):PAGE57_I46@PURE_QUANTA.GENOA_SP5(CHIPS)':
 'RSVD_D72': CDS_PINID='RSVD_D72';
NODE_NAME     U26 DG17
 '@T6G_MB_LIB.T6G(SCH_1):PAGE57_I46@PURE_QUANTA.GENOA_SP5(CHIPS)':
 'RSVD_DG17': CDS_PINID='RSVD_DG17';
NODE_NAME     U26 DH17
 '@T6G_MB_LIB.T6G(SCH_1):PAGE57_I46@PURE_QUANTA.GENOA_SP5(CHIPS)':
 'RSVD_DH17': CDS_PINID='RSVD_DH17';
NODE_NAME     U26 DH21
 '@T6G_MB_LIB.T6G(SCH_1):PAGE57_I46@PURE_QUANTA.GENOA_SP5(CHIPS)':
 'RSVD_DH21': CDS_PINID='RSVD_DH21';
NODE_NAME     U26 DJ4
 '@T6G_MB_LIB.T6G(SCH_1):PAGE57_I46@PURE_QUANTA.GENOA_SP5(CHIPS)':
 'RSVD_DJ4': CDS_PINID='RSVD_DJ4';
NODE_NAME     U26 E33
 '@T6G_MB_LIB.T6G(SCH_1):PAGE57_I46@PURE_QUANTA.GENOA_SP5(CHIPS)':
 'RSVD_E33': CDS_PINID='RSVD_E33';
NODE_NAME     U26 E36
 '@T6G_MB_LIB.T6G(SCH_1):PAGE57_I46@PURE_QUANTA.GENOA_SP5(CHIPS)':
 'RSVD_E36': CDS_PINID='RSVD_E36';
NODE_NAME     U26 C58
 '@T6G_MB_LIB.T6G(SCH_1):PAGE57_I46@PURE_QUANTA.GENOA_SP5(CHIPS)':
 'TEST4_CCD12': CDS_PINID='TEST4_CCD12';
NODE_NAME     U26 DH13
 '@T6G_MB_LIB.T6G(SCH_1):PAGE57_I46@PURE_QUANTA.GENOA_SP5(CHIPS)':
 'TEST4_CCD13': CDS_PINID='TEST4_CCD13';
NODE_NAME     U26 DF41
 '@T6G_MB_LIB.T6G(SCH_1):PAGE57_I46@PURE_QUANTA.GENOA_SP5(CHIPS)':
 'TEST4_CCD14': CDS_PINID='TEST4_CCD14';
NODE_NAME     U26 C23
 '@T6G_MB_LIB.T6G(SCH_1):PAGE57_I46@PURE_QUANTA.GENOA_SP5(CHIPS)':
 'TEST4_CCD15': CDS_PINID='TEST4_CCD15';
NODE_NAME     U26 C59
 '@T6G_MB_LIB.T6G(SCH_1):PAGE57_I46@PURE_QUANTA.GENOA_SP5(CHIPS)':
 'TEST5_CCD12': CDS_PINID='TEST5_CCD12';
NODE_NAME     U26 DH14
 '@T6G_MB_LIB.T6G(SCH_1):PAGE57_I46@PURE_QUANTA.GENOA_SP5(CHIPS)':
 'TEST5_CCD13': CDS_PINID='TEST5_CCD13';
NODE_NAME     U26 DG42
 '@T6G_MB_LIB.T6G(SCH_1):PAGE57_I46@PURE_QUANTA.GENOA_SP5(CHIPS)':
 'TEST5_CCD14': CDS_PINID='TEST5_CCD14';
NODE_NAME     U26 D23
 '@T6G_MB_LIB.T6G(SCH_1):PAGE57_I46@PURE_QUANTA.GENOA_SP5(CHIPS)':
 'TEST5_CCD15': CDS_PINID='TEST5_CCD15';
NODE_NAME     U26 B36
 '@T6G_MB_LIB.T6G(SCH_1):PAGE57_I46@PURE_QUANTA.GENOA_SP5(CHIPS)':
 'TEST6_X3D6': CDS_PINID='TEST6_X3D6';
NODE_NAME     U26 DJ57
 '@T6G_MB_LIB.T6G(SCH_1):PAGE57_I46@PURE_QUANTA.GENOA_SP5(CHIPS)':
 'TEST6_X3D7': CDS_PINID='TEST6_X3D7';
NODE_NAME     J15 2
 '@T6G_MB_LIB.T6G(SCH_1):PAGE86_I350@PURE_QUANTA.SCONN288_DDR506112002KQ(CHIPS)':
 'RFU0': CDS_PINID='RFU0';
NODE_NAME     J15 144
 '@T6G_MB_LIB.T6G(SCH_1):PAGE86_I350@PURE_QUANTA.SCONN288_DDR506112002KQ(CHIPS)':
 'RFU1': CDS_PINID='RFU1';
NODE_NAME     J15 149
 '@T6G_MB_LIB.T6G(SCH_1):PAGE86_I350@PURE_QUANTA.SCONN288_DDR506112002KQ(CHIPS)':
 'RFU2': CDS_PINID='RFU2';
NODE_NAME     J15 150
 '@T6G_MB_LIB.T6G(SCH_1):PAGE86_I350@PURE_QUANTA.SCONN288_DDR506112002KQ(CHIPS)':
 'RFU3': CDS_PINID='RFU3';
NODE_NAME     J15 220
 '@T6G_MB_LIB.T6G(SCH_1):PAGE86_I350@PURE_QUANTA.SCONN288_DDR506112002KQ(CHIPS)':
 'RFU4': CDS_PINID='RFU4';
NODE_NAME     J15 231
 '@T6G_MB_LIB.T6G(SCH_1):PAGE86_I350@PURE_QUANTA.SCONN288_DDR506112002KQ(CHIPS)':
 'RFU5': CDS_PINID='RFU5';
NODE_NAME     J15 232
 '@T6G_MB_LIB.T6G(SCH_1):PAGE86_I350@PURE_QUANTA.SCONN288_DDR506112002KQ(CHIPS)':
 'RFU6': CDS_PINID='RFU6';
NODE_NAME     J17 2
 '@T6G_MB_LIB.T6G(SCH_1):PAGE87_I350@PURE_QUANTA.SCONN288_DDR506112002KQ(CHIPS)':
 'RFU0': CDS_PINID='RFU0';
NODE_NAME     J17 144
 '@T6G_MB_LIB.T6G(SCH_1):PAGE87_I350@PURE_QUANTA.SCONN288_DDR506112002KQ(CHIPS)':
 'RFU1': CDS_PINID='RFU1';
NODE_NAME     J17 149
 '@T6G_MB_LIB.T6G(SCH_1):PAGE87_I350@PURE_QUANTA.SCONN288_DDR506112002KQ(CHIPS)':
 'RFU2': CDS_PINID='RFU2';
NODE_NAME     J17 150
 '@T6G_MB_LIB.T6G(SCH_1):PAGE87_I350@PURE_QUANTA.SCONN288_DDR506112002KQ(CHIPS)':
 'RFU3': CDS_PINID='RFU3';
NODE_NAME     J17 220
 '@T6G_MB_LIB.T6G(SCH_1):PAGE87_I350@PURE_QUANTA.SCONN288_DDR506112002KQ(CHIPS)':
 'RFU4': CDS_PINID='RFU4';
NODE_NAME     J17 231
 '@T6G_MB_LIB.T6G(SCH_1):PAGE87_I350@PURE_QUANTA.SCONN288_DDR506112002KQ(CHIPS)':
 'RFU5': CDS_PINID='RFU5';
NODE_NAME     J17 232
 '@T6G_MB_LIB.T6G(SCH_1):PAGE87_I350@PURE_QUANTA.SCONN288_DDR506112002KQ(CHIPS)':
 'RFU6': CDS_PINID='RFU6';
NODE_NAME     J19 2
 '@T6G_MB_LIB.T6G(SCH_1):PAGE88_I350@PURE_QUANTA.SCONN288_DDR506112002KQ(CHIPS)':
 'RFU0': CDS_PINID='RFU0';
NODE_NAME     J19 144
 '@T6G_MB_LIB.T6G(SCH_1):PAGE88_I350@PURE_QUANTA.SCONN288_DDR506112002KQ(CHIPS)':
 'RFU1': CDS_PINID='RFU1';
NODE_NAME     J19 149
 '@T6G_MB_LIB.T6G(SCH_1):PAGE88_I350@PURE_QUANTA.SCONN288_DDR506112002KQ(CHIPS)':
 'RFU2': CDS_PINID='RFU2';
NODE_NAME     J19 150
 '@T6G_MB_LIB.T6G(SCH_1):PAGE88_I350@PURE_QUANTA.SCONN288_DDR506112002KQ(CHIPS)':
 'RFU3': CDS_PINID='RFU3';
NODE_NAME     J19 220
 '@T6G_MB_LIB.T6G(SCH_1):PAGE88_I350@PURE_QUANTA.SCONN288_DDR506112002KQ(CHIPS)':
 'RFU4': CDS_PINID='RFU4';
NODE_NAME     J19 231
 '@T6G_MB_LIB.T6G(SCH_1):PAGE88_I350@PURE_QUANTA.SCONN288_DDR506112002KQ(CHIPS)':
 'RFU5': CDS_PINID='RFU5';
NODE_NAME     J19 232
 '@T6G_MB_LIB.T6G(SCH_1):PAGE88_I350@PURE_QUANTA.SCONN288_DDR506112002KQ(CHIPS)':
 'RFU6': CDS_PINID='RFU6';
NODE_NAME     J21 2
 '@T6G_MB_LIB.T6G(SCH_1):PAGE89_I348@PURE_QUANTA.SCONN288_DDR506112002KQ(CHIPS)':
 'RFU0': CDS_PINID='RFU0';
NODE_NAME     J21 144
 '@T6G_MB_LIB.T6G(SCH_1):PAGE89_I348@PURE_QUANTA.SCONN288_DDR506112002KQ(CHIPS)':
 'RFU1': CDS_PINID='RFU1';
NODE_NAME     J21 149
 '@T6G_MB_LIB.T6G(SCH_1):PAGE89_I348@PURE_QUANTA.SCONN288_DDR506112002KQ(CHIPS)':
 'RFU2': CDS_PINID='RFU2';
NODE_NAME     J21 150
 '@T6G_MB_LIB.T6G(SCH_1):PAGE89_I348@PURE_QUANTA.SCONN288_DDR506112002KQ(CHIPS)':
 'RFU3': CDS_PINID='RFU3';
NODE_NAME     J21 220
 '@T6G_MB_LIB.T6G(SCH_1):PAGE89_I348@PURE_QUANTA.SCONN288_DDR506112002KQ(CHIPS)':
 'RFU4': CDS_PINID='RFU4';
NODE_NAME     J21 231
 '@T6G_MB_LIB.T6G(SCH_1):PAGE89_I348@PURE_QUANTA.SCONN288_DDR506112002KQ(CHIPS)':
 'RFU5': CDS_PINID='RFU5';
NODE_NAME     J21 232
 '@T6G_MB_LIB.T6G(SCH_1):PAGE89_I348@PURE_QUANTA.SCONN288_DDR506112002KQ(CHIPS)':
 'RFU6': CDS_PINID='RFU6';
NODE_NAME     J23 2
 '@T6G_MB_LIB.T6G(SCH_1):PAGE90_I350@PURE_QUANTA.SCONN288_DDR506112002KQ(CHIPS)':
 'RFU0': CDS_PINID='RFU0';
NODE_NAME     J23 144
 '@T6G_MB_LIB.T6G(SCH_1):PAGE90_I350@PURE_QUANTA.SCONN288_DDR506112002KQ(CHIPS)':
 'RFU1': CDS_PINID='RFU1';
NODE_NAME     J23 149
 '@T6G_MB_LIB.T6G(SCH_1):PAGE90_I350@PURE_QUANTA.SCONN288_DDR506112002KQ(CHIPS)':
 'RFU2': CDS_PINID='RFU2';
NODE_NAME     J23 150
 '@T6G_MB_LIB.T6G(SCH_1):PAGE90_I350@PURE_QUANTA.SCONN288_DDR506112002KQ(CHIPS)':
 'RFU3': CDS_PINID='RFU3';
NODE_NAME     J23 220
 '@T6G_MB_LIB.T6G(SCH_1):PAGE90_I350@PURE_QUANTA.SCONN288_DDR506112002KQ(CHIPS)':
 'RFU4': CDS_PINID='RFU4';
NODE_NAME     J23 231
 '@T6G_MB_LIB.T6G(SCH_1):PAGE90_I350@PURE_QUANTA.SCONN288_DDR506112002KQ(CHIPS)':
 'RFU5': CDS_PINID='RFU5';
NODE_NAME     J23 232
 '@T6G_MB_LIB.T6G(SCH_1):PAGE90_I350@PURE_QUANTA.SCONN288_DDR506112002KQ(CHIPS)':
 'RFU6': CDS_PINID='RFU6';
NODE_NAME     J16 2
 '@T6G_MB_LIB.T6G(SCH_1):PAGE91_I22@PURE_QUANTA.SCONN288_DDR506112002KQ(CHIPS)':
 'RFU0': CDS_PINID='RFU0';
NODE_NAME     J16 144
 '@T6G_MB_LIB.T6G(SCH_1):PAGE91_I22@PURE_QUANTA.SCONN288_DDR506112002KQ(CHIPS)':
 'RFU1': CDS_PINID='RFU1';
NODE_NAME     J16 149
 '@T6G_MB_LIB.T6G(SCH_1):PAGE91_I22@PURE_QUANTA.SCONN288_DDR506112002KQ(CHIPS)':
 'RFU2': CDS_PINID='RFU2';
NODE_NAME     J16 150
 '@T6G_MB_LIB.T6G(SCH_1):PAGE91_I22@PURE_QUANTA.SCONN288_DDR506112002KQ(CHIPS)':
 'RFU3': CDS_PINID='RFU3';
NODE_NAME     J16 220
 '@T6G_MB_LIB.T6G(SCH_1):PAGE91_I22@PURE_QUANTA.SCONN288_DDR506112002KQ(CHIPS)':
 'RFU4': CDS_PINID='RFU4';
NODE_NAME     J16 231
 '@T6G_MB_LIB.T6G(SCH_1):PAGE91_I22@PURE_QUANTA.SCONN288_DDR506112002KQ(CHIPS)':
 'RFU5': CDS_PINID='RFU5';
NODE_NAME     J16 232
 '@T6G_MB_LIB.T6G(SCH_1):PAGE91_I22@PURE_QUANTA.SCONN288_DDR506112002KQ(CHIPS)':
 'RFU6': CDS_PINID='RFU6';
NODE_NAME     J69 2
 '@T6G_MB_LIB.T6G(SCH_1):PAGE92_I22@PURE_QUANTA.SCONN288_DDR506112002KQ(CHIPS)':
 'RFU0': CDS_PINID='RFU0';
NODE_NAME     J69 144
 '@T6G_MB_LIB.T6G(SCH_1):PAGE92_I22@PURE_QUANTA.SCONN288_DDR506112002KQ(CHIPS)':
 'RFU1': CDS_PINID='RFU1';
NODE_NAME     J69 149
 '@T6G_MB_LIB.T6G(SCH_1):PAGE92_I22@PURE_QUANTA.SCONN288_DDR506112002KQ(CHIPS)':
 'RFU2': CDS_PINID='RFU2';
NODE_NAME     J69 150
 '@T6G_MB_LIB.T6G(SCH_1):PAGE92_I22@PURE_QUANTA.SCONN288_DDR506112002KQ(CHIPS)':
 'RFU3': CDS_PINID='RFU3';
NODE_NAME     J69 220
 '@T6G_MB_LIB.T6G(SCH_1):PAGE92_I22@PURE_QUANTA.SCONN288_DDR506112002KQ(CHIPS)':
 'RFU4': CDS_PINID='RFU4';
NODE_NAME     J69 231
 '@T6G_MB_LIB.T6G(SCH_1):PAGE92_I22@PURE_QUANTA.SCONN288_DDR506112002KQ(CHIPS)':
 'RFU5': CDS_PINID='RFU5';
NODE_NAME     J69 232
 '@T6G_MB_LIB.T6G(SCH_1):PAGE92_I22@PURE_QUANTA.SCONN288_DDR506112002KQ(CHIPS)':
 'RFU6': CDS_PINID='RFU6';
NODE_NAME     J18 2
 '@T6G_MB_LIB.T6G(SCH_1):PAGE93_I22@PURE_QUANTA.SCONN288_DDR506112002KQ(CHIPS)':
 'RFU0': CDS_PINID='RFU0';
NODE_NAME     J18 144
 '@T6G_MB_LIB.T6G(SCH_1):PAGE93_I22@PURE_QUANTA.SCONN288_DDR506112002KQ(CHIPS)':
 'RFU1': CDS_PINID='RFU1';
NODE_NAME     J18 149
 '@T6G_MB_LIB.T6G(SCH_1):PAGE93_I22@PURE_QUANTA.SCONN288_DDR506112002KQ(CHIPS)':
 'RFU2': CDS_PINID='RFU2';
NODE_NAME     J18 150
 '@T6G_MB_LIB.T6G(SCH_1):PAGE93_I22@PURE_QUANTA.SCONN288_DDR506112002KQ(CHIPS)':
 'RFU3': CDS_PINID='RFU3';
NODE_NAME     J18 220
 '@T6G_MB_LIB.T6G(SCH_1):PAGE93_I22@PURE_QUANTA.SCONN288_DDR506112002KQ(CHIPS)':
 'RFU4': CDS_PINID='RFU4';
NODE_NAME     J18 231
 '@T6G_MB_LIB.T6G(SCH_1):PAGE93_I22@PURE_QUANTA.SCONN288_DDR506112002KQ(CHIPS)':
 'RFU5': CDS_PINID='RFU5';
NODE_NAME     J18 232
 '@T6G_MB_LIB.T6G(SCH_1):PAGE93_I22@PURE_QUANTA.SCONN288_DDR506112002KQ(CHIPS)':
 'RFU6': CDS_PINID='RFU6';
NODE_NAME     J68 2
 '@T6G_MB_LIB.T6G(SCH_1):PAGE94_I22@PURE_QUANTA.SCONN288_DDR506112002KQ(CHIPS)':
 'RFU0': CDS_PINID='RFU0';
NODE_NAME     J68 144
 '@T6G_MB_LIB.T6G(SCH_1):PAGE94_I22@PURE_QUANTA.SCONN288_DDR506112002KQ(CHIPS)':
 'RFU1': CDS_PINID='RFU1';
NODE_NAME     J68 149
 '@T6G_MB_LIB.T6G(SCH_1):PAGE94_I22@PURE_QUANTA.SCONN288_DDR506112002KQ(CHIPS)':
 'RFU2': CDS_PINID='RFU2';
NODE_NAME     J68 150
 '@T6G_MB_LIB.T6G(SCH_1):PAGE94_I22@PURE_QUANTA.SCONN288_DDR506112002KQ(CHIPS)':
 'RFU3': CDS_PINID='RFU3';
NODE_NAME     J68 220
 '@T6G_MB_LIB.T6G(SCH_1):PAGE94_I22@PURE_QUANTA.SCONN288_DDR506112002KQ(CHIPS)':
 'RFU4': CDS_PINID='RFU4';
NODE_NAME     J68 231
 '@T6G_MB_LIB.T6G(SCH_1):PAGE94_I22@PURE_QUANTA.SCONN288_DDR506112002KQ(CHIPS)':
 'RFU5': CDS_PINID='RFU5';
NODE_NAME     J68 232
 '@T6G_MB_LIB.T6G(SCH_1):PAGE94_I22@PURE_QUANTA.SCONN288_DDR506112002KQ(CHIPS)':
 'RFU6': CDS_PINID='RFU6';
NODE_NAME     J20 2
 '@T6G_MB_LIB.T6G(SCH_1):PAGE95_I22@PURE_QUANTA.SCONN288_DDR506112002KQ(CHIPS)':
 'RFU0': CDS_PINID='RFU0';
NODE_NAME     J20 144
 '@T6G_MB_LIB.T6G(SCH_1):PAGE95_I22@PURE_QUANTA.SCONN288_DDR506112002KQ(CHIPS)':
 'RFU1': CDS_PINID='RFU1';
NODE_NAME     J20 149
 '@T6G_MB_LIB.T6G(SCH_1):PAGE95_I22@PURE_QUANTA.SCONN288_DDR506112002KQ(CHIPS)':
 'RFU2': CDS_PINID='RFU2';
NODE_NAME     J20 150
 '@T6G_MB_LIB.T6G(SCH_1):PAGE95_I22@PURE_QUANTA.SCONN288_DDR506112002KQ(CHIPS)':
 'RFU3': CDS_PINID='RFU3';
NODE_NAME     J20 220
 '@T6G_MB_LIB.T6G(SCH_1):PAGE95_I22@PURE_QUANTA.SCONN288_DDR506112002KQ(CHIPS)':
 'RFU4': CDS_PINID='RFU4';
NODE_NAME     J20 231
 '@T6G_MB_LIB.T6G(SCH_1):PAGE95_I22@PURE_QUANTA.SCONN288_DDR506112002KQ(CHIPS)':
 'RFU5': CDS_PINID='RFU5';
NODE_NAME     J20 232
 '@T6G_MB_LIB.T6G(SCH_1):PAGE95_I22@PURE_QUANTA.SCONN288_DDR506112002KQ(CHIPS)':
 'RFU6': CDS_PINID='RFU6';
NODE_NAME     J67 2
 '@T6G_MB_LIB.T6G(SCH_1):PAGE96_I22@PURE_QUANTA.SCONN288_DDR506112002KQ(CHIPS)':
 'RFU0': CDS_PINID='RFU0';
NODE_NAME     J67 144
 '@T6G_MB_LIB.T6G(SCH_1):PAGE96_I22@PURE_QUANTA.SCONN288_DDR506112002KQ(CHIPS)':
 'RFU1': CDS_PINID='RFU1';
NODE_NAME     J67 149
 '@T6G_MB_LIB.T6G(SCH_1):PAGE96_I22@PURE_QUANTA.SCONN288_DDR506112002KQ(CHIPS)':
 'RFU2': CDS_PINID='RFU2';
NODE_NAME     J67 150
 '@T6G_MB_LIB.T6G(SCH_1):PAGE96_I22@PURE_QUANTA.SCONN288_DDR506112002KQ(CHIPS)':
 'RFU3': CDS_PINID='RFU3';
NODE_NAME     J67 220
 '@T6G_MB_LIB.T6G(SCH_1):PAGE96_I22@PURE_QUANTA.SCONN288_DDR506112002KQ(CHIPS)':
 'RFU4': CDS_PINID='RFU4';
NODE_NAME     J67 231
 '@T6G_MB_LIB.T6G(SCH_1):PAGE96_I22@PURE_QUANTA.SCONN288_DDR506112002KQ(CHIPS)':
 'RFU5': CDS_PINID='RFU5';
NODE_NAME     J67 232
 '@T6G_MB_LIB.T6G(SCH_1):PAGE96_I22@PURE_QUANTA.SCONN288_DDR506112002KQ(CHIPS)':
 'RFU6': CDS_PINID='RFU6';
NODE_NAME     J24 2
 '@T6G_MB_LIB.T6G(SCH_1):PAGE97_I22@PURE_QUANTA.SCONN288_DDR506112002KQ(CHIPS)':
 'RFU0': CDS_PINID='RFU0';
NODE_NAME     J24 144
 '@T6G_MB_LIB.T6G(SCH_1):PAGE97_I22@PURE_QUANTA.SCONN288_DDR506112002KQ(CHIPS)':
 'RFU1': CDS_PINID='RFU1';
NODE_NAME     J24 149
 '@T6G_MB_LIB.T6G(SCH_1):PAGE97_I22@PURE_QUANTA.SCONN288_DDR506112002KQ(CHIPS)':
 'RFU2': CDS_PINID='RFU2';
NODE_NAME     J24 150
 '@T6G_MB_LIB.T6G(SCH_1):PAGE97_I22@PURE_QUANTA.SCONN288_DDR506112002KQ(CHIPS)':
 'RFU3': CDS_PINID='RFU3';
NODE_NAME     J24 220
 '@T6G_MB_LIB.T6G(SCH_1):PAGE97_I22@PURE_QUANTA.SCONN288_DDR506112002KQ(CHIPS)':
 'RFU4': CDS_PINID='RFU4';
NODE_NAME     J24 231
 '@T6G_MB_LIB.T6G(SCH_1):PAGE97_I22@PURE_QUANTA.SCONN288_DDR506112002KQ(CHIPS)':
 'RFU5': CDS_PINID='RFU5';
NODE_NAME     J24 232
 '@T6G_MB_LIB.T6G(SCH_1):PAGE97_I22@PURE_QUANTA.SCONN288_DDR506112002KQ(CHIPS)':
 'RFU6': CDS_PINID='RFU6';
NODE_NAME     J26 2
 '@T6G_MB_LIB.T6G(SCH_1):PAGE98_I22@PURE_QUANTA.SCONN288_DDR506112002KQ(CHIPS)':
 'RFU0': CDS_PINID='RFU0';
NODE_NAME     J26 144
 '@T6G_MB_LIB.T6G(SCH_1):PAGE98_I22@PURE_QUANTA.SCONN288_DDR506112002KQ(CHIPS)':
 'RFU1': CDS_PINID='RFU1';
NODE_NAME     J26 149
 '@T6G_MB_LIB.T6G(SCH_1):PAGE98_I22@PURE_QUANTA.SCONN288_DDR506112002KQ(CHIPS)':
 'RFU2': CDS_PINID='RFU2';
NODE_NAME     J26 150
 '@T6G_MB_LIB.T6G(SCH_1):PAGE98_I22@PURE_QUANTA.SCONN288_DDR506112002KQ(CHIPS)':
 'RFU3': CDS_PINID='RFU3';
NODE_NAME     J26 220
 '@T6G_MB_LIB.T6G(SCH_1):PAGE98_I22@PURE_QUANTA.SCONN288_DDR506112002KQ(CHIPS)':
 'RFU4': CDS_PINID='RFU4';
NODE_NAME     J26 231
 '@T6G_MB_LIB.T6G(SCH_1):PAGE98_I22@PURE_QUANTA.SCONN288_DDR506112002KQ(CHIPS)':
 'RFU5': CDS_PINID='RFU5';
NODE_NAME     J26 232
 '@T6G_MB_LIB.T6G(SCH_1):PAGE98_I22@PURE_QUANTA.SCONN288_DDR506112002KQ(CHIPS)':
 'RFU6': CDS_PINID='RFU6';
NODE_NAME     J28 2
 '@T6G_MB_LIB.T6G(SCH_1):PAGE99_I22@PURE_QUANTA.SCONN288_DDR506112002KQ(CHIPS)':
 'RFU0': CDS_PINID='RFU0';
NODE_NAME     J28 144
 '@T6G_MB_LIB.T6G(SCH_1):PAGE99_I22@PURE_QUANTA.SCONN288_DDR506112002KQ(CHIPS)':
 'RFU1': CDS_PINID='RFU1';
NODE_NAME     J28 149
 '@T6G_MB_LIB.T6G(SCH_1):PAGE99_I22@PURE_QUANTA.SCONN288_DDR506112002KQ(CHIPS)':
 'RFU2': CDS_PINID='RFU2';
NODE_NAME     J28 150
 '@T6G_MB_LIB.T6G(SCH_1):PAGE99_I22@PURE_QUANTA.SCONN288_DDR506112002KQ(CHIPS)':
 'RFU3': CDS_PINID='RFU3';
NODE_NAME     J28 220
 '@T6G_MB_LIB.T6G(SCH_1):PAGE99_I22@PURE_QUANTA.SCONN288_DDR506112002KQ(CHIPS)':
 'RFU4': CDS_PINID='RFU4';
NODE_NAME     J28 231
 '@T6G_MB_LIB.T6G(SCH_1):PAGE99_I22@PURE_QUANTA.SCONN288_DDR506112002KQ(CHIPS)':
 'RFU5': CDS_PINID='RFU5';
NODE_NAME     J28 232
 '@T6G_MB_LIB.T6G(SCH_1):PAGE99_I22@PURE_QUANTA.SCONN288_DDR506112002KQ(CHIPS)':
 'RFU6': CDS_PINID='RFU6';
NODE_NAME     J30 2
 '@T6G_MB_LIB.T6G(SCH_1):PAGE100_I52@PURE_QUANTA.SCONN288_DDR506112002KQ(CHIPS)':
 'RFU0': CDS_PINID='RFU0';
NODE_NAME     J30 144
 '@T6G_MB_LIB.T6G(SCH_1):PAGE100_I52@PURE_QUANTA.SCONN288_DDR506112002KQ(CHIPS)':
 'RFU1': CDS_PINID='RFU1';
NODE_NAME     J30 149
 '@T6G_MB_LIB.T6G(SCH_1):PAGE100_I52@PURE_QUANTA.SCONN288_DDR506112002KQ(CHIPS)':
 'RFU2': CDS_PINID='RFU2';
NODE_NAME     J30 150
 '@T6G_MB_LIB.T6G(SCH_1):PAGE100_I52@PURE_QUANTA.SCONN288_DDR506112002KQ(CHIPS)':
 'RFU3': CDS_PINID='RFU3';
NODE_NAME     J30 220
 '@T6G_MB_LIB.T6G(SCH_1):PAGE100_I52@PURE_QUANTA.SCONN288_DDR506112002KQ(CHIPS)':
 'RFU4': CDS_PINID='RFU4';
NODE_NAME     J30 231
 '@T6G_MB_LIB.T6G(SCH_1):PAGE100_I52@PURE_QUANTA.SCONN288_DDR506112002KQ(CHIPS)':
 'RFU5': CDS_PINID='RFU5';
NODE_NAME     J30 232
 '@T6G_MB_LIB.T6G(SCH_1):PAGE100_I52@PURE_QUANTA.SCONN288_DDR506112002KQ(CHIPS)':
 'RFU6': CDS_PINID='RFU6';
NODE_NAME     J32 2
 '@T6G_MB_LIB.T6G(SCH_1):PAGE101_I52@PURE_QUANTA.SCONN288_DDR506112002KQ(CHIPS)':
 'RFU0': CDS_PINID='RFU0';
NODE_NAME     J32 144
 '@T6G_MB_LIB.T6G(SCH_1):PAGE101_I52@PURE_QUANTA.SCONN288_DDR506112002KQ(CHIPS)':
 'RFU1': CDS_PINID='RFU1';
NODE_NAME     J32 149
 '@T6G_MB_LIB.T6G(SCH_1):PAGE101_I52@PURE_QUANTA.SCONN288_DDR506112002KQ(CHIPS)':
 'RFU2': CDS_PINID='RFU2';
NODE_NAME     J32 150
 '@T6G_MB_LIB.T6G(SCH_1):PAGE101_I52@PURE_QUANTA.SCONN288_DDR506112002KQ(CHIPS)':
 'RFU3': CDS_PINID='RFU3';
NODE_NAME     J32 220
 '@T6G_MB_LIB.T6G(SCH_1):PAGE101_I52@PURE_QUANTA.SCONN288_DDR506112002KQ(CHIPS)':
 'RFU4': CDS_PINID='RFU4';
NODE_NAME     J32 231
 '@T6G_MB_LIB.T6G(SCH_1):PAGE101_I52@PURE_QUANTA.SCONN288_DDR506112002KQ(CHIPS)':
 'RFU5': CDS_PINID='RFU5';
NODE_NAME     J32 232
 '@T6G_MB_LIB.T6G(SCH_1):PAGE101_I52@PURE_QUANTA.SCONN288_DDR506112002KQ(CHIPS)':
 'RFU6': CDS_PINID='RFU6';
NODE_NAME     J33 2
 '@T6G_MB_LIB.T6G(SCH_1):PAGE102_I22@PURE_QUANTA.SCONN288_DDR506112002KQ(CHIPS)':
 'RFU0': CDS_PINID='RFU0';
NODE_NAME     J33 144
 '@T6G_MB_LIB.T6G(SCH_1):PAGE102_I22@PURE_QUANTA.SCONN288_DDR506112002KQ(CHIPS)':
 'RFU1': CDS_PINID='RFU1';
NODE_NAME     J33 149
 '@T6G_MB_LIB.T6G(SCH_1):PAGE102_I22@PURE_QUANTA.SCONN288_DDR506112002KQ(CHIPS)':
 'RFU2': CDS_PINID='RFU2';
NODE_NAME     J33 150
 '@T6G_MB_LIB.T6G(SCH_1):PAGE102_I22@PURE_QUANTA.SCONN288_DDR506112002KQ(CHIPS)':
 'RFU3': CDS_PINID='RFU3';
NODE_NAME     J33 220
 '@T6G_MB_LIB.T6G(SCH_1):PAGE102_I22@PURE_QUANTA.SCONN288_DDR506112002KQ(CHIPS)':
 'RFU4': CDS_PINID='RFU4';
NODE_NAME     J33 231
 '@T6G_MB_LIB.T6G(SCH_1):PAGE102_I22@PURE_QUANTA.SCONN288_DDR506112002KQ(CHIPS)':
 'RFU5': CDS_PINID='RFU5';
NODE_NAME     J33 232
 '@T6G_MB_LIB.T6G(SCH_1):PAGE102_I22@PURE_QUANTA.SCONN288_DDR506112002KQ(CHIPS)':
 'RFU6': CDS_PINID='RFU6';
NODE_NAME     J102 2
 '@T6G_MB_LIB.T6G(SCH_1):PAGE103_I22@PURE_QUANTA.SCONN288_DDR506112002KQ(CHIPS)':
 'RFU0': CDS_PINID='RFU0';
NODE_NAME     J102 144
 '@T6G_MB_LIB.T6G(SCH_1):PAGE103_I22@PURE_QUANTA.SCONN288_DDR506112002KQ(CHIPS)':
 'RFU1': CDS_PINID='RFU1';
NODE_NAME     J102 149
 '@T6G_MB_LIB.T6G(SCH_1):PAGE103_I22@PURE_QUANTA.SCONN288_DDR506112002KQ(CHIPS)':
 'RFU2': CDS_PINID='RFU2';
NODE_NAME     J102 150
 '@T6G_MB_LIB.T6G(SCH_1):PAGE103_I22@PURE_QUANTA.SCONN288_DDR506112002KQ(CHIPS)':
 'RFU3': CDS_PINID='RFU3';
NODE_NAME     J102 220
 '@T6G_MB_LIB.T6G(SCH_1):PAGE103_I22@PURE_QUANTA.SCONN288_DDR506112002KQ(CHIPS)':
 'RFU4': CDS_PINID='RFU4';
NODE_NAME     J102 231
 '@T6G_MB_LIB.T6G(SCH_1):PAGE103_I22@PURE_QUANTA.SCONN288_DDR506112002KQ(CHIPS)':
 'RFU5': CDS_PINID='RFU5';
NODE_NAME     J102 232
 '@T6G_MB_LIB.T6G(SCH_1):PAGE103_I22@PURE_QUANTA.SCONN288_DDR506112002KQ(CHIPS)':
 'RFU6': CDS_PINID='RFU6';
NODE_NAME     J27 2
 '@T6G_MB_LIB.T6G(SCH_1):PAGE104_I22@PURE_QUANTA.SCONN288_DDR506112002KQ(CHIPS)':
 'RFU0': CDS_PINID='RFU0';
NODE_NAME     J27 144
 '@T6G_MB_LIB.T6G(SCH_1):PAGE104_I22@PURE_QUANTA.SCONN288_DDR506112002KQ(CHIPS)':
 'RFU1': CDS_PINID='RFU1';
NODE_NAME     J27 149
 '@T6G_MB_LIB.T6G(SCH_1):PAGE104_I22@PURE_QUANTA.SCONN288_DDR506112002KQ(CHIPS)':
 'RFU2': CDS_PINID='RFU2';
NODE_NAME     J27 150
 '@T6G_MB_LIB.T6G(SCH_1):PAGE104_I22@PURE_QUANTA.SCONN288_DDR506112002KQ(CHIPS)':
 'RFU3': CDS_PINID='RFU3';
NODE_NAME     J27 220
 '@T6G_MB_LIB.T6G(SCH_1):PAGE104_I22@PURE_QUANTA.SCONN288_DDR506112002KQ(CHIPS)':
 'RFU4': CDS_PINID='RFU4';
NODE_NAME     J27 231
 '@T6G_MB_LIB.T6G(SCH_1):PAGE104_I22@PURE_QUANTA.SCONN288_DDR506112002KQ(CHIPS)':
 'RFU5': CDS_PINID='RFU5';
NODE_NAME     J27 232
 '@T6G_MB_LIB.T6G(SCH_1):PAGE104_I22@PURE_QUANTA.SCONN288_DDR506112002KQ(CHIPS)':
 'RFU6': CDS_PINID='RFU6';
NODE_NAME     J100 2
 '@T6G_MB_LIB.T6G(SCH_1):PAGE105_I22@PURE_QUANTA.SCONN288_DDR506112002KQ(CHIPS)':
 'RFU0': CDS_PINID='RFU0';
NODE_NAME     J100 144
 '@T6G_MB_LIB.T6G(SCH_1):PAGE105_I22@PURE_QUANTA.SCONN288_DDR506112002KQ(CHIPS)':
 'RFU1': CDS_PINID='RFU1';
NODE_NAME     J100 149
 '@T6G_MB_LIB.T6G(SCH_1):PAGE105_I22@PURE_QUANTA.SCONN288_DDR506112002KQ(CHIPS)':
 'RFU2': CDS_PINID='RFU2';
NODE_NAME     J100 150
 '@T6G_MB_LIB.T6G(SCH_1):PAGE105_I22@PURE_QUANTA.SCONN288_DDR506112002KQ(CHIPS)':
 'RFU3': CDS_PINID='RFU3';
NODE_NAME     J100 220
 '@T6G_MB_LIB.T6G(SCH_1):PAGE105_I22@PURE_QUANTA.SCONN288_DDR506112002KQ(CHIPS)':
 'RFU4': CDS_PINID='RFU4';
NODE_NAME     J100 231
 '@T6G_MB_LIB.T6G(SCH_1):PAGE105_I22@PURE_QUANTA.SCONN288_DDR506112002KQ(CHIPS)':
 'RFU5': CDS_PINID='RFU5';
NODE_NAME     J100 232
 '@T6G_MB_LIB.T6G(SCH_1):PAGE105_I22@PURE_QUANTA.SCONN288_DDR506112002KQ(CHIPS)':
 'RFU6': CDS_PINID='RFU6';
NODE_NAME     J29 2
 '@T6G_MB_LIB.T6G(SCH_1):PAGE106_I22@PURE_QUANTA.SCONN288_DDR506112002KQ(CHIPS)':
 'RFU0': CDS_PINID='RFU0';
NODE_NAME     J29 144
 '@T6G_MB_LIB.T6G(SCH_1):PAGE106_I22@PURE_QUANTA.SCONN288_DDR506112002KQ(CHIPS)':
 'RFU1': CDS_PINID='RFU1';
NODE_NAME     J29 149
 '@T6G_MB_LIB.T6G(SCH_1):PAGE106_I22@PURE_QUANTA.SCONN288_DDR506112002KQ(CHIPS)':
 'RFU2': CDS_PINID='RFU2';
NODE_NAME     J29 150
 '@T6G_MB_LIB.T6G(SCH_1):PAGE106_I22@PURE_QUANTA.SCONN288_DDR506112002KQ(CHIPS)':
 'RFU3': CDS_PINID='RFU3';
NODE_NAME     J29 220
 '@T6G_MB_LIB.T6G(SCH_1):PAGE106_I22@PURE_QUANTA.SCONN288_DDR506112002KQ(CHIPS)':
 'RFU4': CDS_PINID='RFU4';
NODE_NAME     J29 231
 '@T6G_MB_LIB.T6G(SCH_1):PAGE106_I22@PURE_QUANTA.SCONN288_DDR506112002KQ(CHIPS)':
 'RFU5': CDS_PINID='RFU5';
NODE_NAME     J29 232
 '@T6G_MB_LIB.T6G(SCH_1):PAGE106_I22@PURE_QUANTA.SCONN288_DDR506112002KQ(CHIPS)':
 'RFU6': CDS_PINID='RFU6';
NODE_NAME     J99 2
 '@T6G_MB_LIB.T6G(SCH_1):PAGE107_I22@PURE_QUANTA.SCONN288_DDR506112002KQ(CHIPS)':
 'RFU0': CDS_PINID='RFU0';
NODE_NAME     J99 144
 '@T6G_MB_LIB.T6G(SCH_1):PAGE107_I22@PURE_QUANTA.SCONN288_DDR506112002KQ(CHIPS)':
 'RFU1': CDS_PINID='RFU1';
NODE_NAME     J99 149
 '@T6G_MB_LIB.T6G(SCH_1):PAGE107_I22@PURE_QUANTA.SCONN288_DDR506112002KQ(CHIPS)':
 'RFU2': CDS_PINID='RFU2';
NODE_NAME     J99 150
 '@T6G_MB_LIB.T6G(SCH_1):PAGE107_I22@PURE_QUANTA.SCONN288_DDR506112002KQ(CHIPS)':
 'RFU3': CDS_PINID='RFU3';
NODE_NAME     J99 220
 '@T6G_MB_LIB.T6G(SCH_1):PAGE107_I22@PURE_QUANTA.SCONN288_DDR506112002KQ(CHIPS)':
 'RFU4': CDS_PINID='RFU4';
NODE_NAME     J99 231
 '@T6G_MB_LIB.T6G(SCH_1):PAGE107_I22@PURE_QUANTA.SCONN288_DDR506112002KQ(CHIPS)':
 'RFU5': CDS_PINID='RFU5';
NODE_NAME     J99 232
 '@T6G_MB_LIB.T6G(SCH_1):PAGE107_I22@PURE_QUANTA.SCONN288_DDR506112002KQ(CHIPS)':
 'RFU6': CDS_PINID='RFU6';
NODE_NAME     J37 2
 '@T6G_MB_LIB.T6G(SCH_1):PAGE108_I22@PURE_QUANTA.SCONN288_DDR506112002KQ(CHIPS)':
 'RFU0': CDS_PINID='RFU0';
NODE_NAME     J37 144
 '@T6G_MB_LIB.T6G(SCH_1):PAGE108_I22@PURE_QUANTA.SCONN288_DDR506112002KQ(CHIPS)':
 'RFU1': CDS_PINID='RFU1';
NODE_NAME     J37 149
 '@T6G_MB_LIB.T6G(SCH_1):PAGE108_I22@PURE_QUANTA.SCONN288_DDR506112002KQ(CHIPS)':
 'RFU2': CDS_PINID='RFU2';
NODE_NAME     J37 150
 '@T6G_MB_LIB.T6G(SCH_1):PAGE108_I22@PURE_QUANTA.SCONN288_DDR506112002KQ(CHIPS)':
 'RFU3': CDS_PINID='RFU3';
NODE_NAME     J37 220
 '@T6G_MB_LIB.T6G(SCH_1):PAGE108_I22@PURE_QUANTA.SCONN288_DDR506112002KQ(CHIPS)':
 'RFU4': CDS_PINID='RFU4';
NODE_NAME     J37 231
 '@T6G_MB_LIB.T6G(SCH_1):PAGE108_I22@PURE_QUANTA.SCONN288_DDR506112002KQ(CHIPS)':
 'RFU5': CDS_PINID='RFU5';
NODE_NAME     J37 232
 '@T6G_MB_LIB.T6G(SCH_1):PAGE108_I22@PURE_QUANTA.SCONN288_DDR506112002KQ(CHIPS)':
 'RFU6': CDS_PINID='RFU6';
NODE_NAME     U82 1
 '@T6G_MB_LIB.T6G(SCH_1):PAGE143_I26@PURE_QUANTA.SN74LVC1G07DBVR(CHIPS)':
 'NC': CDS_PINID='NC';
NODE_NAME     U86 1
 '@T6G_MB_LIB.T6G(SCH_1):PAGE143_I31@PURE_QUANTA.SN74LVC1G07DBVR(CHIPS)':
 'NC': CDS_PINID='NC';
NODE_NAME     U124 1
 '@T6G_MB_LIB.T6G(SCH_1):PAGE144_I38@PURE_QUANTA.SN74LVC1G07DBVR(CHIPS)':
 'NC': CDS_PINID='NC';
NODE_NAME     U99 1
 '@T6G_MB_LIB.T6G(SCH_1):PAGE148_I340@PURE_QUANTA.SN74LVC1G07DBVR(CHIPS)':
 'NC': CDS_PINID='NC';
NODE_NAME     J54 14
 '@T6G_MB_LIB.T6G(SCH_1):PAGE149_I142@PURE_QUANTA.SCONN20_HSU2101L00007H(CHIPS)':
 '14': CDS_PINID='\14\';
NODE_NAME     J54 20
 '@T6G_MB_LIB.T6G(SCH_1):PAGE149_I142@PURE_QUANTA.SCONN20_HSU2101L00007H(CHIPS)':
 '20': CDS_PINID='\20\';
NODE_NAME     J1 2
 '@T6G_MB_LIB.T6G(SCH_1):PAGE85_I536@PURE_QUANTA.SCONN288_DDR506112002KQ(CHIPS)':
 'RFU0': CDS_PINID='RFU0';
NODE_NAME     J1 144
 '@T6G_MB_LIB.T6G(SCH_1):PAGE85_I536@PURE_QUANTA.SCONN288_DDR506112002KQ(CHIPS)':
 'RFU1': CDS_PINID='RFU1';
NODE_NAME     J1 149
 '@T6G_MB_LIB.T6G(SCH_1):PAGE85_I536@PURE_QUANTA.SCONN288_DDR506112002KQ(CHIPS)':
 'RFU2': CDS_PINID='RFU2';
NODE_NAME     J1 150
 '@T6G_MB_LIB.T6G(SCH_1):PAGE85_I536@PURE_QUANTA.SCONN288_DDR506112002KQ(CHIPS)':
 'RFU3': CDS_PINID='RFU3';
NODE_NAME     J1 220
 '@T6G_MB_LIB.T6G(SCH_1):PAGE85_I536@PURE_QUANTA.SCONN288_DDR506112002KQ(CHIPS)':
 'RFU4': CDS_PINID='RFU4';
NODE_NAME     J1 231
 '@T6G_MB_LIB.T6G(SCH_1):PAGE85_I536@PURE_QUANTA.SCONN288_DDR506112002KQ(CHIPS)':
 'RFU5': CDS_PINID='RFU5';
NODE_NAME     J1 232
 '@T6G_MB_LIB.T6G(SCH_1):PAGE85_I536@PURE_QUANTA.SCONN288_DDR506112002KQ(CHIPS)':
 'RFU6': CDS_PINID='RFU6';
NODE_NAME     U192 5
 '@T6G_MB_LIB.T6G(SCH_1):PAGE363_I398@PURE_QUANTA.LTC4307CMS8(CHIPS)':
 'READY': CDS_PINID='READY';
NODE_NAME     U308 3
 '@T6G_MB_LIB.T6G(SCH_1):PAGE364_I37@PURE_QUANTA.74LVC2G07DW7(CHIPS)':
 '2A': CDS_PINID='\2a\';
NODE_NAME     U308 4
 '@T6G_MB_LIB.T6G(SCH_1):PAGE364_I37@PURE_QUANTA.74LVC2G07DW7(CHIPS)':
 '2Y': CDS_PINID='\2y\';
NODE_NAME     U200 5
 '@T6G_MB_LIB.T6G(SCH_1):PAGE249_I15@PURE_QUANTA.LTC4307CMS8(CHIPS)':
 'READY': CDS_PINID='READY';
NODE_NAME     U176 5
 '@T6G_MB_LIB.T6G(SCH_1):PAGE249_I30@PURE_QUANTA.LTC4307CMS8(CHIPS)':
 'READY': CDS_PINID='READY';
NODE_NAME     U194 5
 '@T6G_MB_LIB.T6G(SCH_1):PAGE249_I42@PURE_QUANTA.LTC4307CMS8(CHIPS)':
 'READY': CDS_PINID='READY';
NODE_NAME     U175 5
 '@T6G_MB_LIB.T6G(SCH_1):PAGE249_I49@PURE_QUANTA.LTC4307CMS8(CHIPS)':
 'READY': CDS_PINID='READY';
NODE_NAME     U39 20
 '@T6G_MB_LIB.T6G(SCH_1):PAGE251_I74@PURE_QUANTA.TCA9548APWR(CHIPS)':
 'SC7': CDS_PINID='SC7';
NODE_NAME     U39 19
 '@T6G_MB_LIB.T6G(SCH_1):PAGE251_I74@PURE_QUANTA.TCA9548APWR(CHIPS)':
 'SD7': CDS_PINID='SD7';
NODE_NAME     U36 20
 '@T6G_MB_LIB.T6G(SCH_1):PAGE252_I33@PURE_QUANTA.TCA9548APWR(CHIPS)':
 'SC7': CDS_PINID='SC7';
NODE_NAME     U36 19
 '@T6G_MB_LIB.T6G(SCH_1):PAGE252_I33@PURE_QUANTA.TCA9548APWR(CHIPS)':
 'SD7': CDS_PINID='SD7';
NODE_NAME     U26 E50
 '@T6G_MB_LIB.T6G(SCH_1):PAGE53_I145@PURE_QUANTA.GENOA_SP5(CHIPS)':
 'WAFL_RXN0||P5_RXN0': CDS_PINID='\wafl_rxn0||p5_rxn0\';
NODE_NAME     U26 E49
 '@T6G_MB_LIB.T6G(SCH_1):PAGE53_I145@PURE_QUANTA.GENOA_SP5(CHIPS)':
 'WAFL_RXP0||P5_RXP0': CDS_PINID='\wafl_rxp0||p5_rxp0\';
NODE_NAME     U26 C51
 '@T6G_MB_LIB.T6G(SCH_1):PAGE53_I145@PURE_QUANTA.GENOA_SP5(CHIPS)':
 'WAFL_TXN0||P5_TXN0': CDS_PINID='\wafl_txn0||p5_txn0\';
NODE_NAME     U26 C50
 '@T6G_MB_LIB.T6G(SCH_1):PAGE53_I145@PURE_QUANTA.GENOA_SP5(CHIPS)':
 'WAFL_TXP0||P5_TXP0': CDS_PINID='\wafl_txp0||p5_txp0\';
NODE_NAME     U44 1
 '@T6G_MB_LIB.T6G(SCH_1):PAGE297_I97@PURE_QUANTA.74LVC1G17GW(CHIPS)':
 'NC': CDS_PINID='NC';
NODE_NAME     U92 1
 '@T6G_MB_LIB.T6G(SCH_1):PAGE83_I26@PURE_QUANTA.SN74LVC1G07DBVR(CHIPS)':
 'NC': CDS_PINID='NC';
NODE_NAME     J57 4
 '@T6G_MB_LIB.T6G(SCH_1):PAGE84_I41@PURE_QUANTA.CONN8_HBB1081L200D8H(CHIPS)':
 '4': CDS_PINID='\4\';
NODE_NAME     J57 5
 '@T6G_MB_LIB.T6G(SCH_1):PAGE84_I41@PURE_QUANTA.CONN8_HBB1081L200D8H(CHIPS)':
 '5': CDS_PINID='\5\';
NODE_NAME     U18 U12
 '@T6G_MB_LIB.T6G(SCH_1):PAGE80_I216@PURE_QUANTA.LCMXO3LF9400C5BG484C(CHIPS)':
 'PB27C': CDS_PINID='PB27C';
NODE_NAME     J6 5
 '@T6G_MB_LIB.T6G(SCH_1):PAGE28_I28@PURE_QUANTA.CONN6_HBC1031L200D8H(CHIPS)':
 '5': CDS_PINID='\5\';
NODE_NAME     U25 DG11
 '@T6G_MB_LIB.T6G(SCH_1):PAGE28_I188@PURE_QUANTA.GENOA_SP5(CHIPS)':
 'AGPIO87': CDS_PINID='AGPIO87';
NODE_NAME     U25 B16
 '@T6G_MB_LIB.T6G(SCH_1):PAGE28_I188@PURE_QUANTA.GENOA_SP5(CHIPS)':
 'AGPIO259||SGPIO3_CLK': CDS_PINID='\agpio259||sgpio3_clk\';
NODE_NAME     U25 DJ47
 '@T6G_MB_LIB.T6G(SCH_1):PAGE28_I188@PURE_QUANTA.GENOA_SP5(CHIPS)':
 'GPP_CLK14N': CDS_PINID='GPP_CLK14N';
NODE_NAME     U25 DJ48
 '@T6G_MB_LIB.T6G(SCH_1):PAGE28_I188@PURE_QUANTA.GENOA_SP5(CHIPS)':
 'GPP_CLK14P': CDS_PINID='GPP_CLK14P';
NODE_NAME     U25 DJ50
 '@T6G_MB_LIB.T6G(SCH_1):PAGE28_I188@PURE_QUANTA.GENOA_SP5(CHIPS)':
 'GPP_CLK15N': CDS_PINID='GPP_CLK15N';
NODE_NAME     U25 DJ51
 '@T6G_MB_LIB.T6G(SCH_1):PAGE28_I188@PURE_QUANTA.GENOA_SP5(CHIPS)':
 'GPP_CLK15P': CDS_PINID='GPP_CLK15P';
NODE_NAME     U25 D15
 '@T6G_MB_LIB.T6G(SCH_1):PAGE28_I188@PURE_QUANTA.GENOA_SP5(CHIPS)':
 'SGPIO_DATAOUT||AGPIO260': CDS_PINID='\sgpio_dataout||agpio260\';
NODE_NAME     U25 B15
 '@T6G_MB_LIB.T6G(SCH_1):PAGE28_I188@PURE_QUANTA.GENOA_SP5(CHIPS)':
 'SGPIO_LOAD||AGPIO261': CDS_PINID='\sgpio_load||agpio261\';
NODE_NAME     H27 1
 '@T6G_MB_LIB.T6G(SCH_1):PAGE212_I41@PURE_QUANTA.HOLE(CHIPS)':
 '1': CDS_PINID='\1\';
NODE_NAME     H28 1
 '@T6G_MB_LIB.T6G(SCH_1):PAGE212_I50@PURE_QUANTA.HOLE(CHIPS)':
 '1': CDS_PINID='\1\';
NODE_NAME     H29 1
 '@T6G_MB_LIB.T6G(SCH_1):PAGE212_I51@PURE_QUANTA.HOLE(CHIPS)':
 '1': CDS_PINID='\1\';
NODE_NAME     H30 1
 '@T6G_MB_LIB.T6G(SCH_1):PAGE212_I56@PURE_QUANTA.HOLE(CHIPS)':
 '1': CDS_PINID='\1\';
NODE_NAME     H124 1
 '@T6G_MB_LIB.T6G(SCH_1):PAGE212_I84@PURE_QUANTA.HOLE(CHIPS)':
 '1': CDS_PINID='\1\';
NODE_NAME     H125 1
 '@T6G_MB_LIB.T6G(SCH_1):PAGE212_I85@PURE_QUANTA.HOLE(CHIPS)':
 '1': CDS_PINID='\1\';
NODE_NAME     H74 1
 '@T6G_MB_LIB.T6G(SCH_1):PAGE212_I88@PURE_QUANTA.HOLE(CHIPS)':
 '1': CDS_PINID='\1\';
NODE_NAME     H75 1
 '@T6G_MB_LIB.T6G(SCH_1):PAGE212_I89@PURE_QUANTA.HOLE(CHIPS)':
 '1': CDS_PINID='\1\';
NODE_NAME     H127 1
 '@T6G_MB_LIB.T6G(SCH_1):PAGE212_I94@PURE_QUANTA.HOLE(CHIPS)':
 '1': CDS_PINID='\1\';
NODE_NAME     J122 SCR_H1
 '@T6G_MB_LIB.T6G(SCH_1):PAGE212_I101@PURE_QUANTA.CONN1_10165288101LF(CHIPS)':
 'NC1': CDS_PINID='NC1';
NODE_NAME     J123 SCR_H1
 '@T6G_MB_LIB.T6G(SCH_1):PAGE212_I106@PURE_QUANTA.CONN1_10165288101LF(CHIPS)':
 'NC1': CDS_PINID='NC1';
NODE_NAME     H126 1
 '@T6G_MB_LIB.T6G(SCH_1):PAGE212_I111@PURE_QUANTA.HOLE(CHIPS)':
 '1': CDS_PINID='\1\';
NODE_NAME     U75 1
 '@T6G_MB_LIB.T6G(SCH_1):PAGE337_I64@PURE_QUANTA.74LVC1G17GW(CHIPS)':
 'NC': CDS_PINID='NC';
NODE_NAME     U207 1
 '@T6G_MB_LIB.T6G(SCH_1):PAGE342_I58@PURE_QUANTA.74LVC1G17GW(CHIPS)':
 'NC': CDS_PINID='NC';
NODE_NAME     JP4003 1
 '@T6G_MB_LIB.T6G(SCH_1):PAGE372_I18@PURE_QUANTA.CONN3_210HP1030BR1(CHIPS)':
 '1': CDS_PINID='\1\';
NODE_NAME     U6001 63
 '@T6G_MB_LIB.T6G(SCH_1):PAGE153_I1@PURE_QUANTA.CYUSB330468LTXI(CHIPS)':
 'DS2_DM': CDS_PINID='DS2_DM';
NODE_NAME     U6001 62
 '@T6G_MB_LIB.T6G(SCH_1):PAGE153_I1@PURE_QUANTA.CYUSB330468LTXI(CHIPS)':
 'DS2_DP': CDS_PINID='DS2_DP';
NODE_NAME     U6001 44
 '@T6G_MB_LIB.T6G(SCH_1):PAGE153_I1@PURE_QUANTA.CYUSB330468LTXI(CHIPS)':
 'DS2_RXM': CDS_PINID='DS2_RXM';
NODE_NAME     U6001 45
 '@T6G_MB_LIB.T6G(SCH_1):PAGE153_I1@PURE_QUANTA.CYUSB330468LTXI(CHIPS)':
 'DS2_RXP': CDS_PINID='DS2_RXP';
NODE_NAME     U6001 42
 '@T6G_MB_LIB.T6G(SCH_1):PAGE153_I1@PURE_QUANTA.CYUSB330468LTXI(CHIPS)':
 'DS2_TXM': CDS_PINID='DS2_TXM';
NODE_NAME     U6001 41
 '@T6G_MB_LIB.T6G(SCH_1):PAGE153_I1@PURE_QUANTA.CYUSB330468LTXI(CHIPS)':
 'DS2_TXP': CDS_PINID='DS2_TXP';
NODE_NAME     U6001 64
 '@T6G_MB_LIB.T6G(SCH_1):PAGE153_I1@PURE_QUANTA.CYUSB330468LTXI(CHIPS)':
 'DS3_DM': CDS_PINID='DS3_DM';
NODE_NAME     U6001 65
 '@T6G_MB_LIB.T6G(SCH_1):PAGE153_I1@PURE_QUANTA.CYUSB330468LTXI(CHIPS)':
 'DS3_DP': CDS_PINID='DS3_DP';
NODE_NAME     U6001 36
 '@T6G_MB_LIB.T6G(SCH_1):PAGE153_I1@PURE_QUANTA.CYUSB330468LTXI(CHIPS)':
 'DS3_RXM': CDS_PINID='DS3_RXM';
NODE_NAME     U6001 35
 '@T6G_MB_LIB.T6G(SCH_1):PAGE153_I1@PURE_QUANTA.CYUSB330468LTXI(CHIPS)':
 'DS3_RXP': CDS_PINID='DS3_RXP';
NODE_NAME     U6001 39
 '@T6G_MB_LIB.T6G(SCH_1):PAGE153_I1@PURE_QUANTA.CYUSB330468LTXI(CHIPS)':
 'DS3_TXM': CDS_PINID='DS3_TXM';
NODE_NAME     U6001 38
 '@T6G_MB_LIB.T6G(SCH_1):PAGE153_I1@PURE_QUANTA.CYUSB330468LTXI(CHIPS)':
 'DS3_TXP': CDS_PINID='DS3_TXP';
NODE_NAME     U6001 68
 '@T6G_MB_LIB.T6G(SCH_1):PAGE153_I1@PURE_QUANTA.CYUSB330468LTXI(CHIPS)':
 'DS4_DM': CDS_PINID='DS4_DM';
NODE_NAME     U6001 67
 '@T6G_MB_LIB.T6G(SCH_1):PAGE153_I1@PURE_QUANTA.CYUSB330468LTXI(CHIPS)':
 'DS4_DP': CDS_PINID='DS4_DP';
NODE_NAME     U6001 14
 '@T6G_MB_LIB.T6G(SCH_1):PAGE153_I1@PURE_QUANTA.CYUSB330468LTXI(CHIPS)':
 'DS4_RXM': CDS_PINID='DS4_RXM';
NODE_NAME     U6001 15
 '@T6G_MB_LIB.T6G(SCH_1):PAGE153_I1@PURE_QUANTA.CYUSB330468LTXI(CHIPS)':
 'DS4_RXP': CDS_PINID='DS4_RXP';
NODE_NAME     U6001 12
 '@T6G_MB_LIB.T6G(SCH_1):PAGE153_I1@PURE_QUANTA.CYUSB330468LTXI(CHIPS)':
 'DS4_TXM': CDS_PINID='DS4_TXM';
NODE_NAME     U6001 11
 '@T6G_MB_LIB.T6G(SCH_1):PAGE153_I1@PURE_QUANTA.CYUSB330468LTXI(CHIPS)':
 'DS4_TXP': CDS_PINID='DS4_TXP';
NODE_NAME     U6001 25
 '@T6G_MB_LIB.T6G(SCH_1):PAGE153_I1@PURE_QUANTA.CYUSB330468LTXI(CHIPS)':
 'NC_25': CDS_PINID='NC_25';
NODE_NAME     J212 9
 '@T6G_MB_LIB.T6G(SCH_1):PAGE27_I423@PURE_QUANTA.CONN10_HBC1051L300D8H(CHIPS)':
 '9': CDS_PINID='\9\';
NODE_NAME     J212 10
 '@T6G_MB_LIB.T6G(SCH_1):PAGE27_I423@PURE_QUANTA.CONN10_HBC1051L300D8H(CHIPS)':
 '10': CDS_PINID='\10\';
NODE_NAME     U6002 36
 '@T6G_MB_LIB.T6G(SCH_1):PAGE155_I101@PURE_QUANTA.TUSB8042AIRGCR(CHIPS)':
 'PWRCTL1||BATEN1': CDS_PINID='\pwrctl1||baten1\';
NODE_NAME     U6002 32
 '@T6G_MB_LIB.T6G(SCH_1):PAGE155_I101@PURE_QUANTA.TUSB8042AIRGCR(CHIPS)':
 'PWRCTL4||BATEN4': CDS_PINID='\pwrctl4||baten4\';
NODE_NAME     U6002 2
 '@T6G_MB_LIB.T6G(SCH_1):PAGE155_I101@PURE_QUANTA.TUSB8042AIRGCR(CHIPS)':
 'USB_DM_DN1': CDS_PINID='USB_DM_DN1';
NODE_NAME     U6002 25
 '@T6G_MB_LIB.T6G(SCH_1):PAGE155_I101@PURE_QUANTA.TUSB8042AIRGCR(CHIPS)':
 'USB_DM_DN4': CDS_PINID='USB_DM_DN4';
NODE_NAME     U6002 24
 '@T6G_MB_LIB.T6G(SCH_1):PAGE155_I101@PURE_QUANTA.TUSB8042AIRGCR(CHIPS)':
 'USB_DP_DN4': CDS_PINID='USB_DP_DN4';
NODE_NAME     U6002 7
 '@T6G_MB_LIB.T6G(SCH_1):PAGE155_I101@PURE_QUANTA.TUSB8042AIRGCR(CHIPS)':
 'USB_SSRXM_DN1': CDS_PINID='USB_SSRXM_DN1';
NODE_NAME     U6002 22
 '@T6G_MB_LIB.T6G(SCH_1):PAGE155_I101@PURE_QUANTA.TUSB8042AIRGCR(CHIPS)':
 'USB_SSRXP_DN3': CDS_PINID='USB_SSRXP_DN3';
NODE_NAME     U6002 29
 '@T6G_MB_LIB.T6G(SCH_1):PAGE155_I101@PURE_QUANTA.TUSB8042AIRGCR(CHIPS)':
 'USB_SSRXP_DN4': CDS_PINID='USB_SSRXP_DN4';
NODE_NAME     U6002 4
 '@T6G_MB_LIB.T6G(SCH_1):PAGE155_I101@PURE_QUANTA.TUSB8042AIRGCR(CHIPS)':
 'USB_SSTXM_DN1': CDS_PINID='USB_SSTXM_DN1';
NODE_NAME     U6002 20
 '@T6G_MB_LIB.T6G(SCH_1):PAGE155_I101@PURE_QUANTA.TUSB8042AIRGCR(CHIPS)':
 'USB_SSTXM_DN3': CDS_PINID='USB_SSTXM_DN3';
NODE_NAME     U6002 27
 '@T6G_MB_LIB.T6G(SCH_1):PAGE155_I101@PURE_QUANTA.TUSB8042AIRGCR(CHIPS)':
 'USB_SSTXM_DN4': CDS_PINID='USB_SSTXM_DN4';
NODE_NAME     U6002 3
 '@T6G_MB_LIB.T6G(SCH_1):PAGE155_I101@PURE_QUANTA.TUSB8042AIRGCR(CHIPS)':
 'USB_SSTXP_DN1': CDS_PINID='USB_SSTXP_DN1';
NODE_NAME     U6002 19
 '@T6G_MB_LIB.T6G(SCH_1):PAGE155_I101@PURE_QUANTA.TUSB8042AIRGCR(CHIPS)':
 'USB_SSTXP_DN3': CDS_PINID='USB_SSTXP_DN3';
NODE_NAME     U6002 26
 '@T6G_MB_LIB.T6G(SCH_1):PAGE155_I101@PURE_QUANTA.TUSB8042AIRGCR(CHIPS)':
 'USB_SSTXP_DN4': CDS_PINID='USB_SSTXP_DN4';
NODE_NAME     H90 1
 '@T6G_MB_LIB.T6G(SCH_1):PAGE212_I167@PURE_QUANTA.HOLE(CHIPS)':
 '1': CDS_PINID='\1\';
NODE_NAME     U8005 3
 '@T6G_MB_LIB.T6G(SCH_1):PAGE371_I101@PURE_QUANTA.LM4040AIM3X25NOPB(CHIPS)':
 '3': CDS_PINID='\3\';
NODE_NAME     U8007 3
 '@T6G_MB_LIB.T6G(SCH_1):PAGE372_I51@PURE_QUANTA.LM4040AIM3X25NOPB(CHIPS)':
 '3': CDS_PINID='\3\';
NODE_NAME     U8009 3
 '@T6G_MB_LIB.T6G(SCH_1):PAGE372_I93@PURE_QUANTA.LM4040AIM3X25NOPB(CHIPS)':
 '3': CDS_PINID='\3\';
NODE_NAME     U6014 FJ6
 '@T6G_MB_LIB.T6G(SCH_1):PAGE401_I1@PURE_QUANTA.PT5161LRS(CHIPS)':
 'GPIO0': CDS_PINID='GPIO0';
NODE_NAME     U6014 FJ23
 '@T6G_MB_LIB.T6G(SCH_1):PAGE401_I1@PURE_QUANTA.PT5161LRS(CHIPS)':
 'GPIO1': CDS_PINID='GPIO1';
NODE_NAME     U6014 FJ31
 '@T6G_MB_LIB.T6G(SCH_1):PAGE401_I1@PURE_QUANTA.PT5161LRS(CHIPS)':
 'INT_N': CDS_PINID='INT_N';
NODE_NAME     U6014 E18
 '@T6G_MB_LIB.T6G(SCH_1):PAGE401_I1@PURE_QUANTA.PT5161LRS(CHIPS)':
 'REFCLK_OUTN': CDS_PINID='REFCLK_OUTN';
NODE_NAME     U6014 B16
 '@T6G_MB_LIB.T6G(SCH_1):PAGE401_I1@PURE_QUANTA.PT5161LRS(CHIPS)':
 'REFCLK_OUTP': CDS_PINID='REFCLK_OUTP';
NODE_NAME     U11 1
 '@T6G_MB_LIB.T6G(SCH_1):PAGE387_I3@PURE_QUANTA.M24M02DRMN6TP(CHIPS)':
 'DU1': CDS_PINID='DU1';
NODE_NAME     U11 2
 '@T6G_MB_LIB.T6G(SCH_1):PAGE387_I3@PURE_QUANTA.M24M02DRMN6TP(CHIPS)':
 'DU2': CDS_PINID='DU2';
NODE_NAME     U15 1
 '@T6G_MB_LIB.T6G(SCH_1):PAGE410_I5@PURE_QUANTA.M24M02DRMN6TP(CHIPS)':
 'DU1': CDS_PINID='DU1';
NODE_NAME     U15 2
 '@T6G_MB_LIB.T6G(SCH_1):PAGE410_I5@PURE_QUANTA.M24M02DRMN6TP(CHIPS)':
 'DU2': CDS_PINID='DU2';
NODE_NAME     U16 1
 '@T6G_MB_LIB.T6G(SCH_1):PAGE421_I5@PURE_QUANTA.M24M02DRMN6TP(CHIPS)':
 'DU1': CDS_PINID='DU1';
NODE_NAME     U16 2
 '@T6G_MB_LIB.T6G(SCH_1):PAGE421_I5@PURE_QUANTA.M24M02DRMN6TP(CHIPS)':
 'DU2': CDS_PINID='DU2';
NODE_NAME     U17 1
 '@T6G_MB_LIB.T6G(SCH_1):PAGE432_I5@PURE_QUANTA.M24M02DRMN6TP(CHIPS)':
 'DU1': CDS_PINID='DU1';
NODE_NAME     U17 2
 '@T6G_MB_LIB.T6G(SCH_1):PAGE432_I5@PURE_QUANTA.M24M02DRMN6TP(CHIPS)':
 'DU2': CDS_PINID='DU2';
NODE_NAME     U12 1
 '@T6G_MB_LIB.T6G(SCH_1):PAGE399_I5@PURE_QUANTA.M24M02DRMN6TP(CHIPS)':
 'DU1': CDS_PINID='DU1';
NODE_NAME     U12 2
 '@T6G_MB_LIB.T6G(SCH_1):PAGE399_I5@PURE_QUANTA.M24M02DRMN6TP(CHIPS)':
 'DU2': CDS_PINID='DU2';
NODE_NAME     U19 1
 '@T6G_MB_LIB.T6G(SCH_1):PAGE442_I5@PURE_QUANTA.M24M02DRMN6TP(CHIPS)':
 'DU1': CDS_PINID='DU1';
NODE_NAME     U19 2
 '@T6G_MB_LIB.T6G(SCH_1):PAGE442_I5@PURE_QUANTA.M24M02DRMN6TP(CHIPS)':
 'DU2': CDS_PINID='DU2';
NODE_NAME     U20 1
 '@T6G_MB_LIB.T6G(SCH_1):PAGE453_I5@PURE_QUANTA.M24M02DRMN6TP(CHIPS)':
 'DU1': CDS_PINID='DU1';
NODE_NAME     U20 2
 '@T6G_MB_LIB.T6G(SCH_1):PAGE453_I5@PURE_QUANTA.M24M02DRMN6TP(CHIPS)':
 'DU2': CDS_PINID='DU2';
NODE_NAME     U21 1
 '@T6G_MB_LIB.T6G(SCH_1):PAGE464_I5@PURE_QUANTA.M24M02DRMN6TP(CHIPS)':
 'DU1': CDS_PINID='DU1';
NODE_NAME     U21 2
 '@T6G_MB_LIB.T6G(SCH_1):PAGE464_I5@PURE_QUANTA.M24M02DRMN6TP(CHIPS)':
 'DU2': CDS_PINID='DU2';
NODE_NAME     U6015 FJ6
 '@T6G_MB_LIB.T6G(SCH_1):PAGE392_I47@PURE_QUANTA.PT5161LRS(CHIPS)':
 'GPIO0': CDS_PINID='GPIO0';
NODE_NAME     U6015 FJ23
 '@T6G_MB_LIB.T6G(SCH_1):PAGE392_I47@PURE_QUANTA.PT5161LRS(CHIPS)':
 'GPIO1': CDS_PINID='GPIO1';
NODE_NAME     U6015 FJ31
 '@T6G_MB_LIB.T6G(SCH_1):PAGE392_I47@PURE_QUANTA.PT5161LRS(CHIPS)':
 'INT_N': CDS_PINID='INT_N';
NODE_NAME     U6015 E18
 '@T6G_MB_LIB.T6G(SCH_1):PAGE392_I47@PURE_QUANTA.PT5161LRS(CHIPS)':
 'REFCLK_OUTN': CDS_PINID='REFCLK_OUTN';
NODE_NAME     U6015 B16
 '@T6G_MB_LIB.T6G(SCH_1):PAGE392_I47@PURE_QUANTA.PT5161LRS(CHIPS)':
 'REFCLK_OUTP': CDS_PINID='REFCLK_OUTP';
NODE_NAME     U6016 FJ6
 '@T6G_MB_LIB.T6G(SCH_1):PAGE451_I97@PURE_QUANTA.PT5161LRS(CHIPS)':
 'GPIO0': CDS_PINID='GPIO0';
NODE_NAME     U6016 FJ23
 '@T6G_MB_LIB.T6G(SCH_1):PAGE451_I97@PURE_QUANTA.PT5161LRS(CHIPS)':
 'GPIO1': CDS_PINID='GPIO1';
NODE_NAME     U6016 FJ31
 '@T6G_MB_LIB.T6G(SCH_1):PAGE451_I97@PURE_QUANTA.PT5161LRS(CHIPS)':
 'INT_N': CDS_PINID='INT_N';
NODE_NAME     U6016 E18
 '@T6G_MB_LIB.T6G(SCH_1):PAGE451_I97@PURE_QUANTA.PT5161LRS(CHIPS)':
 'REFCLK_OUTN': CDS_PINID='REFCLK_OUTN';
NODE_NAME     U6016 B16
 '@T6G_MB_LIB.T6G(SCH_1):PAGE451_I97@PURE_QUANTA.PT5161LRS(CHIPS)':
 'REFCLK_OUTP': CDS_PINID='REFCLK_OUTP';
NODE_NAME     U6017 FJ6
 '@T6G_MB_LIB.T6G(SCH_1):PAGE462_I97@PURE_QUANTA.PT5161LRS(CHIPS)':
 'GPIO0': CDS_PINID='GPIO0';
NODE_NAME     U6017 FJ23
 '@T6G_MB_LIB.T6G(SCH_1):PAGE462_I97@PURE_QUANTA.PT5161LRS(CHIPS)':
 'GPIO1': CDS_PINID='GPIO1';
NODE_NAME     U6017 FJ31
 '@T6G_MB_LIB.T6G(SCH_1):PAGE462_I97@PURE_QUANTA.PT5161LRS(CHIPS)':
 'INT_N': CDS_PINID='INT_N';
NODE_NAME     U6017 E18
 '@T6G_MB_LIB.T6G(SCH_1):PAGE462_I97@PURE_QUANTA.PT5161LRS(CHIPS)':
 'REFCLK_OUTN': CDS_PINID='REFCLK_OUTN';
NODE_NAME     U6017 B16
 '@T6G_MB_LIB.T6G(SCH_1):PAGE462_I97@PURE_QUANTA.PT5161LRS(CHIPS)':
 'REFCLK_OUTP': CDS_PINID='REFCLK_OUTP';
NODE_NAME     U6010 FJ6
 '@T6G_MB_LIB.T6G(SCH_1):PAGE385_I53@PURE_QUANTA.PT5161LRS(CHIPS)':
 'GPIO0': CDS_PINID='GPIO0';
NODE_NAME     U6010 FJ23
 '@T6G_MB_LIB.T6G(SCH_1):PAGE385_I53@PURE_QUANTA.PT5161LRS(CHIPS)':
 'GPIO1': CDS_PINID='GPIO1';
NODE_NAME     U6010 FJ31
 '@T6G_MB_LIB.T6G(SCH_1):PAGE385_I53@PURE_QUANTA.PT5161LRS(CHIPS)':
 'INT_N': CDS_PINID='INT_N';
NODE_NAME     U6010 E18
 '@T6G_MB_LIB.T6G(SCH_1):PAGE385_I53@PURE_QUANTA.PT5161LRS(CHIPS)':
 'REFCLK_OUTN': CDS_PINID='REFCLK_OUTN';
NODE_NAME     U6010 B16
 '@T6G_MB_LIB.T6G(SCH_1):PAGE385_I53@PURE_QUANTA.PT5161LRS(CHIPS)':
 'REFCLK_OUTP': CDS_PINID='REFCLK_OUTP';
NODE_NAME     U6011 FJ6
 '@T6G_MB_LIB.T6G(SCH_1):PAGE408_I83@PURE_QUANTA.PT5161LRS(CHIPS)':
 'GPIO0': CDS_PINID='GPIO0';
NODE_NAME     U6011 FJ23
 '@T6G_MB_LIB.T6G(SCH_1):PAGE408_I83@PURE_QUANTA.PT5161LRS(CHIPS)':
 'GPIO1': CDS_PINID='GPIO1';
NODE_NAME     U6011 FJ31
 '@T6G_MB_LIB.T6G(SCH_1):PAGE408_I83@PURE_QUANTA.PT5161LRS(CHIPS)':
 'INT_N': CDS_PINID='INT_N';
NODE_NAME     U6011 E18
 '@T6G_MB_LIB.T6G(SCH_1):PAGE408_I83@PURE_QUANTA.PT5161LRS(CHIPS)':
 'REFCLK_OUTN': CDS_PINID='REFCLK_OUTN';
NODE_NAME     U6011 B16
 '@T6G_MB_LIB.T6G(SCH_1):PAGE408_I83@PURE_QUANTA.PT5161LRS(CHIPS)':
 'REFCLK_OUTP': CDS_PINID='REFCLK_OUTP';
NODE_NAME     U6012 FJ6
 '@T6G_MB_LIB.T6G(SCH_1):PAGE419_I83@PURE_QUANTA.PT5161LRS(CHIPS)':
 'GPIO0': CDS_PINID='GPIO0';
NODE_NAME     U6012 FJ23
 '@T6G_MB_LIB.T6G(SCH_1):PAGE419_I83@PURE_QUANTA.PT5161LRS(CHIPS)':
 'GPIO1': CDS_PINID='GPIO1';
NODE_NAME     U6012 FJ31
 '@T6G_MB_LIB.T6G(SCH_1):PAGE419_I83@PURE_QUANTA.PT5161LRS(CHIPS)':
 'INT_N': CDS_PINID='INT_N';
NODE_NAME     U6012 E18
 '@T6G_MB_LIB.T6G(SCH_1):PAGE419_I83@PURE_QUANTA.PT5161LRS(CHIPS)':
 'REFCLK_OUTN': CDS_PINID='REFCLK_OUTN';
NODE_NAME     U6012 B16
 '@T6G_MB_LIB.T6G(SCH_1):PAGE419_I83@PURE_QUANTA.PT5161LRS(CHIPS)':
 'REFCLK_OUTP': CDS_PINID='REFCLK_OUTP';
NODE_NAME     U6013 FJ6
 '@T6G_MB_LIB.T6G(SCH_1):PAGE430_I83@PURE_QUANTA.PT5161LRS(CHIPS)':
 'GPIO0': CDS_PINID='GPIO0';
NODE_NAME     U6013 FJ23
 '@T6G_MB_LIB.T6G(SCH_1):PAGE430_I83@PURE_QUANTA.PT5161LRS(CHIPS)':
 'GPIO1': CDS_PINID='GPIO1';
NODE_NAME     U6013 FJ31
 '@T6G_MB_LIB.T6G(SCH_1):PAGE430_I83@PURE_QUANTA.PT5161LRS(CHIPS)':
 'INT_N': CDS_PINID='INT_N';
NODE_NAME     U6013 E18
 '@T6G_MB_LIB.T6G(SCH_1):PAGE430_I83@PURE_QUANTA.PT5161LRS(CHIPS)':
 'REFCLK_OUTN': CDS_PINID='REFCLK_OUTN';
NODE_NAME     U6013 B16
 '@T6G_MB_LIB.T6G(SCH_1):PAGE430_I83@PURE_QUANTA.PT5161LRS(CHIPS)':
 'REFCLK_OUTP': CDS_PINID='REFCLK_OUTP';
NODE_NAME     U28 1
 '@T6G_MB_LIB.T6G(SCH_1):PAGE340_I51@PURE_QUANTA.SN74LVC1G07DBVR(CHIPS)':
 'NC': CDS_PINID='NC';
NODE_NAME     U30 1
 '@T6G_MB_LIB.T6G(SCH_1):PAGE340_I66@PURE_QUANTA.SN74LVC1G07DBVR(CHIPS)':
 'NC': CDS_PINID='NC';
NODE_NAME     U34 1
 '@T6G_MB_LIB.T6G(SCH_1):PAGE257_I45@PURE_QUANTA.SN74LVC1G07DBVR(CHIPS)':
 'NC': CDS_PINID='NC';
NODE_NAME     U33 1
 '@T6G_MB_LIB.T6G(SCH_1):PAGE257_I64@PURE_QUANTA.SN74LVC1G07DBVR(CHIPS)':
 'NC': CDS_PINID='NC';
NODE_NAME     U57 2
 '@T6G_MB_LIB.T6G(SCH_1):PAGE146_I5@PURE_QUANTA.SCHOTTKY_DUAL_12A_3C(CHIPS)':
 'A': CDS_PINID='A';
NODE_NAME     U60 2
 '@T6G_MB_LIB.T6G(SCH_1):PAGE146_I25@PURE_QUANTA.SCHOTTKY_DUAL_12A_3C(CHIPS)':
 'A': CDS_PINID='A';
NET_NAME
'NCF_A1_CPU0_P0_GND'
 '@T6G_MB_LIB.T6G(SCH_1):NCF_A1_CPU0_P0_GND':
 C_SIGNAL='@t6g_mb_lib.t6g(sch_1):ncf_a1_cpu0_p0_gnd';
NODE_NAME     R6820 1
 '@T6G_MB_LIB.T6G(SCH_1):PAGE386_I15@PURE_QUANTA.Q_RES(CHIPS)':
 'A': CDS_PINID='A';
NODE_NAME     U6010 A1
 '@T6G_MB_LIB.T6G(SCH_1):PAGE386_I17@PURE_QUANTA.PT5161LRS(CHIPS)':
 'NCF_GND1': CDS_PINID='NCF_GND1';
NET_NAME
'NCF_A1_CPU0_P1_GND'
 '@T6G_MB_LIB.T6G(SCH_1):NCF_A1_CPU0_P1_GND':
 C_SIGNAL='@t6g_mb_lib.t6g(sch_1):ncf_a1_cpu0_p1_gnd';
NODE_NAME     R1043 1
 '@T6G_MB_LIB.T6G(SCH_1):PAGE409_I15@PURE_QUANTA.Q_RES(CHIPS)':
 'A': CDS_PINID='A';
NODE_NAME     U6011 A1
 '@T6G_MB_LIB.T6G(SCH_1):PAGE409_I17@PURE_QUANTA.PT5161LRS(CHIPS)':
 'NCF_GND1': CDS_PINID='NCF_GND1';
NET_NAME
'NCF_A1_CPU0_P2_GND'
 '@T6G_MB_LIB.T6G(SCH_1):NCF_A1_CPU0_P2_GND':
 C_SIGNAL='@t6g_mb_lib.t6g(sch_1):ncf_a1_cpu0_p2_gnd';
NODE_NAME     R1084 1
 '@T6G_MB_LIB.T6G(SCH_1):PAGE420_I14@PURE_QUANTA.Q_RES(CHIPS)':
 'A': CDS_PINID='A';
NODE_NAME     U6012 A1
 '@T6G_MB_LIB.T6G(SCH_1):PAGE420_I17@PURE_QUANTA.PT5161LRS(CHIPS)':
 'NCF_GND1': CDS_PINID='NCF_GND1';
NET_NAME
'NCF_A1_CPU0_P3_GND'
 '@T6G_MB_LIB.T6G(SCH_1):NCF_A1_CPU0_P3_GND':
 C_SIGNAL='@t6g_mb_lib.t6g(sch_1):ncf_a1_cpu0_p3_gnd';
NODE_NAME     R1126 1
 '@T6G_MB_LIB.T6G(SCH_1):PAGE431_I14@PURE_QUANTA.Q_RES(CHIPS)':
 'A': CDS_PINID='A';
NODE_NAME     U6013 A1
 '@T6G_MB_LIB.T6G(SCH_1):PAGE431_I17@PURE_QUANTA.PT5161LRS(CHIPS)':
 'NCF_GND1': CDS_PINID='NCF_GND1';
NET_NAME
'NCF_A1_CPU1_P0_GND'
 '@T6G_MB_LIB.T6G(SCH_1):NCF_A1_CPU1_P0_GND':
 C_SIGNAL='@t6g_mb_lib.t6g(sch_1):ncf_a1_cpu1_p0_gnd';
NODE_NAME     U6014 A1
 '@T6G_MB_LIB.T6G(SCH_1):PAGE400_I2@PURE_QUANTA.PT5161LRS(CHIPS)':
 'NCF_GND1': CDS_PINID='NCF_GND1';
NODE_NAME     R711 1
 '@T6G_MB_LIB.T6G(SCH_1):PAGE400_I102@PURE_QUANTA.Q_RES(CHIPS)':
 'A': CDS_PINID='A';
NET_NAME
'NCF_A1_CPU1_P1_GND'
 '@T6G_MB_LIB.T6G(SCH_1):NCF_A1_CPU1_P1_GND':
 C_SIGNAL='@t6g_mb_lib.t6g(sch_1):ncf_a1_cpu1_p1_gnd';
NODE_NAME     R6732 1
 '@T6G_MB_LIB.T6G(SCH_1):PAGE391_I16@PURE_QUANTA.Q_RES(CHIPS)':
 'A': CDS_PINID='A';
NODE_NAME     U6015 A1
 '@T6G_MB_LIB.T6G(SCH_1):PAGE391_I19@PURE_QUANTA.PT5161LRS(CHIPS)':
 'NCF_GND1': CDS_PINID='NCF_GND1';
NET_NAME
'NCF_A1_CPU1_P2_GND'
 '@T6G_MB_LIB.T6G(SCH_1):NCF_A1_CPU1_P2_GND':
 C_SIGNAL='@t6g_mb_lib.t6g(sch_1):ncf_a1_cpu1_p2_gnd';
NODE_NAME     R6796 1
 '@T6G_MB_LIB.T6G(SCH_1):PAGE452_I18@PURE_QUANTA.Q_RES(CHIPS)':
 'A': CDS_PINID='A';
NODE_NAME     U6016 A1
 '@T6G_MB_LIB.T6G(SCH_1):PAGE452_I19@PURE_QUANTA.PT5161LRS(CHIPS)':
 'NCF_GND1': CDS_PINID='NCF_GND1';
NET_NAME
'NCF_A1_CPU1_P3_GND'
 '@T6G_MB_LIB.T6G(SCH_1):NCF_A1_CPU1_P3_GND':
 C_SIGNAL='@t6g_mb_lib.t6g(sch_1):ncf_a1_cpu1_p3_gnd';
NODE_NAME     R6902 1
 '@T6G_MB_LIB.T6G(SCH_1):PAGE463_I15@PURE_QUANTA.Q_RES(CHIPS)':
 'A': CDS_PINID='A';
NODE_NAME     U6017 A1
 '@T6G_MB_LIB.T6G(SCH_1):PAGE463_I17@PURE_QUANTA.PT5161LRS(CHIPS)':
 'NCF_GND1': CDS_PINID='NCF_GND1';
NET_NAME
'NCF_CPU0_P0_GND'
 '@T6G_MB_LIB.T6G(SCH_1):NCF_CPU0_P0_GND':
 C_SIGNAL='@t6g_mb_lib.t6g(sch_1):ncf_cpu0_p0_gnd';
NODE_NAME     R6821 1
 '@T6G_MB_LIB.T6G(SCH_1):PAGE386_I13@PURE_QUANTA.Q_RES(CHIPS)':
 'A': CDS_PINID='A';
NODE_NAME     U6010 A35
 '@T6G_MB_LIB.T6G(SCH_1):PAGE386_I17@PURE_QUANTA.PT5161LRS(CHIPS)':
 'NCF_GND2': CDS_PINID='NCF_GND2';
NODE_NAME     U6010 C2
 '@T6G_MB_LIB.T6G(SCH_1):PAGE386_I17@PURE_QUANTA.PT5161LRS(CHIPS)':
 'NCF_GND3': CDS_PINID='NCF_GND3';
NODE_NAME     U6010 C34
 '@T6G_MB_LIB.T6G(SCH_1):PAGE386_I17@PURE_QUANTA.PT5161LRS(CHIPS)':
 'NCF_GND4': CDS_PINID='NCF_GND4';
NODE_NAME     U6010 D1
 '@T6G_MB_LIB.T6G(SCH_1):PAGE386_I17@PURE_QUANTA.PT5161LRS(CHIPS)':
 'NCF_GND5': CDS_PINID='NCF_GND5';
NODE_NAME     U6010 D35
 '@T6G_MB_LIB.T6G(SCH_1):PAGE386_I17@PURE_QUANTA.PT5161LRS(CHIPS)':
 'NCF_GND6': CDS_PINID='NCF_GND6';
NODE_NAME     U6010 FE2
 '@T6G_MB_LIB.T6G(SCH_1):PAGE386_I17@PURE_QUANTA.PT5161LRS(CHIPS)':
 'NCF_GND7': CDS_PINID='NCF_GND7';
NODE_NAME     U6010 FE34
 '@T6G_MB_LIB.T6G(SCH_1):PAGE386_I17@PURE_QUANTA.PT5161LRS(CHIPS)':
 'NCF_GND8': CDS_PINID='NCF_GND8';
NODE_NAME     U6010 FG1
 '@T6G_MB_LIB.T6G(SCH_1):PAGE386_I17@PURE_QUANTA.PT5161LRS(CHIPS)':
 'NCF_GND9': CDS_PINID='NCF_GND9';
NODE_NAME     U6010 FG35
 '@T6G_MB_LIB.T6G(SCH_1):PAGE386_I17@PURE_QUANTA.PT5161LRS(CHIPS)':
 'NCF_GND10': CDS_PINID='NCF_GND10';
NODE_NAME     U6010 FH2
 '@T6G_MB_LIB.T6G(SCH_1):PAGE386_I17@PURE_QUANTA.PT5161LRS(CHIPS)':
 'NCF_GND11': CDS_PINID='NCF_GND11';
NODE_NAME     U6010 FH34
 '@T6G_MB_LIB.T6G(SCH_1):PAGE386_I17@PURE_QUANTA.PT5161LRS(CHIPS)':
 'NCF_GND12': CDS_PINID='NCF_GND12';
NET_NAME
'NCF_CPU0_P1_GND'
 '@T6G_MB_LIB.T6G(SCH_1):NCF_CPU0_P1_GND':
 C_SIGNAL='@t6g_mb_lib.t6g(sch_1):ncf_cpu0_p1_gnd';
NODE_NAME     R1042 1
 '@T6G_MB_LIB.T6G(SCH_1):PAGE409_I13@PURE_QUANTA.Q_RES(CHIPS)':
 'A': CDS_PINID='A';
NODE_NAME     U6011 A35
 '@T6G_MB_LIB.T6G(SCH_1):PAGE409_I17@PURE_QUANTA.PT5161LRS(CHIPS)':
 'NCF_GND2': CDS_PINID='NCF_GND2';
NODE_NAME     U6011 C2
 '@T6G_MB_LIB.T6G(SCH_1):PAGE409_I17@PURE_QUANTA.PT5161LRS(CHIPS)':
 'NCF_GND3': CDS_PINID='NCF_GND3';
NODE_NAME     U6011 C34
 '@T6G_MB_LIB.T6G(SCH_1):PAGE409_I17@PURE_QUANTA.PT5161LRS(CHIPS)':
 'NCF_GND4': CDS_PINID='NCF_GND4';
NODE_NAME     U6011 D1
 '@T6G_MB_LIB.T6G(SCH_1):PAGE409_I17@PURE_QUANTA.PT5161LRS(CHIPS)':
 'NCF_GND5': CDS_PINID='NCF_GND5';
NODE_NAME     U6011 D35
 '@T6G_MB_LIB.T6G(SCH_1):PAGE409_I17@PURE_QUANTA.PT5161LRS(CHIPS)':
 'NCF_GND6': CDS_PINID='NCF_GND6';
NODE_NAME     U6011 FE2
 '@T6G_MB_LIB.T6G(SCH_1):PAGE409_I17@PURE_QUANTA.PT5161LRS(CHIPS)':
 'NCF_GND7': CDS_PINID='NCF_GND7';
NODE_NAME     U6011 FE34
 '@T6G_MB_LIB.T6G(SCH_1):PAGE409_I17@PURE_QUANTA.PT5161LRS(CHIPS)':
 'NCF_GND8': CDS_PINID='NCF_GND8';
NODE_NAME     U6011 FG1
 '@T6G_MB_LIB.T6G(SCH_1):PAGE409_I17@PURE_QUANTA.PT5161LRS(CHIPS)':
 'NCF_GND9': CDS_PINID='NCF_GND9';
NODE_NAME     U6011 FG35
 '@T6G_MB_LIB.T6G(SCH_1):PAGE409_I17@PURE_QUANTA.PT5161LRS(CHIPS)':
 'NCF_GND10': CDS_PINID='NCF_GND10';
NODE_NAME     U6011 FH2
 '@T6G_MB_LIB.T6G(SCH_1):PAGE409_I17@PURE_QUANTA.PT5161LRS(CHIPS)':
 'NCF_GND11': CDS_PINID='NCF_GND11';
NODE_NAME     U6011 FH34
 '@T6G_MB_LIB.T6G(SCH_1):PAGE409_I17@PURE_QUANTA.PT5161LRS(CHIPS)':
 'NCF_GND12': CDS_PINID='NCF_GND12';
NET_NAME
'NCF_CPU0_P2_GND'
 '@T6G_MB_LIB.T6G(SCH_1):NCF_CPU0_P2_GND':
 C_SIGNAL='@t6g_mb_lib.t6g(sch_1):ncf_cpu0_p2_gnd';
NODE_NAME     R1083 1
 '@T6G_MB_LIB.T6G(SCH_1):PAGE420_I13@PURE_QUANTA.Q_RES(CHIPS)':
 'A': CDS_PINID='A';
NODE_NAME     U6012 A35
 '@T6G_MB_LIB.T6G(SCH_1):PAGE420_I17@PURE_QUANTA.PT5161LRS(CHIPS)':
 'NCF_GND2': CDS_PINID='NCF_GND2';
NODE_NAME     U6012 C2
 '@T6G_MB_LIB.T6G(SCH_1):PAGE420_I17@PURE_QUANTA.PT5161LRS(CHIPS)':
 'NCF_GND3': CDS_PINID='NCF_GND3';
NODE_NAME     U6012 C34
 '@T6G_MB_LIB.T6G(SCH_1):PAGE420_I17@PURE_QUANTA.PT5161LRS(CHIPS)':
 'NCF_GND4': CDS_PINID='NCF_GND4';
NODE_NAME     U6012 D1
 '@T6G_MB_LIB.T6G(SCH_1):PAGE420_I17@PURE_QUANTA.PT5161LRS(CHIPS)':
 'NCF_GND5': CDS_PINID='NCF_GND5';
NODE_NAME     U6012 D35
 '@T6G_MB_LIB.T6G(SCH_1):PAGE420_I17@PURE_QUANTA.PT5161LRS(CHIPS)':
 'NCF_GND6': CDS_PINID='NCF_GND6';
NODE_NAME     U6012 FE2
 '@T6G_MB_LIB.T6G(SCH_1):PAGE420_I17@PURE_QUANTA.PT5161LRS(CHIPS)':
 'NCF_GND7': CDS_PINID='NCF_GND7';
NODE_NAME     U6012 FE34
 '@T6G_MB_LIB.T6G(SCH_1):PAGE420_I17@PURE_QUANTA.PT5161LRS(CHIPS)':
 'NCF_GND8': CDS_PINID='NCF_GND8';
NODE_NAME     U6012 FG1
 '@T6G_MB_LIB.T6G(SCH_1):PAGE420_I17@PURE_QUANTA.PT5161LRS(CHIPS)':
 'NCF_GND9': CDS_PINID='NCF_GND9';
NODE_NAME     U6012 FG35
 '@T6G_MB_LIB.T6G(SCH_1):PAGE420_I17@PURE_QUANTA.PT5161LRS(CHIPS)':
 'NCF_GND10': CDS_PINID='NCF_GND10';
NODE_NAME     U6012 FH2
 '@T6G_MB_LIB.T6G(SCH_1):PAGE420_I17@PURE_QUANTA.PT5161LRS(CHIPS)':
 'NCF_GND11': CDS_PINID='NCF_GND11';
NODE_NAME     U6012 FH34
 '@T6G_MB_LIB.T6G(SCH_1):PAGE420_I17@PURE_QUANTA.PT5161LRS(CHIPS)':
 'NCF_GND12': CDS_PINID='NCF_GND12';
NET_NAME
'NCF_CPU0_P3_GND'
 '@T6G_MB_LIB.T6G(SCH_1):NCF_CPU0_P3_GND':
 C_SIGNAL='@t6g_mb_lib.t6g(sch_1):ncf_cpu0_p3_gnd';
NODE_NAME     R1125 1
 '@T6G_MB_LIB.T6G(SCH_1):PAGE431_I13@PURE_QUANTA.Q_RES(CHIPS)':
 'A': CDS_PINID='A';
NODE_NAME     U6013 A35
 '@T6G_MB_LIB.T6G(SCH_1):PAGE431_I17@PURE_QUANTA.PT5161LRS(CHIPS)':
 'NCF_GND2': CDS_PINID='NCF_GND2';
NODE_NAME     U6013 C2
 '@T6G_MB_LIB.T6G(SCH_1):PAGE431_I17@PURE_QUANTA.PT5161LRS(CHIPS)':
 'NCF_GND3': CDS_PINID='NCF_GND3';
NODE_NAME     U6013 C34
 '@T6G_MB_LIB.T6G(SCH_1):PAGE431_I17@PURE_QUANTA.PT5161LRS(CHIPS)':
 'NCF_GND4': CDS_PINID='NCF_GND4';
NODE_NAME     U6013 D1
 '@T6G_MB_LIB.T6G(SCH_1):PAGE431_I17@PURE_QUANTA.PT5161LRS(CHIPS)':
 'NCF_GND5': CDS_PINID='NCF_GND5';
NODE_NAME     U6013 D35
 '@T6G_MB_LIB.T6G(SCH_1):PAGE431_I17@PURE_QUANTA.PT5161LRS(CHIPS)':
 'NCF_GND6': CDS_PINID='NCF_GND6';
NODE_NAME     U6013 FE2
 '@T6G_MB_LIB.T6G(SCH_1):PAGE431_I17@PURE_QUANTA.PT5161LRS(CHIPS)':
 'NCF_GND7': CDS_PINID='NCF_GND7';
NODE_NAME     U6013 FE34
 '@T6G_MB_LIB.T6G(SCH_1):PAGE431_I17@PURE_QUANTA.PT5161LRS(CHIPS)':
 'NCF_GND8': CDS_PINID='NCF_GND8';
NODE_NAME     U6013 FG1
 '@T6G_MB_LIB.T6G(SCH_1):PAGE431_I17@PURE_QUANTA.PT5161LRS(CHIPS)':
 'NCF_GND9': CDS_PINID='NCF_GND9';
NODE_NAME     U6013 FG35
 '@T6G_MB_LIB.T6G(SCH_1):PAGE431_I17@PURE_QUANTA.PT5161LRS(CHIPS)':
 'NCF_GND10': CDS_PINID='NCF_GND10';
NODE_NAME     U6013 FH2
 '@T6G_MB_LIB.T6G(SCH_1):PAGE431_I17@PURE_QUANTA.PT5161LRS(CHIPS)':
 'NCF_GND11': CDS_PINID='NCF_GND11';
NODE_NAME     U6013 FH34
 '@T6G_MB_LIB.T6G(SCH_1):PAGE431_I17@PURE_QUANTA.PT5161LRS(CHIPS)':
 'NCF_GND12': CDS_PINID='NCF_GND12';
NET_NAME
'NCF_CPU1_P0_GND'
 '@T6G_MB_LIB.T6G(SCH_1):NCF_CPU1_P0_GND':
 C_SIGNAL='@t6g_mb_lib.t6g(sch_1):ncf_cpu1_p0_gnd';
NODE_NAME     U6014 A35
 '@T6G_MB_LIB.T6G(SCH_1):PAGE400_I2@PURE_QUANTA.PT5161LRS(CHIPS)':
 'NCF_GND2': CDS_PINID='NCF_GND2';
NODE_NAME     U6014 C2
 '@T6G_MB_LIB.T6G(SCH_1):PAGE400_I2@PURE_QUANTA.PT5161LRS(CHIPS)':
 'NCF_GND3': CDS_PINID='NCF_GND3';
NODE_NAME     U6014 C34
 '@T6G_MB_LIB.T6G(SCH_1):PAGE400_I2@PURE_QUANTA.PT5161LRS(CHIPS)':
 'NCF_GND4': CDS_PINID='NCF_GND4';
NODE_NAME     U6014 D1
 '@T6G_MB_LIB.T6G(SCH_1):PAGE400_I2@PURE_QUANTA.PT5161LRS(CHIPS)':
 'NCF_GND5': CDS_PINID='NCF_GND5';
NODE_NAME     U6014 D35
 '@T6G_MB_LIB.T6G(SCH_1):PAGE400_I2@PURE_QUANTA.PT5161LRS(CHIPS)':
 'NCF_GND6': CDS_PINID='NCF_GND6';
NODE_NAME     U6014 FE2
 '@T6G_MB_LIB.T6G(SCH_1):PAGE400_I2@PURE_QUANTA.PT5161LRS(CHIPS)':
 'NCF_GND7': CDS_PINID='NCF_GND7';
NODE_NAME     U6014 FE34
 '@T6G_MB_LIB.T6G(SCH_1):PAGE400_I2@PURE_QUANTA.PT5161LRS(CHIPS)':
 'NCF_GND8': CDS_PINID='NCF_GND8';
NODE_NAME     U6014 FG1
 '@T6G_MB_LIB.T6G(SCH_1):PAGE400_I2@PURE_QUANTA.PT5161LRS(CHIPS)':
 'NCF_GND9': CDS_PINID='NCF_GND9';
NODE_NAME     U6014 FG35
 '@T6G_MB_LIB.T6G(SCH_1):PAGE400_I2@PURE_QUANTA.PT5161LRS(CHIPS)':
 'NCF_GND10': CDS_PINID='NCF_GND10';
NODE_NAME     U6014 FH2
 '@T6G_MB_LIB.T6G(SCH_1):PAGE400_I2@PURE_QUANTA.PT5161LRS(CHIPS)':
 'NCF_GND11': CDS_PINID='NCF_GND11';
NODE_NAME     U6014 FH34
 '@T6G_MB_LIB.T6G(SCH_1):PAGE400_I2@PURE_QUANTA.PT5161LRS(CHIPS)':
 'NCF_GND12': CDS_PINID='NCF_GND12';
NODE_NAME     R709 1
 '@T6G_MB_LIB.T6G(SCH_1):PAGE400_I103@PURE_QUANTA.Q_RES(CHIPS)':
 'A': CDS_PINID='A';
NET_NAME
'NCF_CPU1_P1_GND'
 '@T6G_MB_LIB.T6G(SCH_1):NCF_CPU1_P1_GND':
 C_SIGNAL='@t6g_mb_lib.t6g(sch_1):ncf_cpu1_p1_gnd';
NODE_NAME     R6733 1
 '@T6G_MB_LIB.T6G(SCH_1):PAGE391_I15@PURE_QUANTA.Q_RES(CHIPS)':
 'A': CDS_PINID='A';
NODE_NAME     U6015 A35
 '@T6G_MB_LIB.T6G(SCH_1):PAGE391_I19@PURE_QUANTA.PT5161LRS(CHIPS)':
 'NCF_GND2': CDS_PINID='NCF_GND2';
NODE_NAME     U6015 C2
 '@T6G_MB_LIB.T6G(SCH_1):PAGE391_I19@PURE_QUANTA.PT5161LRS(CHIPS)':
 'NCF_GND3': CDS_PINID='NCF_GND3';
NODE_NAME     U6015 C34
 '@T6G_MB_LIB.T6G(SCH_1):PAGE391_I19@PURE_QUANTA.PT5161LRS(CHIPS)':
 'NCF_GND4': CDS_PINID='NCF_GND4';
NODE_NAME     U6015 D1
 '@T6G_MB_LIB.T6G(SCH_1):PAGE391_I19@PURE_QUANTA.PT5161LRS(CHIPS)':
 'NCF_GND5': CDS_PINID='NCF_GND5';
NODE_NAME     U6015 D35
 '@T6G_MB_LIB.T6G(SCH_1):PAGE391_I19@PURE_QUANTA.PT5161LRS(CHIPS)':
 'NCF_GND6': CDS_PINID='NCF_GND6';
NODE_NAME     U6015 FE2
 '@T6G_MB_LIB.T6G(SCH_1):PAGE391_I19@PURE_QUANTA.PT5161LRS(CHIPS)':
 'NCF_GND7': CDS_PINID='NCF_GND7';
NODE_NAME     U6015 FE34
 '@T6G_MB_LIB.T6G(SCH_1):PAGE391_I19@PURE_QUANTA.PT5161LRS(CHIPS)':
 'NCF_GND8': CDS_PINID='NCF_GND8';
NODE_NAME     U6015 FG1
 '@T6G_MB_LIB.T6G(SCH_1):PAGE391_I19@PURE_QUANTA.PT5161LRS(CHIPS)':
 'NCF_GND9': CDS_PINID='NCF_GND9';
NODE_NAME     U6015 FG35
 '@T6G_MB_LIB.T6G(SCH_1):PAGE391_I19@PURE_QUANTA.PT5161LRS(CHIPS)':
 'NCF_GND10': CDS_PINID='NCF_GND10';
NODE_NAME     U6015 FH2
 '@T6G_MB_LIB.T6G(SCH_1):PAGE391_I19@PURE_QUANTA.PT5161LRS(CHIPS)':
 'NCF_GND11': CDS_PINID='NCF_GND11';
NODE_NAME     U6015 FH34
 '@T6G_MB_LIB.T6G(SCH_1):PAGE391_I19@PURE_QUANTA.PT5161LRS(CHIPS)':
 'NCF_GND12': CDS_PINID='NCF_GND12';
NET_NAME
'NCF_CPU1_P2_GND'
 '@T6G_MB_LIB.T6G(SCH_1):NCF_CPU1_P2_GND':
 C_SIGNAL='@t6g_mb_lib.t6g(sch_1):ncf_cpu1_p2_gnd';
NODE_NAME     R6797 1
 '@T6G_MB_LIB.T6G(SCH_1):PAGE452_I15@PURE_QUANTA.Q_RES(CHIPS)':
 'A': CDS_PINID='A';
NODE_NAME     U6016 A35
 '@T6G_MB_LIB.T6G(SCH_1):PAGE452_I19@PURE_QUANTA.PT5161LRS(CHIPS)':
 'NCF_GND2': CDS_PINID='NCF_GND2';
NODE_NAME     U6016 C2
 '@T6G_MB_LIB.T6G(SCH_1):PAGE452_I19@PURE_QUANTA.PT5161LRS(CHIPS)':
 'NCF_GND3': CDS_PINID='NCF_GND3';
NODE_NAME     U6016 C34
 '@T6G_MB_LIB.T6G(SCH_1):PAGE452_I19@PURE_QUANTA.PT5161LRS(CHIPS)':
 'NCF_GND4': CDS_PINID='NCF_GND4';
NODE_NAME     U6016 D1
 '@T6G_MB_LIB.T6G(SCH_1):PAGE452_I19@PURE_QUANTA.PT5161LRS(CHIPS)':
 'NCF_GND5': CDS_PINID='NCF_GND5';
NODE_NAME     U6016 D35
 '@T6G_MB_LIB.T6G(SCH_1):PAGE452_I19@PURE_QUANTA.PT5161LRS(CHIPS)':
 'NCF_GND6': CDS_PINID='NCF_GND6';
NODE_NAME     U6016 FE2
 '@T6G_MB_LIB.T6G(SCH_1):PAGE452_I19@PURE_QUANTA.PT5161LRS(CHIPS)':
 'NCF_GND7': CDS_PINID='NCF_GND7';
NODE_NAME     U6016 FE34
 '@T6G_MB_LIB.T6G(SCH_1):PAGE452_I19@PURE_QUANTA.PT5161LRS(CHIPS)':
 'NCF_GND8': CDS_PINID='NCF_GND8';
NODE_NAME     U6016 FG1
 '@T6G_MB_LIB.T6G(SCH_1):PAGE452_I19@PURE_QUANTA.PT5161LRS(CHIPS)':
 'NCF_GND9': CDS_PINID='NCF_GND9';
NODE_NAME     U6016 FG35
 '@T6G_MB_LIB.T6G(SCH_1):PAGE452_I19@PURE_QUANTA.PT5161LRS(CHIPS)':
 'NCF_GND10': CDS_PINID='NCF_GND10';
NODE_NAME     U6016 FH2
 '@T6G_MB_LIB.T6G(SCH_1):PAGE452_I19@PURE_QUANTA.PT5161LRS(CHIPS)':
 'NCF_GND11': CDS_PINID='NCF_GND11';
NODE_NAME     U6016 FH34
 '@T6G_MB_LIB.T6G(SCH_1):PAGE452_I19@PURE_QUANTA.PT5161LRS(CHIPS)':
 'NCF_GND12': CDS_PINID='NCF_GND12';
NET_NAME
'NCF_CPU1_P3_GND'
 '@T6G_MB_LIB.T6G(SCH_1):NCF_CPU1_P3_GND':
 C_SIGNAL='@t6g_mb_lib.t6g(sch_1):ncf_cpu1_p3_gnd';
NODE_NAME     R6903 1
 '@T6G_MB_LIB.T6G(SCH_1):PAGE463_I13@PURE_QUANTA.Q_RES(CHIPS)':
 'A': CDS_PINID='A';
NODE_NAME     U6017 A35
 '@T6G_MB_LIB.T6G(SCH_1):PAGE463_I17@PURE_QUANTA.PT5161LRS(CHIPS)':
 'NCF_GND2': CDS_PINID='NCF_GND2';
NODE_NAME     U6017 C2
 '@T6G_MB_LIB.T6G(SCH_1):PAGE463_I17@PURE_QUANTA.PT5161LRS(CHIPS)':
 'NCF_GND3': CDS_PINID='NCF_GND3';
NODE_NAME     U6017 C34
 '@T6G_MB_LIB.T6G(SCH_1):PAGE463_I17@PURE_QUANTA.PT5161LRS(CHIPS)':
 'NCF_GND4': CDS_PINID='NCF_GND4';
NODE_NAME     U6017 D1
 '@T6G_MB_LIB.T6G(SCH_1):PAGE463_I17@PURE_QUANTA.PT5161LRS(CHIPS)':
 'NCF_GND5': CDS_PINID='NCF_GND5';
NODE_NAME     U6017 D35
 '@T6G_MB_LIB.T6G(SCH_1):PAGE463_I17@PURE_QUANTA.PT5161LRS(CHIPS)':
 'NCF_GND6': CDS_PINID='NCF_GND6';
NODE_NAME     U6017 FE2
 '@T6G_MB_LIB.T6G(SCH_1):PAGE463_I17@PURE_QUANTA.PT5161LRS(CHIPS)':
 'NCF_GND7': CDS_PINID='NCF_GND7';
NODE_NAME     U6017 FE34
 '@T6G_MB_LIB.T6G(SCH_1):PAGE463_I17@PURE_QUANTA.PT5161LRS(CHIPS)':
 'NCF_GND8': CDS_PINID='NCF_GND8';
NODE_NAME     U6017 FG1
 '@T6G_MB_LIB.T6G(SCH_1):PAGE463_I17@PURE_QUANTA.PT5161LRS(CHIPS)':
 'NCF_GND9': CDS_PINID='NCF_GND9';
NODE_NAME     U6017 FG35
 '@T6G_MB_LIB.T6G(SCH_1):PAGE463_I17@PURE_QUANTA.PT5161LRS(CHIPS)':
 'NCF_GND10': CDS_PINID='NCF_GND10';
NODE_NAME     U6017 FH2
 '@T6G_MB_LIB.T6G(SCH_1):PAGE463_I17@PURE_QUANTA.PT5161LRS(CHIPS)':
 'NCF_GND11': CDS_PINID='NCF_GND11';
NODE_NAME     U6017 FH34
 '@T6G_MB_LIB.T6G(SCH_1):PAGE463_I17@PURE_QUANTA.PT5161LRS(CHIPS)':
 'NCF_GND12': CDS_PINID='NCF_GND12';
NET_NAME
'NCSI_BMC_CRS_DV_R'
 '@T6G_MB_LIB.T6G(SCH_1):NCSI_BMC_CRS_DV_R':
 C_SIGNAL='@t6g_mb_lib.t6g(sch_1):ncsi_bmc_crs_dv_r';
NODE_NAME     U67 9
 '@T6G_MB_LIB.T6G(SCH_1):PAGE336_I1@PURE_QUANTA.74CBTLV3126PW(CHIPS)':
 '3A': CDS_PINID='\3a\';
NODE_NAME     R59 1
 '@T6G_MB_LIB.T6G(SCH_1):PAGE336_I99@PURE_QUANTA.Q_RES(CHIPS)':
 'A': CDS_PINID='A';
NET_NAME
'NCSI_BMC_CRS_DV_R1'
 '@T6G_MB_LIB.T6G(SCH_1):NCSI_BMC_CRS_DV_R1':
 C_SIGNAL='@t6g_mb_lib.t6g(sch_1):ncsi_bmc_crs_dv_r1';
NODE_NAME     U222 9
 '@T6G_MB_LIB.T6G(SCH_1):PAGE307_I32@PURE_QUANTA.74CBTLV3126PW(CHIPS)':
 '3A': CDS_PINID='\3a\';
NODE_NAME     R3210 1
 '@T6G_MB_LIB.T6G(SCH_1):PAGE307_I65@PURE_QUANTA.Q_RES(CHIPS)':
 'A': CDS_PINID='A';
NET_NAME
'NCSI_BMC_RXD0_R'
 '@T6G_MB_LIB.T6G(SCH_1):NCSI_BMC_RXD0_R':
 C_SIGNAL='@t6g_mb_lib.t6g(sch_1):ncsi_bmc_rxd0_r';
NODE_NAME     U67 5
 '@T6G_MB_LIB.T6G(SCH_1):PAGE336_I1@PURE_QUANTA.74CBTLV3126PW(CHIPS)':
 '2A': CDS_PINID='\2a\';
NODE_NAME     R72 1
 '@T6G_MB_LIB.T6G(SCH_1):PAGE336_I100@PURE_QUANTA.Q_RES(CHIPS)':
 'A': CDS_PINID='A';
NET_NAME
'NCSI_BMC_RXD0_R1'
 '@T6G_MB_LIB.T6G(SCH_1):NCSI_BMC_RXD0_R1':
 C_SIGNAL='@t6g_mb_lib.t6g(sch_1):ncsi_bmc_rxd0_r1';
NODE_NAME     U222 5
 '@T6G_MB_LIB.T6G(SCH_1):PAGE307_I32@PURE_QUANTA.74CBTLV3126PW(CHIPS)':
 '2A': CDS_PINID='\2a\';
NODE_NAME     R3211 1
 '@T6G_MB_LIB.T6G(SCH_1):PAGE307_I63@PURE_QUANTA.Q_RES(CHIPS)':
 'A': CDS_PINID='A';
NET_NAME
'NCSI_BMC_RXD1_R'
 '@T6G_MB_LIB.T6G(SCH_1):NCSI_BMC_RXD1_R':
 C_SIGNAL='@t6g_mb_lib.t6g(sch_1):ncsi_bmc_rxd1_r';
NODE_NAME     U67 2
 '@T6G_MB_LIB.T6G(SCH_1):PAGE336_I1@PURE_QUANTA.74CBTLV3126PW(CHIPS)':
 '1A': CDS_PINID='\1a\';
NODE_NAME     R73 1
 '@T6G_MB_LIB.T6G(SCH_1):PAGE336_I101@PURE_QUANTA.Q_RES(CHIPS)':
 'A': CDS_PINID='A';
NET_NAME
'NCSI_BMC_RXD1_R1'
 '@T6G_MB_LIB.T6G(SCH_1):NCSI_BMC_RXD1_R1':
 C_SIGNAL='@t6g_mb_lib.t6g(sch_1):ncsi_bmc_rxd1_r1';
NODE_NAME     U222 2
 '@T6G_MB_LIB.T6G(SCH_1):PAGE307_I32@PURE_QUANTA.74CBTLV3126PW(CHIPS)':
 '1A': CDS_PINID='\1a\';
NODE_NAME     R3212 1
 '@T6G_MB_LIB.T6G(SCH_1):PAGE307_I62@PURE_QUANTA.Q_RES(CHIPS)':
 'A': CDS_PINID='A';
NET_NAME
'NCSI_BMC_TXD0_R'
 '@T6G_MB_LIB.T6G(SCH_1):NCSI_BMC_TXD0_R':
 C_SIGNAL='@t6g_mb_lib.t6g(sch_1):ncsi_bmc_txd0_r';
NODE_NAME     U7 5
 '@T6G_MB_LIB.T6G(SCH_1):PAGE336_I2@PURE_QUANTA.74CBTLV3126PW(CHIPS)':
 '2A': CDS_PINID='\2a\';
NODE_NAME     R75 1
 '@T6G_MB_LIB.T6G(SCH_1):PAGE336_I103@PURE_QUANTA.Q_RES(CHIPS)':
 'A': CDS_PINID='A';
NET_NAME
'NCSI_BMC_TXD0_R1'
 '@T6G_MB_LIB.T6G(SCH_1):NCSI_BMC_TXD0_R1':
 C_SIGNAL='@t6g_mb_lib.t6g(sch_1):ncsi_bmc_txd0_r1';
NODE_NAME     R3214 1
 '@T6G_MB_LIB.T6G(SCH_1):PAGE307_I60@PURE_QUANTA.Q_RES(CHIPS)':
 'A': CDS_PINID='A';
NODE_NAME     U223 5
 '@T6G_MB_LIB.T6G(SCH_1):PAGE307_I78@PURE_QUANTA.74CBTLV3126PW(CHIPS)':
 '2A': CDS_PINID='\2a\';
NET_NAME
'NCSI_BMC_TXD1_R'
 '@T6G_MB_LIB.T6G(SCH_1):NCSI_BMC_TXD1_R':
 C_SIGNAL='@t6g_mb_lib.t6g(sch_1):ncsi_bmc_txd1_r';
NODE_NAME     U7 2
 '@T6G_MB_LIB.T6G(SCH_1):PAGE336_I2@PURE_QUANTA.74CBTLV3126PW(CHIPS)':
 '1A': CDS_PINID='\1a\';
NODE_NAME     R76 1
 '@T6G_MB_LIB.T6G(SCH_1):PAGE336_I104@PURE_QUANTA.Q_RES(CHIPS)':
 'A': CDS_PINID='A';
NET_NAME
'NCSI_BMC_TXD1_R1'
 '@T6G_MB_LIB.T6G(SCH_1):NCSI_BMC_TXD1_R1':
 C_SIGNAL='@t6g_mb_lib.t6g(sch_1):ncsi_bmc_txd1_r1';
NODE_NAME     R3215 1
 '@T6G_MB_LIB.T6G(SCH_1):PAGE307_I56@PURE_QUANTA.Q_RES(CHIPS)':
 'A': CDS_PINID='A';
NODE_NAME     U223 2
 '@T6G_MB_LIB.T6G(SCH_1):PAGE307_I78@PURE_QUANTA.74CBTLV3126PW(CHIPS)':
 '1A': CDS_PINID='\1a\';
NET_NAME
'NCSI_BMC_TX_EN_R'
 '@T6G_MB_LIB.T6G(SCH_1):NCSI_BMC_TX_EN_R':
 C_SIGNAL='@t6g_mb_lib.t6g(sch_1):ncsi_bmc_tx_en_r';
NODE_NAME     U7 9
 '@T6G_MB_LIB.T6G(SCH_1):PAGE336_I2@PURE_QUANTA.74CBTLV3126PW(CHIPS)':
 '3A': CDS_PINID='\3a\';
NODE_NAME     R74 1
 '@T6G_MB_LIB.T6G(SCH_1):PAGE336_I102@PURE_QUANTA.Q_RES(CHIPS)':
 'A': CDS_PINID='A';
NET_NAME
'NCSI_BMC_TX_EN_R1'
 '@T6G_MB_LIB.T6G(SCH_1):NCSI_BMC_TX_EN_R1':
 C_SIGNAL='@t6g_mb_lib.t6g(sch_1):ncsi_bmc_tx_en_r1';
NODE_NAME     R3213 1
 '@T6G_MB_LIB.T6G(SCH_1):PAGE307_I61@PURE_QUANTA.Q_RES(CHIPS)':
 'A': CDS_PINID='A';
NODE_NAME     U223 9
 '@T6G_MB_LIB.T6G(SCH_1):PAGE307_I78@PURE_QUANTA.74CBTLV3126PW(CHIPS)':
 '3A': CDS_PINID='\3a\';
NET_NAME
'NCSI_OCP_SFF_CRS_DV'
 '@T6G_MB_LIB.T6G(SCH_1):NCSI_OCP_SFF_CRS_DV':
 C_SIGNAL='@t6g_mb_lib.t6g(sch_1):ncsi_ocp_sff_crs_dv';
NODE_NAME     J38 OB14
 '@T6G_MB_LIB.T6G(SCH_1):PAGE335_I168@PURE_QUANTA.SCONN168_ME1016810202011(CHIPS)':
 'RBT_CRS_DV': CDS_PINID='RBT_CRS_DV';
NODE_NAME     U67 8
 '@T6G_MB_LIB.T6G(SCH_1):PAGE336_I1@PURE_QUANTA.74CBTLV3126PW(CHIPS)':
 '3B': CDS_PINID='\3b\';
NET_NAME
'NCSI_OCP_SFF_RXD0'
 '@T6G_MB_LIB.T6G(SCH_1):NCSI_OCP_SFF_RXD0':
 C_SIGNAL='@t6g_mb_lib.t6g(sch_1):ncsi_ocp_sff_rxd0';
NODE_NAME     J38 OB9
 '@T6G_MB_LIB.T6G(SCH_1):PAGE335_I168@PURE_QUANTA.SCONN168_ME1016810202011(CHIPS)':
 'RBT_RXD0': CDS_PINID='RBT_RXD0';
NODE_NAME     U67 6
 '@T6G_MB_LIB.T6G(SCH_1):PAGE336_I1@PURE_QUANTA.74CBTLV3126PW(CHIPS)':
 '2B': CDS_PINID='\2b\';
NET_NAME
'NCSI_OCP_SFF_RXD1'
 '@T6G_MB_LIB.T6G(SCH_1):NCSI_OCP_SFF_RXD1':
 C_SIGNAL='@t6g_mb_lib.t6g(sch_1):ncsi_ocp_sff_rxd1';
NODE_NAME     J38 OB8
 '@T6G_MB_LIB.T6G(SCH_1):PAGE335_I168@PURE_QUANTA.SCONN168_ME1016810202011(CHIPS)':
 'RBT_RXD1': CDS_PINID='RBT_RXD1';
NODE_NAME     U67 3
 '@T6G_MB_LIB.T6G(SCH_1):PAGE336_I1@PURE_QUANTA.74CBTLV3126PW(CHIPS)':
 '1B': CDS_PINID='\1b\';
NET_NAME
'NCSI_OCP_SFF_TXD0'
 '@T6G_MB_LIB.T6G(SCH_1):NCSI_OCP_SFF_TXD0':
 C_SIGNAL='@t6g_mb_lib.t6g(sch_1):ncsi_ocp_sff_txd0';
NODE_NAME     J38 OA9
 '@T6G_MB_LIB.T6G(SCH_1):PAGE335_I168@PURE_QUANTA.SCONN168_ME1016810202011(CHIPS)':
 'RBT_TXD0': CDS_PINID='RBT_TXD0';
NODE_NAME     U7 6
 '@T6G_MB_LIB.T6G(SCH_1):PAGE336_I2@PURE_QUANTA.74CBTLV3126PW(CHIPS)':
 '2B': CDS_PINID='\2b\';
NET_NAME
'NCSI_OCP_SFF_TXD1'
 '@T6G_MB_LIB.T6G(SCH_1):NCSI_OCP_SFF_TXD1':
 C_SIGNAL='@t6g_mb_lib.t6g(sch_1):ncsi_ocp_sff_txd1';
NODE_NAME     J38 OA8
 '@T6G_MB_LIB.T6G(SCH_1):PAGE335_I168@PURE_QUANTA.SCONN168_ME1016810202011(CHIPS)':
 'RBT_TXD1': CDS_PINID='RBT_TXD1';
NODE_NAME     U7 3
 '@T6G_MB_LIB.T6G(SCH_1):PAGE336_I2@PURE_QUANTA.74CBTLV3126PW(CHIPS)':
 '1B': CDS_PINID='\1b\';
NET_NAME
'NCSI_OCP_SFF_TX_EN'
 '@T6G_MB_LIB.T6G(SCH_1):NCSI_OCP_SFF_TX_EN':
 C_SIGNAL='@t6g_mb_lib.t6g(sch_1):ncsi_ocp_sff_tx_en';
NODE_NAME     J38 OA7
 '@T6G_MB_LIB.T6G(SCH_1):PAGE335_I168@PURE_QUANTA.SCONN168_ME1016810202011(CHIPS)':
 'RBT_TX_EN': CDS_PINID='RBT_TX_EN';
NODE_NAME     U7 8
 '@T6G_MB_LIB.T6G(SCH_1):PAGE336_I2@PURE_QUANTA.74CBTLV3126PW(CHIPS)':
 '3B': CDS_PINID='\3b\';
NET_NAME
'NCSI_OCP_V3_2_CRS_DV'
 '@T6G_MB_LIB.T6G(SCH_1):NCSI_OCP_V3_2_CRS_DV':
 C_SIGNAL='@t6g_mb_lib.t6g(sch_1):ncsi_ocp_v3_2_crs_dv';
NODE_NAME     U222 8
 '@T6G_MB_LIB.T6G(SCH_1):PAGE307_I32@PURE_QUANTA.74CBTLV3126PW(CHIPS)':
 '3B': CDS_PINID='\3b\';
NODE_NAME     J35 OB14
 '@T6G_MB_LIB.T6G(SCH_1):PAGE341_I168@PURE_QUANTA.SCONN168_ME1016810202011(CHIPS)':
 'RBT_CRS_DV': CDS_PINID='RBT_CRS_DV';
NET_NAME
'NCSI_OCP_V3_2_RXD0'
 '@T6G_MB_LIB.T6G(SCH_1):NCSI_OCP_V3_2_RXD0':
 C_SIGNAL='@t6g_mb_lib.t6g(sch_1):ncsi_ocp_v3_2_rxd0';
NODE_NAME     U222 6
 '@T6G_MB_LIB.T6G(SCH_1):PAGE307_I32@PURE_QUANTA.74CBTLV3126PW(CHIPS)':
 '2B': CDS_PINID='\2b\';
NODE_NAME     J35 OB9
 '@T6G_MB_LIB.T6G(SCH_1):PAGE341_I168@PURE_QUANTA.SCONN168_ME1016810202011(CHIPS)':
 'RBT_RXD0': CDS_PINID='RBT_RXD0';
NET_NAME
'NCSI_OCP_V3_2_RXD1'
 '@T6G_MB_LIB.T6G(SCH_1):NCSI_OCP_V3_2_RXD1':
 C_SIGNAL='@t6g_mb_lib.t6g(sch_1):ncsi_ocp_v3_2_rxd1';
NODE_NAME     U222 3
 '@T6G_MB_LIB.T6G(SCH_1):PAGE307_I32@PURE_QUANTA.74CBTLV3126PW(CHIPS)':
 '1B': CDS_PINID='\1b\';
NODE_NAME     J35 OB8
 '@T6G_MB_LIB.T6G(SCH_1):PAGE341_I168@PURE_QUANTA.SCONN168_ME1016810202011(CHIPS)':
 'RBT_RXD1': CDS_PINID='RBT_RXD1';
NET_NAME
'NCSI_OCP_V3_2_TXD0'
 '@T6G_MB_LIB.T6G(SCH_1):NCSI_OCP_V3_2_TXD0':
 C_SIGNAL='@t6g_mb_lib.t6g(sch_1):ncsi_ocp_v3_2_txd0';
NODE_NAME     U223 6
 '@T6G_MB_LIB.T6G(SCH_1):PAGE307_I78@PURE_QUANTA.74CBTLV3126PW(CHIPS)':
 '2B': CDS_PINID='\2b\';
NODE_NAME     J35 OA9
 '@T6G_MB_LIB.T6G(SCH_1):PAGE341_I168@PURE_QUANTA.SCONN168_ME1016810202011(CHIPS)':
 'RBT_TXD0': CDS_PINID='RBT_TXD0';
NET_NAME
'NCSI_OCP_V3_2_TXD1'
 '@T6G_MB_LIB.T6G(SCH_1):NCSI_OCP_V3_2_TXD1':
 C_SIGNAL='@t6g_mb_lib.t6g(sch_1):ncsi_ocp_v3_2_txd1';
NODE_NAME     U223 3
 '@T6G_MB_LIB.T6G(SCH_1):PAGE307_I78@PURE_QUANTA.74CBTLV3126PW(CHIPS)':
 '1B': CDS_PINID='\1b\';
NODE_NAME     J35 OA8
 '@T6G_MB_LIB.T6G(SCH_1):PAGE341_I168@PURE_QUANTA.SCONN168_ME1016810202011(CHIPS)':
 'RBT_TXD1': CDS_PINID='RBT_TXD1';
NET_NAME
'NCSI_OCP_V3_2_TX_EN'
 '@T6G_MB_LIB.T6G(SCH_1):NCSI_OCP_V3_2_TX_EN':
 C_SIGNAL='@t6g_mb_lib.t6g(sch_1):ncsi_ocp_v3_2_tx_en';
NODE_NAME     U223 8
 '@T6G_MB_LIB.T6G(SCH_1):PAGE307_I78@PURE_QUANTA.74CBTLV3126PW(CHIPS)':
 '3B': CDS_PINID='\3b\';
NODE_NAME     J35 OA7
 '@T6G_MB_LIB.T6G(SCH_1):PAGE341_I168@PURE_QUANTA.SCONN168_ME1016810202011(CHIPS)':
 'RBT_TX_EN': CDS_PINID='RBT_TX_EN';
NET_NAME
'NC_CPU0_AZ_BITCLK'
 '@T6G_MB_LIB.T6G(SCH_1):NC_CPU0_AZ_BITCLK':
 C_SIGNAL='@t6g_mb_lib.t6g(sch_1):nc_cpu0_az_bitclk';
NODE_NAME     U25 C32
 '@T6G_MB_LIB.T6G(SCH_1):PAGE27_I227@PURE_QUANTA.GENOA_SP5(CHIPS)':
 'AZ_BITCLK': CDS_PINID='AZ_BITCLK';
NET_NAME
'NC_CPU0_AZ_RST_N'
 '@T6G_MB_LIB.T6G(SCH_1):NC_CPU0_AZ_RST_N':
 C_SIGNAL='@t6g_mb_lib.t6g(sch_1):nc_cpu0_az_rst_n';
NODE_NAME     U25 A34
 '@T6G_MB_LIB.T6G(SCH_1):PAGE27_I227@PURE_QUANTA.GENOA_SP5(CHIPS)':
 'AZ_RST_L||SW_MDATA1': CDS_PINID='\az_rst_l||sw_mdata1\';
NET_NAME
'NC_CPU0_AZ_SDIN0'
 '@T6G_MB_LIB.T6G(SCH_1):NC_CPU0_AZ_SDIN0':
 C_SIGNAL='@t6g_mb_lib.t6g(sch_1):nc_cpu0_az_sdin0';
NODE_NAME     U25 C33
 '@T6G_MB_LIB.T6G(SCH_1):PAGE27_I227@PURE_QUANTA.GENOA_SP5(CHIPS)':
 'AZ_SDIN0||SW_MDATA3': CDS_PINID='\az_sdin0||sw_mdata3\';
NET_NAME
'NC_CPU0_AZ_SDIN1'
 '@T6G_MB_LIB.T6G(SCH_1):NC_CPU0_AZ_SDIN1':
 C_SIGNAL='@t6g_mb_lib.t6g(sch_1):nc_cpu0_az_sdin1';
NODE_NAME     U25 D33
 '@T6G_MB_LIB.T6G(SCH_1):PAGE27_I227@PURE_QUANTA.GENOA_SP5(CHIPS)':
 'AZ_SDIN1||SW_MCLK': CDS_PINID='\az_sdin1||sw_mclk\';
NET_NAME
'NC_CPU0_AZ_SDIN2'
 '@T6G_MB_LIB.T6G(SCH_1):NC_CPU0_AZ_SDIN2':
 C_SIGNAL='@t6g_mb_lib.t6g(sch_1):nc_cpu0_az_sdin2';
NODE_NAME     U25 A33
 '@T6G_MB_LIB.T6G(SCH_1):PAGE27_I227@PURE_QUANTA.GENOA_SP5(CHIPS)':
 'AZ_SDIN2||SW_MDATA0': CDS_PINID='\az_sdin2||sw_mdata0\';
NET_NAME
'NC_CPU0_AZ_SDOUT'
 '@T6G_MB_LIB.T6G(SCH_1):NC_CPU0_AZ_SDOUT':
 C_SIGNAL='@t6g_mb_lib.t6g(sch_1):nc_cpu0_az_sdout';
NODE_NAME     U25 A32
 '@T6G_MB_LIB.T6G(SCH_1):PAGE27_I227@PURE_QUANTA.GENOA_SP5(CHIPS)':
 'AZ_SDOUT||SW_MDATA2': CDS_PINID='\az_sdout||sw_mdata2\';
NET_NAME
'NC_CPU0_AZ_SYNC'
 '@T6G_MB_LIB.T6G(SCH_1):NC_CPU0_AZ_SYNC':
 C_SIGNAL='@t6g_mb_lib.t6g(sch_1):nc_cpu0_az_sync';
NODE_NAME     U25 D32
 '@T6G_MB_LIB.T6G(SCH_1):PAGE27_I227@PURE_QUANTA.GENOA_SP5(CHIPS)':
 'AZ_SYNC': CDS_PINID='AZ_SYNC';
NET_NAME
'NC_CPU0_SPI_CS2_N'
 '@T6G_MB_LIB.T6G(SCH_1):NC_CPU0_SPI_CS2_N':
 C_SIGNAL='@t6g_mb_lib.t6g(sch_1):nc_cpu0_spi_cs2_n';
NODE_NAME     U25 DH27
 '@T6G_MB_LIB.T6G(SCH_1):PAGE29_I287@PURE_QUANTA.GENOA_SP5(CHIPS)':
 'SPI_CS2_L||AGPIO126': CDS_PINID='\spi_cs2_l||agpio126\';
NET_NAME
'NC_CPU1_AZ_BITCLK'
 '@T6G_MB_LIB.T6G(SCH_1):NC_CPU1_AZ_BITCLK':
 C_SIGNAL='@t6g_mb_lib.t6g(sch_1):nc_cpu1_az_bitclk';
NODE_NAME     U26 C32
 '@T6G_MB_LIB.T6G(SCH_1):PAGE54_I190@PURE_QUANTA.GENOA_SP5(CHIPS)':
 'AZ_BITCLK': CDS_PINID='AZ_BITCLK';
NET_NAME
'NC_CPU1_AZ_RST_N'
 '@T6G_MB_LIB.T6G(SCH_1):NC_CPU1_AZ_RST_N':
 C_SIGNAL='@t6g_mb_lib.t6g(sch_1):nc_cpu1_az_rst_n';
NODE_NAME     U26 A34
 '@T6G_MB_LIB.T6G(SCH_1):PAGE54_I190@PURE_QUANTA.GENOA_SP5(CHIPS)':
 'AZ_RST_L||SW_MDATA1': CDS_PINID='\az_rst_l||sw_mdata1\';
NET_NAME
'NC_CPU1_AZ_SDIN0'
 '@T6G_MB_LIB.T6G(SCH_1):NC_CPU1_AZ_SDIN0':
 C_SIGNAL='@t6g_mb_lib.t6g(sch_1):nc_cpu1_az_sdin0';
NODE_NAME     U26 C33
 '@T6G_MB_LIB.T6G(SCH_1):PAGE54_I190@PURE_QUANTA.GENOA_SP5(CHIPS)':
 'AZ_SDIN0||SW_MDATA3': CDS_PINID='\az_sdin0||sw_mdata3\';
NET_NAME
'NC_CPU1_AZ_SDIN1'
 '@T6G_MB_LIB.T6G(SCH_1):NC_CPU1_AZ_SDIN1':
 C_SIGNAL='@t6g_mb_lib.t6g(sch_1):nc_cpu1_az_sdin1';
NODE_NAME     U26 D33
 '@T6G_MB_LIB.T6G(SCH_1):PAGE54_I190@PURE_QUANTA.GENOA_SP5(CHIPS)':
 'AZ_SDIN1||SW_MCLK': CDS_PINID='\az_sdin1||sw_mclk\';
NET_NAME
'NC_CPU1_AZ_SDIN2'
 '@T6G_MB_LIB.T6G(SCH_1):NC_CPU1_AZ_SDIN2':
 C_SIGNAL='@t6g_mb_lib.t6g(sch_1):nc_cpu1_az_sdin2';
NODE_NAME     U26 A33
 '@T6G_MB_LIB.T6G(SCH_1):PAGE54_I190@PURE_QUANTA.GENOA_SP5(CHIPS)':
 'AZ_SDIN2||SW_MDATA0': CDS_PINID='\az_sdin2||sw_mdata0\';
NET_NAME
'NC_CPU1_AZ_SDOUT'
 '@T6G_MB_LIB.T6G(SCH_1):NC_CPU1_AZ_SDOUT':
 C_SIGNAL='@t6g_mb_lib.t6g(sch_1):nc_cpu1_az_sdout';
NODE_NAME     U26 A32
 '@T6G_MB_LIB.T6G(SCH_1):PAGE54_I190@PURE_QUANTA.GENOA_SP5(CHIPS)':
 'AZ_SDOUT||SW_MDATA2': CDS_PINID='\az_sdout||sw_mdata2\';
NET_NAME
'NC_CPU1_AZ_SYNC'
 '@T6G_MB_LIB.T6G(SCH_1):NC_CPU1_AZ_SYNC':
 C_SIGNAL='@t6g_mb_lib.t6g(sch_1):nc_cpu1_az_sync';
NODE_NAME     U26 D32
 '@T6G_MB_LIB.T6G(SCH_1):PAGE54_I190@PURE_QUANTA.GENOA_SP5(CHIPS)':
 'AZ_SYNC': CDS_PINID='AZ_SYNC';
NET_NAME
'NC_CPU1_PWR_BTN_N'
 '@T6G_MB_LIB.T6G(SCH_1):NC_CPU1_PWR_BTN_N':
 C_SIGNAL='@t6g_mb_lib.t6g(sch_1):nc_cpu1_pwr_btn_n';
NODE_NAME     U26 DH7
 '@T6G_MB_LIB.T6G(SCH_1):PAGE55_I182@PURE_QUANTA.GENOA_SP5(CHIPS)':
 'PWR_BTN_L||AGPIO0': CDS_PINID='\pwr_btn_l||agpio0\';
NET_NAME
'NC_CPU1_USB00_OC_N'
 '@T6G_MB_LIB.T6G(SCH_1):NC_CPU1_USB00_OC_N':
 C_SIGNAL='@t6g_mb_lib.t6g(sch_1):nc_cpu1_usb00_oc_n';
NODE_NAME     U26 E23
 '@T6G_MB_LIB.T6G(SCH_1):PAGE56_I8@PURE_QUANTA.GENOA_SP5(CHIPS)':
 'USB00_OC_L||AGPIO264': CDS_PINID='\usb00_oc_l||agpio264\';
NET_NAME
'NC_CPU1_USB01_OC_N'
 '@T6G_MB_LIB.T6G(SCH_1):NC_CPU1_USB01_OC_N':
 C_SIGNAL='@t6g_mb_lib.t6g(sch_1):nc_cpu1_usb01_oc_n';
NODE_NAME     U26 E24
 '@T6G_MB_LIB.T6G(SCH_1):PAGE56_I8@PURE_QUANTA.GENOA_SP5(CHIPS)':
 'USB01_OC_L||AGPIO265': CDS_PINID='\usb01_oc_l||agpio265\';
NET_NAME
'NC_CPU1_USB10_OC_N'
 '@T6G_MB_LIB.T6G(SCH_1):NC_CPU1_USB10_OC_N':
 C_SIGNAL='@t6g_mb_lib.t6g(sch_1):nc_cpu1_usb10_oc_n';
NODE_NAME     U26 DG40
 '@T6G_MB_LIB.T6G(SCH_1):PAGE56_I8@PURE_QUANTA.GENOA_SP5(CHIPS)':
 'USB10_OC_L||AGPIO16': CDS_PINID='\usb10_oc_l||agpio16\';
NET_NAME
'NC_CPU1_USB11_OC_N'
 '@T6G_MB_LIB.T6G(SCH_1):NC_CPU1_USB11_OC_N':
 C_SIGNAL='@t6g_mb_lib.t6g(sch_1):nc_cpu1_usb11_oc_n';
NODE_NAME     U26 DH40
 '@T6G_MB_LIB.T6G(SCH_1):PAGE56_I8@PURE_QUANTA.GENOA_SP5(CHIPS)':
 'USB11_OC_L||AGPIO17': CDS_PINID='\usb11_oc_l||agpio17\';
NET_NAME
'NC_CPU1_USB2_USB00_DN'
 '@T6G_MB_LIB.T6G(SCH_1):NC_CPU1_USB2_USB00_DN':
 C_SIGNAL='@t6g_mb_lib.t6g(sch_1):nc_cpu1_usb2_usb00_dn';
NODE_NAME     U26 A25
 '@T6G_MB_LIB.T6G(SCH_1):PAGE56_I8@PURE_QUANTA.GENOA_SP5(CHIPS)':
 'USB00_DN': CDS_PINID='USB00_DN';
NET_NAME
'NC_CPU1_USB2_USB00_DP'
 '@T6G_MB_LIB.T6G(SCH_1):NC_CPU1_USB2_USB00_DP':
 C_SIGNAL='@t6g_mb_lib.t6g(sch_1):nc_cpu1_usb2_usb00_dp';
NODE_NAME     U26 A26
 '@T6G_MB_LIB.T6G(SCH_1):PAGE56_I8@PURE_QUANTA.GENOA_SP5(CHIPS)':
 'USB00_DP': CDS_PINID='USB00_DP';
NET_NAME
'NC_CPU1_USB2_USB01_DN'
 '@T6G_MB_LIB.T6G(SCH_1):NC_CPU1_USB2_USB01_DN':
 C_SIGNAL='@t6g_mb_lib.t6g(sch_1):nc_cpu1_usb2_usb01_dn';
NODE_NAME     U26 A29
 '@T6G_MB_LIB.T6G(SCH_1):PAGE56_I8@PURE_QUANTA.GENOA_SP5(CHIPS)':
 'USB01_DN': CDS_PINID='USB01_DN';
NET_NAME
'NC_CPU1_USB2_USB01_DP'
 '@T6G_MB_LIB.T6G(SCH_1):NC_CPU1_USB2_USB01_DP':
 C_SIGNAL='@t6g_mb_lib.t6g(sch_1):nc_cpu1_usb2_usb01_dp';
NODE_NAME     U26 A28
 '@T6G_MB_LIB.T6G(SCH_1):PAGE56_I8@PURE_QUANTA.GENOA_SP5(CHIPS)':
 'USB01_DP': CDS_PINID='USB01_DP';
NET_NAME
'NC_CPU1_USB2_USB10_DN'
 '@T6G_MB_LIB.T6G(SCH_1):NC_CPU1_USB2_USB10_DN':
 C_SIGNAL='@t6g_mb_lib.t6g(sch_1):nc_cpu1_usb2_usb10_dn';
NODE_NAME     U26 DH67
 '@T6G_MB_LIB.T6G(SCH_1):PAGE56_I8@PURE_QUANTA.GENOA_SP5(CHIPS)':
 'USB10_DN': CDS_PINID='USB10_DN';
NET_NAME
'NC_CPU1_USB2_USB10_DP'
 '@T6G_MB_LIB.T6G(SCH_1):NC_CPU1_USB2_USB10_DP':
 C_SIGNAL='@t6g_mb_lib.t6g(sch_1):nc_cpu1_usb2_usb10_dp';
NODE_NAME     U26 DJ67
 '@T6G_MB_LIB.T6G(SCH_1):PAGE56_I8@PURE_QUANTA.GENOA_SP5(CHIPS)':
 'USB10_DP': CDS_PINID='USB10_DP';
NET_NAME
'NC_CPU1_USB2_USB11_DN'
 '@T6G_MB_LIB.T6G(SCH_1):NC_CPU1_USB2_USB11_DN':
 C_SIGNAL='@t6g_mb_lib.t6g(sch_1):nc_cpu1_usb2_usb11_dn';
NODE_NAME     U26 DJ60
 '@T6G_MB_LIB.T6G(SCH_1):PAGE56_I8@PURE_QUANTA.GENOA_SP5(CHIPS)':
 'USB11_DN': CDS_PINID='USB11_DN';
NET_NAME
'NC_CPU1_USB2_USB11_DP'
 '@T6G_MB_LIB.T6G(SCH_1):NC_CPU1_USB2_USB11_DP':
 C_SIGNAL='@t6g_mb_lib.t6g(sch_1):nc_cpu1_usb2_usb11_dp';
NODE_NAME     U26 DH60
 '@T6G_MB_LIB.T6G(SCH_1):PAGE56_I8@PURE_QUANTA.GENOA_SP5(CHIPS)':
 'USB11_DP': CDS_PINID='USB11_DP';
NET_NAME
'NC_CPU1_USB3_USB00_RXN'
 '@T6G_MB_LIB.T6G(SCH_1):NC_CPU1_USB3_USB00_RXN':
 C_SIGNAL='@t6g_mb_lib.t6g(sch_1):nc_cpu1_usb3_usb00_rxn';
NODE_NAME     U26 E26
 '@T6G_MB_LIB.T6G(SCH_1):PAGE56_I8@PURE_QUANTA.GENOA_SP5(CHIPS)':
 'USB00_RXN': CDS_PINID='USB00_RXN';
NET_NAME
'NC_CPU1_USB3_USB00_RXP'
 '@T6G_MB_LIB.T6G(SCH_1):NC_CPU1_USB3_USB00_RXP':
 C_SIGNAL='@t6g_mb_lib.t6g(sch_1):nc_cpu1_usb3_usb00_rxp';
NODE_NAME     U26 E27
 '@T6G_MB_LIB.T6G(SCH_1):PAGE56_I8@PURE_QUANTA.GENOA_SP5(CHIPS)':
 'USB00_RXP': CDS_PINID='USB00_RXP';
NET_NAME
'NC_CPU1_USB3_USB00_TXN'
 '@T6G_MB_LIB.T6G(SCH_1):NC_CPU1_USB3_USB00_TXN':
 C_SIGNAL='@t6g_mb_lib.t6g(sch_1):nc_cpu1_usb3_usb00_txn';
NODE_NAME     U26 C25
 '@T6G_MB_LIB.T6G(SCH_1):PAGE56_I8@PURE_QUANTA.GENOA_SP5(CHIPS)':
 'USB00_TXP': CDS_PINID='USB00_TXP';
NET_NAME
'NC_CPU1_USB3_USB00_TXP'
 '@T6G_MB_LIB.T6G(SCH_1):NC_CPU1_USB3_USB00_TXP':
 C_SIGNAL='@t6g_mb_lib.t6g(sch_1):nc_cpu1_usb3_usb00_txp';
NODE_NAME     U26 C26
 '@T6G_MB_LIB.T6G(SCH_1):PAGE56_I8@PURE_QUANTA.GENOA_SP5(CHIPS)':
 'USB00_TXN': CDS_PINID='USB00_TXN';
NET_NAME
'NC_CPU1_USB3_USB01_RXN'
 '@T6G_MB_LIB.T6G(SCH_1):NC_CPU1_USB3_USB01_RXN':
 C_SIGNAL='@t6g_mb_lib.t6g(sch_1):nc_cpu1_usb3_usb01_rxn';
NODE_NAME     U26 C28
 '@T6G_MB_LIB.T6G(SCH_1):PAGE56_I8@PURE_QUANTA.GENOA_SP5(CHIPS)':
 'USB01_RXN': CDS_PINID='USB01_RXN';
NET_NAME
'NC_CPU1_USB3_USB01_RXP'
 '@T6G_MB_LIB.T6G(SCH_1):NC_CPU1_USB3_USB01_RXP':
 C_SIGNAL='@t6g_mb_lib.t6g(sch_1):nc_cpu1_usb3_usb01_rxp';
NODE_NAME     U26 C29
 '@T6G_MB_LIB.T6G(SCH_1):PAGE56_I8@PURE_QUANTA.GENOA_SP5(CHIPS)':
 'USB01_RXP': CDS_PINID='USB01_RXP';
NET_NAME
'NC_CPU1_USB3_USB01_TXN'
 '@T6G_MB_LIB.T6G(SCH_1):NC_CPU1_USB3_USB01_TXN':
 C_SIGNAL='@t6g_mb_lib.t6g(sch_1):nc_cpu1_usb3_usb01_txn';
NODE_NAME     U26 E29
 '@T6G_MB_LIB.T6G(SCH_1):PAGE56_I8@PURE_QUANTA.GENOA_SP5(CHIPS)':
 'USB01_TXN': CDS_PINID='USB01_TXN';
NET_NAME
'NC_CPU1_USB3_USB01_TXP'
 '@T6G_MB_LIB.T6G(SCH_1):NC_CPU1_USB3_USB01_TXP':
 C_SIGNAL='@t6g_mb_lib.t6g(sch_1):nc_cpu1_usb3_usb01_txp';
NODE_NAME     U26 E30
 '@T6G_MB_LIB.T6G(SCH_1):PAGE56_I8@PURE_QUANTA.GENOA_SP5(CHIPS)':
 'USB01_TXP': CDS_PINID='USB01_TXP';
NET_NAME
'NC_CPU1_USB3_USB10_RXN'
 '@T6G_MB_LIB.T6G(SCH_1):NC_CPU1_USB3_USB10_RXN':
 C_SIGNAL='@t6g_mb_lib.t6g(sch_1):nc_cpu1_usb3_usb10_rxn';
NODE_NAME     U26 DH65
 '@T6G_MB_LIB.T6G(SCH_1):PAGE56_I8@PURE_QUANTA.GENOA_SP5(CHIPS)':
 'USB10_RXN': CDS_PINID='USB10_RXN';
NET_NAME
'NC_CPU1_USB3_USB10_RXP'
 '@T6G_MB_LIB.T6G(SCH_1):NC_CPU1_USB3_USB10_RXP':
 C_SIGNAL='@t6g_mb_lib.t6g(sch_1):nc_cpu1_usb3_usb10_rxp';
NODE_NAME     U26 DJ65
 '@T6G_MB_LIB.T6G(SCH_1):PAGE56_I8@PURE_QUANTA.GENOA_SP5(CHIPS)':
 'USB10_RXP': CDS_PINID='USB10_RXP';
NET_NAME
'NC_CPU1_USB3_USB10_TXN'
 '@T6G_MB_LIB.T6G(SCH_1):NC_CPU1_USB3_USB10_TXN':
 C_SIGNAL='@t6g_mb_lib.t6g(sch_1):nc_cpu1_usb3_usb10_txn';
NODE_NAME     U26 DJ69
 '@T6G_MB_LIB.T6G(SCH_1):PAGE56_I8@PURE_QUANTA.GENOA_SP5(CHIPS)':
 'USB10_TXN': CDS_PINID='USB10_TXN';
NET_NAME
'NC_CPU1_USB3_USB10_TXP'
 '@T6G_MB_LIB.T6G(SCH_1):NC_CPU1_USB3_USB10_TXP':
 C_SIGNAL='@t6g_mb_lib.t6g(sch_1):nc_cpu1_usb3_usb10_txp';
NODE_NAME     U26 DH69
 '@T6G_MB_LIB.T6G(SCH_1):PAGE56_I8@PURE_QUANTA.GENOA_SP5(CHIPS)':
 'USB10_TXP': CDS_PINID='USB10_TXP';
NET_NAME
'NC_CPU1_USB3_USB11_RXN'
 '@T6G_MB_LIB.T6G(SCH_1):NC_CPU1_USB3_USB11_RXN':
 C_SIGNAL='@t6g_mb_lib.t6g(sch_1):nc_cpu1_usb3_usb11_rxn';
NODE_NAME     U26 DH62
 '@T6G_MB_LIB.T6G(SCH_1):PAGE56_I8@PURE_QUANTA.GENOA_SP5(CHIPS)':
 'USB11_RXN': CDS_PINID='USB11_RXN';
NET_NAME
'NC_CPU1_USB3_USB11_RXP'
 '@T6G_MB_LIB.T6G(SCH_1):NC_CPU1_USB3_USB11_RXP':
 C_SIGNAL='@t6g_mb_lib.t6g(sch_1):nc_cpu1_usb3_usb11_rxp';
NODE_NAME     U26 DJ62
 '@T6G_MB_LIB.T6G(SCH_1):PAGE56_I8@PURE_QUANTA.GENOA_SP5(CHIPS)':
 'USB11_RXP': CDS_PINID='USB11_RXP';
NET_NAME
'NC_CPU1_USB3_USB11_TXN'
 '@T6G_MB_LIB.T6G(SCH_1):NC_CPU1_USB3_USB11_TXN':
 C_SIGNAL='@t6g_mb_lib.t6g(sch_1):nc_cpu1_usb3_usb11_txn';
NODE_NAME     U26 DH58
 '@T6G_MB_LIB.T6G(SCH_1):PAGE56_I8@PURE_QUANTA.GENOA_SP5(CHIPS)':
 'USB11_TXN': CDS_PINID='USB11_TXN';
NET_NAME
'NC_CPU1_USB3_USB11_TXP'
 '@T6G_MB_LIB.T6G(SCH_1):NC_CPU1_USB3_USB11_TXP':
 C_SIGNAL='@t6g_mb_lib.t6g(sch_1):nc_cpu1_usb3_usb11_txp';
NODE_NAME     U26 DG58
 '@T6G_MB_LIB.T6G(SCH_1):PAGE56_I8@PURE_QUANTA.GENOA_SP5(CHIPS)':
 'USB11_TXP': CDS_PINID='USB11_TXP';
NET_NAME
'NC_HICCUP'
 '@T6G_MB_LIB.T6G(SCH_1):NC_HICCUP':
 C_SIGNAL='@t6g_mb_lib.t6g(sch_1):nc_hiccup';
NODE_NAME     PU9 35
 '@T6G_MB_LIB.T6G(SCH_1):PAGE245_I21@PURE_QUANTA.NCP3284AMNTXG(CHIPS)':
 'HICCUP#': CDS_PINID='\hiccup#\';
NET_NAME
'NC_HSC_TYPE_NC0'
 '@T6G_MB_LIB.T6G(SCH_1):NC_HSC_TYPE_NC0':
 C_SIGNAL='@t6g_mb_lib.t6g(sch_1):nc_hsc_type_nc0';
NODE_NAME     U6005 6
 '@T6G_MB_LIB.T6G(SCH_1):PAGE271_I28@PURE_QUANTA.ISL28022FRZT(CHIPS)':
 'NC0': CDS_PINID='NC0';
NET_NAME
'NC_HSC_TYPE_NC1'
 '@T6G_MB_LIB.T6G(SCH_1):NC_HSC_TYPE_NC1':
 C_SIGNAL='@t6g_mb_lib.t6g(sch_1):nc_hsc_type_nc1';
NODE_NAME     U6005 7
 '@T6G_MB_LIB.T6G(SCH_1):PAGE271_I28@PURE_QUANTA.ISL28022FRZT(CHIPS)':
 'NC1': CDS_PINID='NC1';
NET_NAME
'NC_HSC_TYPE_NC2'
 '@T6G_MB_LIB.T6G(SCH_1):NC_HSC_TYPE_NC2':
 C_SIGNAL='@t6g_mb_lib.t6g(sch_1):nc_hsc_type_nc2';
NODE_NAME     U6005 8
 '@T6G_MB_LIB.T6G(SCH_1):PAGE271_I28@PURE_QUANTA.ISL28022FRZT(CHIPS)':
 'NC2': CDS_PINID='NC2';
NET_NAME
'NC_HSC_TYPE_NC3'
 '@T6G_MB_LIB.T6G(SCH_1):NC_HSC_TYPE_NC3':
 C_SIGNAL='@t6g_mb_lib.t6g(sch_1):nc_hsc_type_nc3';
NODE_NAME     U6005 14
 '@T6G_MB_LIB.T6G(SCH_1):PAGE271_I28@PURE_QUANTA.ISL28022FRZT(CHIPS)':
 'NC3': CDS_PINID='NC3';
NET_NAME
'NC_HSC_TYPE_NC4'
 '@T6G_MB_LIB.T6G(SCH_1):NC_HSC_TYPE_NC4':
 C_SIGNAL='@t6g_mb_lib.t6g(sch_1):nc_hsc_type_nc4';
NODE_NAME     U6005 15
 '@T6G_MB_LIB.T6G(SCH_1):PAGE271_I28@PURE_QUANTA.ISL28022FRZT(CHIPS)':
 'NC4': CDS_PINID='NC4';
NET_NAME
'NC_HSC_TYPE_NC5'
 '@T6G_MB_LIB.T6G(SCH_1):NC_HSC_TYPE_NC5':
 C_SIGNAL='@t6g_mb_lib.t6g(sch_1):nc_hsc_type_nc5';
NODE_NAME     U6005 16
 '@T6G_MB_LIB.T6G(SCH_1):PAGE271_I28@PURE_QUANTA.ISL28022FRZT(CHIPS)':
 'NC5': CDS_PINID='NC5';
NET_NAME
'NC_HSC_TYPE_VINM'
 '@T6G_MB_LIB.T6G(SCH_1):NC_HSC_TYPE_VINM':
 C_SIGNAL='@t6g_mb_lib.t6g(sch_1):nc_hsc_type_vinm';
NODE_NAME     U6005 12
 '@T6G_MB_LIB.T6G(SCH_1):PAGE271_I28@PURE_QUANTA.ISL28022FRZT(CHIPS)':
 'VINM': CDS_PINID='VINM';
NET_NAME
'NC_HSC_TYPE_VINP'
 '@T6G_MB_LIB.T6G(SCH_1):NC_HSC_TYPE_VINP':
 C_SIGNAL='@t6g_mb_lib.t6g(sch_1):nc_hsc_type_vinp';
NODE_NAME     U6005 13
 '@T6G_MB_LIB.T6G(SCH_1):PAGE271_I28@PURE_QUANTA.ISL28022FRZT(CHIPS)':
 'VINP': CDS_PINID='VINP';
NET_NAME
'NC_INA230_1_NC0'
 '@T6G_MB_LIB.T6G(SCH_1):NC_INA230_1_NC0':
 C_SIGNAL='@t6g_mb_lib.t6g(sch_1):nc_ina230_1_nc0';
NODE_NAME     U266 6
 '@T6G_MB_LIB.T6G(SCH_1):PAGE295_I30@PURE_QUANTA.ISL28022FRZT(CHIPS)':
 'NC0': CDS_PINID='NC0';
NET_NAME
'NC_INA230_1_NC1'
 '@T6G_MB_LIB.T6G(SCH_1):NC_INA230_1_NC1':
 C_SIGNAL='@t6g_mb_lib.t6g(sch_1):nc_ina230_1_nc1';
NODE_NAME     U266 7
 '@T6G_MB_LIB.T6G(SCH_1):PAGE295_I30@PURE_QUANTA.ISL28022FRZT(CHIPS)':
 'NC1': CDS_PINID='NC1';
NET_NAME
'NC_INA230_1_NC2'
 '@T6G_MB_LIB.T6G(SCH_1):NC_INA230_1_NC2':
 C_SIGNAL='@t6g_mb_lib.t6g(sch_1):nc_ina230_1_nc2';
NODE_NAME     U266 8
 '@T6G_MB_LIB.T6G(SCH_1):PAGE295_I30@PURE_QUANTA.ISL28022FRZT(CHIPS)':
 'NC2': CDS_PINID='NC2';
NET_NAME
'NC_INA230_1_NC3'
 '@T6G_MB_LIB.T6G(SCH_1):NC_INA230_1_NC3':
 C_SIGNAL='@t6g_mb_lib.t6g(sch_1):nc_ina230_1_nc3';
NODE_NAME     U266 14
 '@T6G_MB_LIB.T6G(SCH_1):PAGE295_I30@PURE_QUANTA.ISL28022FRZT(CHIPS)':
 'NC3': CDS_PINID='NC3';
NET_NAME
'NC_INA230_1_NC4'
 '@T6G_MB_LIB.T6G(SCH_1):NC_INA230_1_NC4':
 C_SIGNAL='@t6g_mb_lib.t6g(sch_1):nc_ina230_1_nc4';
NODE_NAME     U266 15
 '@T6G_MB_LIB.T6G(SCH_1):PAGE295_I30@PURE_QUANTA.ISL28022FRZT(CHIPS)':
 'NC4': CDS_PINID='NC4';
NET_NAME
'NC_INA230_1_NC5'
 '@T6G_MB_LIB.T6G(SCH_1):NC_INA230_1_NC5':
 C_SIGNAL='@t6g_mb_lib.t6g(sch_1):nc_ina230_1_nc5';
NODE_NAME     U266 16
 '@T6G_MB_LIB.T6G(SCH_1):PAGE295_I30@PURE_QUANTA.ISL28022FRZT(CHIPS)':
 'NC5': CDS_PINID='NC5';
NET_NAME
'NC_INA230_2_NC0'
 '@T6G_MB_LIB.T6G(SCH_1):NC_INA230_2_NC0':
 C_SIGNAL='@t6g_mb_lib.t6g(sch_1):nc_ina230_2_nc0';
NODE_NAME     U276 6
 '@T6G_MB_LIB.T6G(SCH_1):PAGE295_I129@PURE_QUANTA.ISL28022FRZT(CHIPS)':
 'NC0': CDS_PINID='NC0';
NET_NAME
'NC_INA230_2_NC1'
 '@T6G_MB_LIB.T6G(SCH_1):NC_INA230_2_NC1':
 C_SIGNAL='@t6g_mb_lib.t6g(sch_1):nc_ina230_2_nc1';
NODE_NAME     U276 7
 '@T6G_MB_LIB.T6G(SCH_1):PAGE295_I129@PURE_QUANTA.ISL28022FRZT(CHIPS)':
 'NC1': CDS_PINID='NC1';
NET_NAME
'NC_INA230_2_NC2'
 '@T6G_MB_LIB.T6G(SCH_1):NC_INA230_2_NC2':
 C_SIGNAL='@t6g_mb_lib.t6g(sch_1):nc_ina230_2_nc2';
NODE_NAME     U276 8
 '@T6G_MB_LIB.T6G(SCH_1):PAGE295_I129@PURE_QUANTA.ISL28022FRZT(CHIPS)':
 'NC2': CDS_PINID='NC2';
NET_NAME
'NC_INA230_2_NC3'
 '@T6G_MB_LIB.T6G(SCH_1):NC_INA230_2_NC3':
 C_SIGNAL='@t6g_mb_lib.t6g(sch_1):nc_ina230_2_nc3';
NODE_NAME     U276 14
 '@T6G_MB_LIB.T6G(SCH_1):PAGE295_I129@PURE_QUANTA.ISL28022FRZT(CHIPS)':
 'NC3': CDS_PINID='NC3';
NET_NAME
'NC_INA230_2_NC4'
 '@T6G_MB_LIB.T6G(SCH_1):NC_INA230_2_NC4':
 C_SIGNAL='@t6g_mb_lib.t6g(sch_1):nc_ina230_2_nc4';
NODE_NAME     U276 15
 '@T6G_MB_LIB.T6G(SCH_1):PAGE295_I129@PURE_QUANTA.ISL28022FRZT(CHIPS)':
 'NC4': CDS_PINID='NC4';
NET_NAME
'NC_INA230_2_NC5'
 '@T6G_MB_LIB.T6G(SCH_1):NC_INA230_2_NC5':
 C_SIGNAL='@t6g_mb_lib.t6g(sch_1):nc_ina230_2_nc5';
NODE_NAME     U276 16
 '@T6G_MB_LIB.T6G(SCH_1):PAGE295_I129@PURE_QUANTA.ISL28022FRZT(CHIPS)':
 'NC5': CDS_PINID='NC5';
NET_NAME
'NC_INA230_3_NC0'
 '@T6G_MB_LIB.T6G(SCH_1):NC_INA230_3_NC0':
 C_SIGNAL='@t6g_mb_lib.t6g(sch_1):nc_ina230_3_nc0';
NODE_NAME     U263 6
 '@T6G_MB_LIB.T6G(SCH_1):PAGE360_I94@PURE_QUANTA.ISL28022FRZT(CHIPS)':
 'NC0': CDS_PINID='NC0';
NET_NAME
'NC_INA230_3_NC1'
 '@T6G_MB_LIB.T6G(SCH_1):NC_INA230_3_NC1':
 C_SIGNAL='@t6g_mb_lib.t6g(sch_1):nc_ina230_3_nc1';
NODE_NAME     U263 7
 '@T6G_MB_LIB.T6G(SCH_1):PAGE360_I94@PURE_QUANTA.ISL28022FRZT(CHIPS)':
 'NC1': CDS_PINID='NC1';
NET_NAME
'NC_INA230_3_NC2'
 '@T6G_MB_LIB.T6G(SCH_1):NC_INA230_3_NC2':
 C_SIGNAL='@t6g_mb_lib.t6g(sch_1):nc_ina230_3_nc2';
NODE_NAME     U263 8
 '@T6G_MB_LIB.T6G(SCH_1):PAGE360_I94@PURE_QUANTA.ISL28022FRZT(CHIPS)':
 'NC2': CDS_PINID='NC2';
NET_NAME
'NC_INA230_3_NC3'
 '@T6G_MB_LIB.T6G(SCH_1):NC_INA230_3_NC3':
 C_SIGNAL='@t6g_mb_lib.t6g(sch_1):nc_ina230_3_nc3';
NODE_NAME     U263 14
 '@T6G_MB_LIB.T6G(SCH_1):PAGE360_I94@PURE_QUANTA.ISL28022FRZT(CHIPS)':
 'NC3': CDS_PINID='NC3';
NET_NAME
'NC_INA230_3_NC4'
 '@T6G_MB_LIB.T6G(SCH_1):NC_INA230_3_NC4':
 C_SIGNAL='@t6g_mb_lib.t6g(sch_1):nc_ina230_3_nc4';
NODE_NAME     U263 15
 '@T6G_MB_LIB.T6G(SCH_1):PAGE360_I94@PURE_QUANTA.ISL28022FRZT(CHIPS)':
 'NC4': CDS_PINID='NC4';
NET_NAME
'NC_INA230_3_NC5'
 '@T6G_MB_LIB.T6G(SCH_1):NC_INA230_3_NC5':
 C_SIGNAL='@t6g_mb_lib.t6g(sch_1):nc_ina230_3_nc5';
NODE_NAME     U263 16
 '@T6G_MB_LIB.T6G(SCH_1):PAGE360_I94@PURE_QUANTA.ISL28022FRZT(CHIPS)':
 'NC5': CDS_PINID='NC5';
NET_NAME
'NC_INA230_4_NC0'
 '@T6G_MB_LIB.T6G(SCH_1):NC_INA230_4_NC0':
 C_SIGNAL='@t6g_mb_lib.t6g(sch_1):nc_ina230_4_nc0';
NODE_NAME     U264 6
 '@T6G_MB_LIB.T6G(SCH_1):PAGE360_I46@PURE_QUANTA.ISL28022FRZT(CHIPS)':
 'NC0': CDS_PINID='NC0';
NET_NAME
'NC_INA230_4_NC1'
 '@T6G_MB_LIB.T6G(SCH_1):NC_INA230_4_NC1':
 C_SIGNAL='@t6g_mb_lib.t6g(sch_1):nc_ina230_4_nc1';
NODE_NAME     U264 7
 '@T6G_MB_LIB.T6G(SCH_1):PAGE360_I46@PURE_QUANTA.ISL28022FRZT(CHIPS)':
 'NC1': CDS_PINID='NC1';
NET_NAME
'NC_INA230_4_NC2'
 '@T6G_MB_LIB.T6G(SCH_1):NC_INA230_4_NC2':
 C_SIGNAL='@t6g_mb_lib.t6g(sch_1):nc_ina230_4_nc2';
NODE_NAME     U264 8
 '@T6G_MB_LIB.T6G(SCH_1):PAGE360_I46@PURE_QUANTA.ISL28022FRZT(CHIPS)':
 'NC2': CDS_PINID='NC2';
NET_NAME
'NC_INA230_4_NC3'
 '@T6G_MB_LIB.T6G(SCH_1):NC_INA230_4_NC3':
 C_SIGNAL='@t6g_mb_lib.t6g(sch_1):nc_ina230_4_nc3';
NODE_NAME     U264 14
 '@T6G_MB_LIB.T6G(SCH_1):PAGE360_I46@PURE_QUANTA.ISL28022FRZT(CHIPS)':
 'NC3': CDS_PINID='NC3';
NET_NAME
'NC_INA230_4_NC4'
 '@T6G_MB_LIB.T6G(SCH_1):NC_INA230_4_NC4':
 C_SIGNAL='@t6g_mb_lib.t6g(sch_1):nc_ina230_4_nc4';
NODE_NAME     U264 15
 '@T6G_MB_LIB.T6G(SCH_1):PAGE360_I46@PURE_QUANTA.ISL28022FRZT(CHIPS)':
 'NC4': CDS_PINID='NC4';
NET_NAME
'NC_INA230_4_NC5'
 '@T6G_MB_LIB.T6G(SCH_1):NC_INA230_4_NC5':
 C_SIGNAL='@t6g_mb_lib.t6g(sch_1):nc_ina230_4_nc5';
NODE_NAME     U264 16
 '@T6G_MB_LIB.T6G(SCH_1):PAGE360_I46@PURE_QUANTA.ISL28022FRZT(CHIPS)':
 'NC5': CDS_PINID='NC5';
NET_NAME
'NC_INA230_5_NC0'
 '@T6G_MB_LIB.T6G(SCH_1):NC_INA230_5_NC0':
 C_SIGNAL='@t6g_mb_lib.t6g(sch_1):nc_ina230_5_nc0';
NODE_NAME     U265 6
 '@T6G_MB_LIB.T6G(SCH_1):PAGE360_I69@PURE_QUANTA.ISL28022FRZT(CHIPS)':
 'NC0': CDS_PINID='NC0';
NET_NAME
'NC_INA230_5_NC1'
 '@T6G_MB_LIB.T6G(SCH_1):NC_INA230_5_NC1':
 C_SIGNAL='@t6g_mb_lib.t6g(sch_1):nc_ina230_5_nc1';
NODE_NAME     U265 7
 '@T6G_MB_LIB.T6G(SCH_1):PAGE360_I69@PURE_QUANTA.ISL28022FRZT(CHIPS)':
 'NC1': CDS_PINID='NC1';
NET_NAME
'NC_INA230_5_NC2'
 '@T6G_MB_LIB.T6G(SCH_1):NC_INA230_5_NC2':
 C_SIGNAL='@t6g_mb_lib.t6g(sch_1):nc_ina230_5_nc2';
NODE_NAME     U265 8
 '@T6G_MB_LIB.T6G(SCH_1):PAGE360_I69@PURE_QUANTA.ISL28022FRZT(CHIPS)':
 'NC2': CDS_PINID='NC2';
NET_NAME
'NC_INA230_5_NC3'
 '@T6G_MB_LIB.T6G(SCH_1):NC_INA230_5_NC3':
 C_SIGNAL='@t6g_mb_lib.t6g(sch_1):nc_ina230_5_nc3';
NODE_NAME     U265 14
 '@T6G_MB_LIB.T6G(SCH_1):PAGE360_I69@PURE_QUANTA.ISL28022FRZT(CHIPS)':
 'NC3': CDS_PINID='NC3';
NET_NAME
'NC_INA230_5_NC4'
 '@T6G_MB_LIB.T6G(SCH_1):NC_INA230_5_NC4':
 C_SIGNAL='@t6g_mb_lib.t6g(sch_1):nc_ina230_5_nc4';
NODE_NAME     U265 15
 '@T6G_MB_LIB.T6G(SCH_1):PAGE360_I69@PURE_QUANTA.ISL28022FRZT(CHIPS)':
 'NC4': CDS_PINID='NC4';
NET_NAME
'NC_INA230_5_NC5'
 '@T6G_MB_LIB.T6G(SCH_1):NC_INA230_5_NC5':
 C_SIGNAL='@t6g_mb_lib.t6g(sch_1):nc_ina230_5_nc5';
NODE_NAME     U265 16
 '@T6G_MB_LIB.T6G(SCH_1):PAGE360_I69@PURE_QUANTA.ISL28022FRZT(CHIPS)':
 'NC5': CDS_PINID='NC5';
NET_NAME
'NC_INA230_6_NC0'
 '@T6G_MB_LIB.T6G(SCH_1):NC_INA230_6_NC0':
 C_SIGNAL='@t6g_mb_lib.t6g(sch_1):nc_ina230_6_nc0';
NODE_NAME     U55 6
 '@T6G_MB_LIB.T6G(SCH_1):PAGE466_I28@PURE_QUANTA.ISL28022FRZT(CHIPS)':
 'NC0': CDS_PINID='NC0';
NET_NAME
'NC_INA230_6_NC1'
 '@T6G_MB_LIB.T6G(SCH_1):NC_INA230_6_NC1':
 C_SIGNAL='@t6g_mb_lib.t6g(sch_1):nc_ina230_6_nc1';
NODE_NAME     U55 7
 '@T6G_MB_LIB.T6G(SCH_1):PAGE466_I28@PURE_QUANTA.ISL28022FRZT(CHIPS)':
 'NC1': CDS_PINID='NC1';
NET_NAME
'NC_INA230_6_NC2'
 '@T6G_MB_LIB.T6G(SCH_1):NC_INA230_6_NC2':
 C_SIGNAL='@t6g_mb_lib.t6g(sch_1):nc_ina230_6_nc2';
NODE_NAME     U55 8
 '@T6G_MB_LIB.T6G(SCH_1):PAGE466_I28@PURE_QUANTA.ISL28022FRZT(CHIPS)':
 'NC2': CDS_PINID='NC2';
NET_NAME
'NC_INA230_6_NC3'
 '@T6G_MB_LIB.T6G(SCH_1):NC_INA230_6_NC3':
 C_SIGNAL='@t6g_mb_lib.t6g(sch_1):nc_ina230_6_nc3';
NODE_NAME     U55 14
 '@T6G_MB_LIB.T6G(SCH_1):PAGE466_I28@PURE_QUANTA.ISL28022FRZT(CHIPS)':
 'NC3': CDS_PINID='NC3';
NET_NAME
'NC_INA230_6_NC4'
 '@T6G_MB_LIB.T6G(SCH_1):NC_INA230_6_NC4':
 C_SIGNAL='@t6g_mb_lib.t6g(sch_1):nc_ina230_6_nc4';
NODE_NAME     U55 15
 '@T6G_MB_LIB.T6G(SCH_1):PAGE466_I28@PURE_QUANTA.ISL28022FRZT(CHIPS)':
 'NC4': CDS_PINID='NC4';
NET_NAME
'NC_INA230_6_NC5'
 '@T6G_MB_LIB.T6G(SCH_1):NC_INA230_6_NC5':
 C_SIGNAL='@t6g_mb_lib.t6g(sch_1):nc_ina230_6_nc5';
NODE_NAME     U55 16
 '@T6G_MB_LIB.T6G(SCH_1):PAGE466_I28@PURE_QUANTA.ISL28022FRZT(CHIPS)':
 'NC5': CDS_PINID='NC5';
NET_NAME
'NC_INA230_7_NC0'
 '@T6G_MB_LIB.T6G(SCH_1):NC_INA230_7_NC0':
 C_SIGNAL='@t6g_mb_lib.t6g(sch_1):nc_ina230_7_nc0';
NODE_NAME     U56 6
 '@T6G_MB_LIB.T6G(SCH_1):PAGE466_I29@PURE_QUANTA.ISL28022FRZT(CHIPS)':
 'NC0': CDS_PINID='NC0';
NET_NAME
'NC_INA230_7_NC1'
 '@T6G_MB_LIB.T6G(SCH_1):NC_INA230_7_NC1':
 C_SIGNAL='@t6g_mb_lib.t6g(sch_1):nc_ina230_7_nc1';
NODE_NAME     U56 7
 '@T6G_MB_LIB.T6G(SCH_1):PAGE466_I29@PURE_QUANTA.ISL28022FRZT(CHIPS)':
 'NC1': CDS_PINID='NC1';
NET_NAME
'NC_INA230_7_NC2'
 '@T6G_MB_LIB.T6G(SCH_1):NC_INA230_7_NC2':
 C_SIGNAL='@t6g_mb_lib.t6g(sch_1):nc_ina230_7_nc2';
NODE_NAME     U56 8
 '@T6G_MB_LIB.T6G(SCH_1):PAGE466_I29@PURE_QUANTA.ISL28022FRZT(CHIPS)':
 'NC2': CDS_PINID='NC2';
NET_NAME
'NC_INA230_7_NC3'
 '@T6G_MB_LIB.T6G(SCH_1):NC_INA230_7_NC3':
 C_SIGNAL='@t6g_mb_lib.t6g(sch_1):nc_ina230_7_nc3';
NODE_NAME     U56 14
 '@T6G_MB_LIB.T6G(SCH_1):PAGE466_I29@PURE_QUANTA.ISL28022FRZT(CHIPS)':
 'NC3': CDS_PINID='NC3';
NET_NAME
'NC_INA230_7_NC4'
 '@T6G_MB_LIB.T6G(SCH_1):NC_INA230_7_NC4':
 C_SIGNAL='@t6g_mb_lib.t6g(sch_1):nc_ina230_7_nc4';
NODE_NAME     U56 15
 '@T6G_MB_LIB.T6G(SCH_1):PAGE466_I29@PURE_QUANTA.ISL28022FRZT(CHIPS)':
 'NC4': CDS_PINID='NC4';
NET_NAME
'NC_INA230_7_NC5'
 '@T6G_MB_LIB.T6G(SCH_1):NC_INA230_7_NC5':
 C_SIGNAL='@t6g_mb_lib.t6g(sch_1):nc_ina230_7_nc5';
NODE_NAME     U56 16
 '@T6G_MB_LIB.T6G(SCH_1):PAGE466_I29@PURE_QUANTA.ISL28022FRZT(CHIPS)':
 'NC5': CDS_PINID='NC5';
NET_NAME
'NC_INA230_8_NC0'
 '@T6G_MB_LIB.T6G(SCH_1):NC_INA230_8_NC0':
 C_SIGNAL='@t6g_mb_lib.t6g(sch_1):nc_ina230_8_nc0';
NODE_NAME     U52 6
 '@T6G_MB_LIB.T6G(SCH_1):PAGE466_I57@PURE_QUANTA.ISL28022FRZT(CHIPS)':
 'NC0': CDS_PINID='NC0';
NET_NAME
'NC_INA230_8_NC1'
 '@T6G_MB_LIB.T6G(SCH_1):NC_INA230_8_NC1':
 C_SIGNAL='@t6g_mb_lib.t6g(sch_1):nc_ina230_8_nc1';
NODE_NAME     U52 7
 '@T6G_MB_LIB.T6G(SCH_1):PAGE466_I57@PURE_QUANTA.ISL28022FRZT(CHIPS)':
 'NC1': CDS_PINID='NC1';
NET_NAME
'NC_INA230_8_NC2'
 '@T6G_MB_LIB.T6G(SCH_1):NC_INA230_8_NC2':
 C_SIGNAL='@t6g_mb_lib.t6g(sch_1):nc_ina230_8_nc2';
NODE_NAME     U52 8
 '@T6G_MB_LIB.T6G(SCH_1):PAGE466_I57@PURE_QUANTA.ISL28022FRZT(CHIPS)':
 'NC2': CDS_PINID='NC2';
NET_NAME
'NC_INA230_8_NC3'
 '@T6G_MB_LIB.T6G(SCH_1):NC_INA230_8_NC3':
 C_SIGNAL='@t6g_mb_lib.t6g(sch_1):nc_ina230_8_nc3';
NODE_NAME     U52 14
 '@T6G_MB_LIB.T6G(SCH_1):PAGE466_I57@PURE_QUANTA.ISL28022FRZT(CHIPS)':
 'NC3': CDS_PINID='NC3';
NET_NAME
'NC_INA230_8_NC4'
 '@T6G_MB_LIB.T6G(SCH_1):NC_INA230_8_NC4':
 C_SIGNAL='@t6g_mb_lib.t6g(sch_1):nc_ina230_8_nc4';
NODE_NAME     U52 15
 '@T6G_MB_LIB.T6G(SCH_1):PAGE466_I57@PURE_QUANTA.ISL28022FRZT(CHIPS)':
 'NC4': CDS_PINID='NC4';
NET_NAME
'NC_INA230_8_NC5'
 '@T6G_MB_LIB.T6G(SCH_1):NC_INA230_8_NC5':
 C_SIGNAL='@t6g_mb_lib.t6g(sch_1):nc_ina230_8_nc5';
NODE_NAME     U52 16
 '@T6G_MB_LIB.T6G(SCH_1):PAGE466_I57@PURE_QUANTA.ISL28022FRZT(CHIPS)':
 'NC5': CDS_PINID='NC5';
NET_NAME
'NC_J106_A5'
 '@T6G_MB_LIB.T6G(SCH_1):NC_J106_A5':
 C_SIGNAL='@t6g_mb_lib.t6g(sch_1):nc_j106_a5';
NODE_NAME     J106 A5
 '@T6G_MB_LIB.T6G(SCH_1):PAGE327_I19@PURE_QUANTA.CONN112_10137002101LF(CHIPS)':
 'A5': CDS_PINID='A5';
NET_NAME
'NC_J107_A1'
 '@T6G_MB_LIB.T6G(SCH_1):NC_J107_A1':
 C_SIGNAL='@t6g_mb_lib.t6g(sch_1):nc_j107_a1';
NODE_NAME     J107 A1
 '@T6G_MB_LIB.T6G(SCH_1):PAGE317_I49@PURE_QUANTA.CONN112_10137002101LF(CHIPS)':
 'A1': CDS_PINID='A1';
NET_NAME
'NC_J107_A3'
 '@T6G_MB_LIB.T6G(SCH_1):NC_J107_A3':
 C_SIGNAL='@t6g_mb_lib.t6g(sch_1):nc_j107_a3';
NODE_NAME     J107 A3
 '@T6G_MB_LIB.T6G(SCH_1):PAGE317_I49@PURE_QUANTA.CONN112_10137002101LF(CHIPS)':
 'A3': CDS_PINID='A3';
NET_NAME
'NC_J107_A5'
 '@T6G_MB_LIB.T6G(SCH_1):NC_J107_A5':
 C_SIGNAL='@t6g_mb_lib.t6g(sch_1):nc_j107_a5';
NODE_NAME     J107 A5
 '@T6G_MB_LIB.T6G(SCH_1):PAGE317_I70@PURE_QUANTA.CONN112_10137002101LF(CHIPS)':
 'A5': CDS_PINID='A5';
NET_NAME
'NC_J107_N4'
 '@T6G_MB_LIB.T6G(SCH_1):NC_J107_N4':
 C_SIGNAL='@t6g_mb_lib.t6g(sch_1):nc_j107_n4';
NODE_NAME     J107 N4
 '@T6G_MB_LIB.T6G(SCH_1):PAGE317_I49@PURE_QUANTA.CONN112_10137002101LF(CHIPS)':
 'N4': CDS_PINID='N4';
NET_NAME
'NC_J107_N6'
 '@T6G_MB_LIB.T6G(SCH_1):NC_J107_N6':
 C_SIGNAL='@t6g_mb_lib.t6g(sch_1):nc_j107_n6';
NODE_NAME     J107 N6
 '@T6G_MB_LIB.T6G(SCH_1):PAGE317_I70@PURE_QUANTA.CONN112_10137002101LF(CHIPS)':
 'N6': CDS_PINID='N6';
NET_NAME
'NC_J108_N2'
 '@T6G_MB_LIB.T6G(SCH_1):NC_J108_N2':
 C_SIGNAL='@t6g_mb_lib.t6g(sch_1):nc_j108_n2';
NODE_NAME     J108 N2
 '@T6G_MB_LIB.T6G(SCH_1):PAGE320_I72@PURE_QUANTA.CONN112_10137002101LF(CHIPS)':
 'N2': CDS_PINID='N2';
NET_NAME
'NC_J108_N4'
 '@T6G_MB_LIB.T6G(SCH_1):NC_J108_N4':
 C_SIGNAL='@t6g_mb_lib.t6g(sch_1):nc_j108_n4';
NODE_NAME     J108 N4
 '@T6G_MB_LIB.T6G(SCH_1):PAGE320_I72@PURE_QUANTA.CONN112_10137002101LF(CHIPS)':
 'N4': CDS_PINID='N4';
NET_NAME
'NC_J108_N6'
 '@T6G_MB_LIB.T6G(SCH_1):NC_J108_N6':
 C_SIGNAL='@t6g_mb_lib.t6g(sch_1):nc_j108_n6';
NODE_NAME     J108 N6
 '@T6G_MB_LIB.T6G(SCH_1):PAGE320_I15@PURE_QUANTA.CONN112_10137002101LF(CHIPS)':
 'N6': CDS_PINID='N6';
NET_NAME
'NC_J112_N2'
 '@T6G_MB_LIB.T6G(SCH_1):NC_J112_N2':
 C_SIGNAL='@t6g_mb_lib.t6g(sch_1):nc_j112_n2';
NODE_NAME     J112 N2
 '@T6G_MB_LIB.T6G(SCH_1):PAGE329_I102@PURE_QUANTA.CONN160_10131762101LF(CHIPS)':
 'N2': CDS_PINID='N2';
NET_NAME
'NC_J112_O2'
 '@T6G_MB_LIB.T6G(SCH_1):NC_J112_O2':
 C_SIGNAL='@t6g_mb_lib.t6g(sch_1):nc_j112_o2';
NODE_NAME     J112 O2
 '@T6G_MB_LIB.T6G(SCH_1):PAGE329_I102@PURE_QUANTA.CONN160_10131762101LF(CHIPS)':
 'O2': CDS_PINID='O2';
NET_NAME
'NC_J112_O5'
 '@T6G_MB_LIB.T6G(SCH_1):NC_J112_O5':
 C_SIGNAL='@t6g_mb_lib.t6g(sch_1):nc_j112_o5';
NODE_NAME     J112 O5
 '@T6G_MB_LIB.T6G(SCH_1):PAGE329_I7@PURE_QUANTA.CONN160_10131762101LF(CHIPS)':
 'O5': CDS_PINID='O5';
NET_NAME
'NC_J112_P5'
 '@T6G_MB_LIB.T6G(SCH_1):NC_J112_P5':
 C_SIGNAL='@t6g_mb_lib.t6g(sch_1):nc_j112_p5';
NODE_NAME     J112 P5
 '@T6G_MB_LIB.T6G(SCH_1):PAGE329_I7@PURE_QUANTA.CONN160_10131762101LF(CHIPS)':
 'P5': CDS_PINID='P5';
NET_NAME
'NC_J112_R5'
 '@T6G_MB_LIB.T6G(SCH_1):NC_J112_R5':
 C_SIGNAL='@t6g_mb_lib.t6g(sch_1):nc_j112_r5';
NODE_NAME     J112 R5
 '@T6G_MB_LIB.T6G(SCH_1):PAGE329_I7@PURE_QUANTA.CONN160_10131762101LF(CHIPS)':
 'R5': CDS_PINID='R5';
NET_NAME
'NC_J112_S5'
 '@T6G_MB_LIB.T6G(SCH_1):NC_J112_S5':
 C_SIGNAL='@t6g_mb_lib.t6g(sch_1):nc_j112_s5';
NODE_NAME     J112 S5
 '@T6G_MB_LIB.T6G(SCH_1):PAGE329_I7@PURE_QUANTA.CONN160_10131762101LF(CHIPS)':
 'S5': CDS_PINID='S5';
NET_NAME
'NC_M2_0_NC1'
 '@T6G_MB_LIB.T6G(SCH_1):NC_M2_0_NC1':
 C_SIGNAL='@t6g_mb_lib.t6g(sch_1):nc_m2_0_nc1';
NODE_NAME     J59 6
 '@T6G_MB_LIB.T6G(SCH_1):PAGE345_I88@PURE_QUANTA.SCONN75K_APCI0155P004A(CHIPS)':
 'NC1': CDS_PINID='NC1';
NET_NAME
'NC_M2_0_NC10'
 '@T6G_MB_LIB.T6G(SCH_1):NC_M2_0_NC10':
 C_SIGNAL='@t6g_mb_lib.t6g(sch_1):nc_m2_0_nc10';
NODE_NAME     J59 34
 '@T6G_MB_LIB.T6G(SCH_1):PAGE345_I88@PURE_QUANTA.SCONN75K_APCI0155P004A(CHIPS)':
 'NC10': CDS_PINID='NC10';
NET_NAME
'NC_M2_0_NC11'
 '@T6G_MB_LIB.T6G(SCH_1):NC_M2_0_NC11':
 C_SIGNAL='@t6g_mb_lib.t6g(sch_1):nc_m2_0_nc11';
NODE_NAME     J59 36
 '@T6G_MB_LIB.T6G(SCH_1):PAGE345_I88@PURE_QUANTA.SCONN75K_APCI0155P004A(CHIPS)':
 'NC11': CDS_PINID='NC11';
NET_NAME
'NC_M2_0_NC14'
 '@T6G_MB_LIB.T6G(SCH_1):NC_M2_0_NC14':
 C_SIGNAL='@t6g_mb_lib.t6g(sch_1):nc_m2_0_nc14';
NODE_NAME     J59 44
 '@T6G_MB_LIB.T6G(SCH_1):PAGE345_I88@PURE_QUANTA.SCONN75K_APCI0155P004A(CHIPS)':
 'NC14': CDS_PINID='NC14';
NET_NAME
'NC_M2_0_NC15'
 '@T6G_MB_LIB.T6G(SCH_1):NC_M2_0_NC15':
 C_SIGNAL='@t6g_mb_lib.t6g(sch_1):nc_m2_0_nc15';
NODE_NAME     J59 46
 '@T6G_MB_LIB.T6G(SCH_1):PAGE345_I88@PURE_QUANTA.SCONN75K_APCI0155P004A(CHIPS)':
 'NC15': CDS_PINID='NC15';
NET_NAME
'NC_M2_0_NC16'
 '@T6G_MB_LIB.T6G(SCH_1):NC_M2_0_NC16':
 C_SIGNAL='@t6g_mb_lib.t6g(sch_1):nc_m2_0_nc16';
NODE_NAME     J59 48
 '@T6G_MB_LIB.T6G(SCH_1):PAGE345_I88@PURE_QUANTA.SCONN75K_APCI0155P004A(CHIPS)':
 'NC16': CDS_PINID='NC16';
NET_NAME
'NC_M2_0_NC17'
 '@T6G_MB_LIB.T6G(SCH_1):NC_M2_0_NC17':
 C_SIGNAL='@t6g_mb_lib.t6g(sch_1):nc_m2_0_nc17';
NODE_NAME     J59 56
 '@T6G_MB_LIB.T6G(SCH_1):PAGE345_I88@PURE_QUANTA.SCONN75K_APCI0155P004A(CHIPS)':
 'NC17': CDS_PINID='NC17';
NET_NAME
'NC_M2_0_NC18'
 '@T6G_MB_LIB.T6G(SCH_1):NC_M2_0_NC18':
 C_SIGNAL='@t6g_mb_lib.t6g(sch_1):nc_m2_0_nc18';
NODE_NAME     J59 58
 '@T6G_MB_LIB.T6G(SCH_1):PAGE345_I88@PURE_QUANTA.SCONN75K_APCI0155P004A(CHIPS)':
 'NC18': CDS_PINID='NC18';
NET_NAME
'NC_M2_0_NC19'
 '@T6G_MB_LIB.T6G(SCH_1):NC_M2_0_NC19':
 C_SIGNAL='@t6g_mb_lib.t6g(sch_1):nc_m2_0_nc19';
NODE_NAME     J59 67
 '@T6G_MB_LIB.T6G(SCH_1):PAGE345_I88@PURE_QUANTA.SCONN75K_APCI0155P004A(CHIPS)':
 'NC19': CDS_PINID='NC19';
NET_NAME
'NC_M2_0_NC2'
 '@T6G_MB_LIB.T6G(SCH_1):NC_M2_0_NC2':
 C_SIGNAL='@t6g_mb_lib.t6g(sch_1):nc_m2_0_nc2';
NODE_NAME     J59 8
 '@T6G_MB_LIB.T6G(SCH_1):PAGE345_I88@PURE_QUANTA.SCONN75K_APCI0155P004A(CHIPS)':
 'NC2': CDS_PINID='NC2';
NET_NAME
'NC_M2_0_NC3'
 '@T6G_MB_LIB.T6G(SCH_1):NC_M2_0_NC3':
 C_SIGNAL='@t6g_mb_lib.t6g(sch_1):nc_m2_0_nc3';
NODE_NAME     J59 20
 '@T6G_MB_LIB.T6G(SCH_1):PAGE345_I88@PURE_QUANTA.SCONN75K_APCI0155P004A(CHIPS)':
 'NC3': CDS_PINID='NC3';
NET_NAME
'NC_M2_0_NC4'
 '@T6G_MB_LIB.T6G(SCH_1):NC_M2_0_NC4':
 C_SIGNAL='@t6g_mb_lib.t6g(sch_1):nc_m2_0_nc4';
NODE_NAME     J59 22
 '@T6G_MB_LIB.T6G(SCH_1):PAGE345_I88@PURE_QUANTA.SCONN75K_APCI0155P004A(CHIPS)':
 'NC4': CDS_PINID='NC4';
NET_NAME
'NC_M2_0_NC5'
 '@T6G_MB_LIB.T6G(SCH_1):NC_M2_0_NC5':
 C_SIGNAL='@t6g_mb_lib.t6g(sch_1):nc_m2_0_nc5';
NODE_NAME     J59 24
 '@T6G_MB_LIB.T6G(SCH_1):PAGE345_I88@PURE_QUANTA.SCONN75K_APCI0155P004A(CHIPS)':
 'NC5': CDS_PINID='NC5';
NET_NAME
'NC_M2_0_NC6'
 '@T6G_MB_LIB.T6G(SCH_1):NC_M2_0_NC6':
 C_SIGNAL='@t6g_mb_lib.t6g(sch_1):nc_m2_0_nc6';
NODE_NAME     J59 26
 '@T6G_MB_LIB.T6G(SCH_1):PAGE345_I88@PURE_QUANTA.SCONN75K_APCI0155P004A(CHIPS)':
 'NC6': CDS_PINID='NC6';
NET_NAME
'NC_M2_0_NC7'
 '@T6G_MB_LIB.T6G(SCH_1):NC_M2_0_NC7':
 C_SIGNAL='@t6g_mb_lib.t6g(sch_1):nc_m2_0_nc7';
NODE_NAME     J59 28
 '@T6G_MB_LIB.T6G(SCH_1):PAGE345_I88@PURE_QUANTA.SCONN75K_APCI0155P004A(CHIPS)':
 'NC7': CDS_PINID='NC7';
NET_NAME
'NC_M2_0_NC8'
 '@T6G_MB_LIB.T6G(SCH_1):NC_M2_0_NC8':
 C_SIGNAL='@t6g_mb_lib.t6g(sch_1):nc_m2_0_nc8';
NODE_NAME     J59 30
 '@T6G_MB_LIB.T6G(SCH_1):PAGE345_I88@PURE_QUANTA.SCONN75K_APCI0155P004A(CHIPS)':
 'NC8': CDS_PINID='NC8';
NET_NAME
'NC_M2_0_NC9'
 '@T6G_MB_LIB.T6G(SCH_1):NC_M2_0_NC9':
 C_SIGNAL='@t6g_mb_lib.t6g(sch_1):nc_m2_0_nc9';
NODE_NAME     J59 32
 '@T6G_MB_LIB.T6G(SCH_1):PAGE345_I88@PURE_QUANTA.SCONN75K_APCI0155P004A(CHIPS)':
 'NC9': CDS_PINID='NC9';
NET_NAME
'NC_M2_0_SUSCLK'
 '@T6G_MB_LIB.T6G(SCH_1):NC_M2_0_SUSCLK':
 C_SIGNAL='@t6g_mb_lib.t6g(sch_1):nc_m2_0_susclk';
NODE_NAME     J59 68
 '@T6G_MB_LIB.T6G(SCH_1):PAGE345_I88@PURE_QUANTA.SCONN75K_APCI0155P004A(CHIPS)':
 'SUSCLK': CDS_PINID='SUSCLK';
NET_NAME
'NC_P0V9_RETIMER_CPU0_IMON3'
 '@T6G_MB_LIB.T6G(SCH_1):NC_P0V9_RETIMER_CPU0_IMON3':
 C_SIGNAL='@t6g_mb_lib.t6g(sch_1):nc_p0v9_retimer_cpu0_imon3';
NODE_NAME     PU6502 25
 '@T6G_MB_LIB.T6G(SCH_1):PAGE475_I42@PURE_QUANTA.ISL69260IRAZT(CHIPS)':
 'CS5': CDS_PINID='CS5';
NODE_NAME     PR6609 1
 '@T6G_MB_LIB.T6G(SCH_1):PAGE475_I188@PURE_QUANTA.Q_RES(CHIPS)':
 'A': CDS_PINID='A';
NET_NAME
'NC_P0V9_RETIMER_CPU0_IMON4'
 '@T6G_MB_LIB.T6G(SCH_1):NC_P0V9_RETIMER_CPU0_IMON4':
 C_SIGNAL='@t6g_mb_lib.t6g(sch_1):nc_p0v9_retimer_cpu0_imon4';
NODE_NAME     PU6502 26
 '@T6G_MB_LIB.T6G(SCH_1):PAGE475_I42@PURE_QUANTA.ISL69260IRAZT(CHIPS)':
 'CS4': CDS_PINID='CS4';
NODE_NAME     PR6610 1
 '@T6G_MB_LIB.T6G(SCH_1):PAGE475_I190@PURE_QUANTA.Q_RES(CHIPS)':
 'A': CDS_PINID='A';
NET_NAME
'NC_P0V9_RETIMER_CPU0_IMON5'
 '@T6G_MB_LIB.T6G(SCH_1):NC_P0V9_RETIMER_CPU0_IMON5':
 C_SIGNAL='@t6g_mb_lib.t6g(sch_1):nc_p0v9_retimer_cpu0_imon5';
NODE_NAME     PU6502 27
 '@T6G_MB_LIB.T6G(SCH_1):PAGE475_I42@PURE_QUANTA.ISL69260IRAZT(CHIPS)':
 'CS3': CDS_PINID='CS3';
NODE_NAME     PR6611 1
 '@T6G_MB_LIB.T6G(SCH_1):PAGE475_I191@PURE_QUANTA.Q_RES(CHIPS)':
 'A': CDS_PINID='A';
NET_NAME
'NC_P0V9_RETIMER_CPU0_IMON6'
 '@T6G_MB_LIB.T6G(SCH_1):NC_P0V9_RETIMER_CPU0_IMON6':
 C_SIGNAL='@t6g_mb_lib.t6g(sch_1):nc_p0v9_retimer_cpu0_imon6';
NODE_NAME     PU6502 28
 '@T6G_MB_LIB.T6G(SCH_1):PAGE475_I42@PURE_QUANTA.ISL69260IRAZT(CHIPS)':
 'CS2': CDS_PINID='CS2';
NODE_NAME     PR6612 1
 '@T6G_MB_LIB.T6G(SCH_1):PAGE475_I192@PURE_QUANTA.Q_RES(CHIPS)':
 'A': CDS_PINID='A';
NET_NAME
'NC_P0V9_RETIMER_CPU0_IMON7'
 '@T6G_MB_LIB.T6G(SCH_1):NC_P0V9_RETIMER_CPU0_IMON7':
 C_SIGNAL='@t6g_mb_lib.t6g(sch_1):nc_p0v9_retimer_cpu0_imon7';
NODE_NAME     PU6502 29
 '@T6G_MB_LIB.T6G(SCH_1):PAGE475_I42@PURE_QUANTA.ISL69260IRAZT(CHIPS)':
 'CS1': CDS_PINID='CS1';
NODE_NAME     PR6613 1
 '@T6G_MB_LIB.T6G(SCH_1):PAGE475_I193@PURE_QUANTA.Q_RES(CHIPS)':
 'A': CDS_PINID='A';
NET_NAME
'NC_P0V9_RETIMER_CPU0_IMON8'
 '@T6G_MB_LIB.T6G(SCH_1):NC_P0V9_RETIMER_CPU0_IMON8':
 C_SIGNAL='@t6g_mb_lib.t6g(sch_1):nc_p0v9_retimer_cpu0_imon8';
NODE_NAME     PU6502 30
 '@T6G_MB_LIB.T6G(SCH_1):PAGE475_I42@PURE_QUANTA.ISL69260IRAZT(CHIPS)':
 'CS0': CDS_PINID='CS0';
NODE_NAME     PR6614 1
 '@T6G_MB_LIB.T6G(SCH_1):PAGE475_I198@PURE_QUANTA.Q_RES(CHIPS)':
 'A': CDS_PINID='A';
NET_NAME
'NC_P0V9_RETIMER_CPU0_PG1'
 '@T6G_MB_LIB.T6G(SCH_1):NC_P0V9_RETIMER_CPU0_PG1':
 C_SIGNAL='@t6g_mb_lib.t6g(sch_1):nc_p0v9_retimer_cpu0_pg1';
NODE_NAME     PU6502 16
 '@T6G_MB_LIB.T6G(SCH_1):PAGE475_I42@PURE_QUANTA.ISL69260IRAZT(CHIPS)':
 'PG1': CDS_PINID='PG1';
NET_NAME
'NC_P0V9_RETIMER_CPU0_PWM3'
 '@T6G_MB_LIB.T6G(SCH_1):NC_P0V9_RETIMER_CPU0_PWM3':
 C_SIGNAL='@t6g_mb_lib.t6g(sch_1):nc_p0v9_retimer_cpu0_pwm3';
NODE_NAME     PU6502 6
 '@T6G_MB_LIB.T6G(SCH_1):PAGE475_I42@PURE_QUANTA.ISL69260IRAZT(CHIPS)':
 'PWM5': CDS_PINID='PWM5';
NET_NAME
'NC_P0V9_RETIMER_CPU0_PWM4'
 '@T6G_MB_LIB.T6G(SCH_1):NC_P0V9_RETIMER_CPU0_PWM4':
 C_SIGNAL='@t6g_mb_lib.t6g(sch_1):nc_p0v9_retimer_cpu0_pwm4';
NODE_NAME     PU6502 5
 '@T6G_MB_LIB.T6G(SCH_1):PAGE475_I42@PURE_QUANTA.ISL69260IRAZT(CHIPS)':
 'PWM4': CDS_PINID='PWM4';
NET_NAME
'NC_P0V9_RETIMER_CPU0_PWM5'
 '@T6G_MB_LIB.T6G(SCH_1):NC_P0V9_RETIMER_CPU0_PWM5':
 C_SIGNAL='@t6g_mb_lib.t6g(sch_1):nc_p0v9_retimer_cpu0_pwm5';
NODE_NAME     PU6502 4
 '@T6G_MB_LIB.T6G(SCH_1):PAGE475_I42@PURE_QUANTA.ISL69260IRAZT(CHIPS)':
 'PWM3': CDS_PINID='PWM3';
NET_NAME
'NC_P0V9_RETIMER_CPU0_PWM6'
 '@T6G_MB_LIB.T6G(SCH_1):NC_P0V9_RETIMER_CPU0_PWM6':
 C_SIGNAL='@t6g_mb_lib.t6g(sch_1):nc_p0v9_retimer_cpu0_pwm6';
NODE_NAME     PU6502 3
 '@T6G_MB_LIB.T6G(SCH_1):PAGE475_I42@PURE_QUANTA.ISL69260IRAZT(CHIPS)':
 'PWM2': CDS_PINID='PWM2';
NET_NAME
'NC_P0V9_RETIMER_CPU0_PWM7'
 '@T6G_MB_LIB.T6G(SCH_1):NC_P0V9_RETIMER_CPU0_PWM7':
 C_SIGNAL='@t6g_mb_lib.t6g(sch_1):nc_p0v9_retimer_cpu0_pwm7';
NODE_NAME     PU6502 2
 '@T6G_MB_LIB.T6G(SCH_1):PAGE475_I42@PURE_QUANTA.ISL69260IRAZT(CHIPS)':
 'PWM1': CDS_PINID='PWM1';
NET_NAME
'NC_P0V9_RETIMER_CPU0_PWM8'
 '@T6G_MB_LIB.T6G(SCH_1):NC_P0V9_RETIMER_CPU0_PWM8':
 C_SIGNAL='@t6g_mb_lib.t6g(sch_1):nc_p0v9_retimer_cpu0_pwm8';
NODE_NAME     PU6502 1
 '@T6G_MB_LIB.T6G(SCH_1):PAGE475_I42@PURE_QUANTA.ISL69260IRAZT(CHIPS)':
 'PWM0': CDS_PINID='PWM0';
NET_NAME
'NC_P0V9_RETIMER_CPU1_IMON3'
 '@T6G_MB_LIB.T6G(SCH_1):NC_P0V9_RETIMER_CPU1_IMON3':
 C_SIGNAL='@t6g_mb_lib.t6g(sch_1):nc_p0v9_retimer_cpu1_imon3';
NODE_NAME     PR6539 1
 '@T6G_MB_LIB.T6G(SCH_1):PAGE477_I69@PURE_QUANTA.Q_RES(CHIPS)':
 'A': CDS_PINID='A';
NODE_NAME     PU6510 25
 '@T6G_MB_LIB.T6G(SCH_1):PAGE477_I88@PURE_QUANTA.ISL69260IRAZT(CHIPS)':
 'CS5': CDS_PINID='CS5';
NET_NAME
'NC_P0V9_RETIMER_CPU1_IMON4'
 '@T6G_MB_LIB.T6G(SCH_1):NC_P0V9_RETIMER_CPU1_IMON4':
 C_SIGNAL='@t6g_mb_lib.t6g(sch_1):nc_p0v9_retimer_cpu1_imon4';
NODE_NAME     PR6540 1
 '@T6G_MB_LIB.T6G(SCH_1):PAGE477_I68@PURE_QUANTA.Q_RES(CHIPS)':
 'A': CDS_PINID='A';
NODE_NAME     PU6510 26
 '@T6G_MB_LIB.T6G(SCH_1):PAGE477_I88@PURE_QUANTA.ISL69260IRAZT(CHIPS)':
 'CS4': CDS_PINID='CS4';
NET_NAME
'NC_P0V9_RETIMER_CPU1_IMON5'
 '@T6G_MB_LIB.T6G(SCH_1):NC_P0V9_RETIMER_CPU1_IMON5':
 C_SIGNAL='@t6g_mb_lib.t6g(sch_1):nc_p0v9_retimer_cpu1_imon5';
NODE_NAME     PR6541 1
 '@T6G_MB_LIB.T6G(SCH_1):PAGE477_I65@PURE_QUANTA.Q_RES(CHIPS)':
 'A': CDS_PINID='A';
NODE_NAME     PU6510 27
 '@T6G_MB_LIB.T6G(SCH_1):PAGE477_I88@PURE_QUANTA.ISL69260IRAZT(CHIPS)':
 'CS3': CDS_PINID='CS3';
NET_NAME
'NC_P0V9_RETIMER_CPU1_IMON6'
 '@T6G_MB_LIB.T6G(SCH_1):NC_P0V9_RETIMER_CPU1_IMON6':
 C_SIGNAL='@t6g_mb_lib.t6g(sch_1):nc_p0v9_retimer_cpu1_imon6';
NODE_NAME     PR6542 1
 '@T6G_MB_LIB.T6G(SCH_1):PAGE477_I64@PURE_QUANTA.Q_RES(CHIPS)':
 'A': CDS_PINID='A';
NODE_NAME     PU6510 28
 '@T6G_MB_LIB.T6G(SCH_1):PAGE477_I88@PURE_QUANTA.ISL69260IRAZT(CHIPS)':
 'CS2': CDS_PINID='CS2';
NET_NAME
'NC_P0V9_RETIMER_CPU1_IMON7'
 '@T6G_MB_LIB.T6G(SCH_1):NC_P0V9_RETIMER_CPU1_IMON7':
 C_SIGNAL='@t6g_mb_lib.t6g(sch_1):nc_p0v9_retimer_cpu1_imon7';
NODE_NAME     PR6543 1
 '@T6G_MB_LIB.T6G(SCH_1):PAGE477_I58@PURE_QUANTA.Q_RES(CHIPS)':
 'A': CDS_PINID='A';
NODE_NAME     PU6510 29
 '@T6G_MB_LIB.T6G(SCH_1):PAGE477_I88@PURE_QUANTA.ISL69260IRAZT(CHIPS)':
 'CS1': CDS_PINID='CS1';
NET_NAME
'NC_P0V9_RETIMER_CPU1_IMON8'
 '@T6G_MB_LIB.T6G(SCH_1):NC_P0V9_RETIMER_CPU1_IMON8':
 C_SIGNAL='@t6g_mb_lib.t6g(sch_1):nc_p0v9_retimer_cpu1_imon8';
NODE_NAME     PR6544 1
 '@T6G_MB_LIB.T6G(SCH_1):PAGE477_I57@PURE_QUANTA.Q_RES(CHIPS)':
 'A': CDS_PINID='A';
NODE_NAME     PU6510 30
 '@T6G_MB_LIB.T6G(SCH_1):PAGE477_I88@PURE_QUANTA.ISL69260IRAZT(CHIPS)':
 'CS0': CDS_PINID='CS0';
NET_NAME
'NC_P0V9_RETIMER_CPU1_PG1'
 '@T6G_MB_LIB.T6G(SCH_1):NC_P0V9_RETIMER_CPU1_PG1':
 C_SIGNAL='@t6g_mb_lib.t6g(sch_1):nc_p0v9_retimer_cpu1_pg1';
NODE_NAME     PU6510 16
 '@T6G_MB_LIB.T6G(SCH_1):PAGE477_I88@PURE_QUANTA.ISL69260IRAZT(CHIPS)':
 'PG1': CDS_PINID='PG1';
NET_NAME
'NC_P0V9_RETIMER_CPU1_PWM3'
 '@T6G_MB_LIB.T6G(SCH_1):NC_P0V9_RETIMER_CPU1_PWM3':
 C_SIGNAL='@t6g_mb_lib.t6g(sch_1):nc_p0v9_retimer_cpu1_pwm3';
NODE_NAME     PU6510 6
 '@T6G_MB_LIB.T6G(SCH_1):PAGE477_I88@PURE_QUANTA.ISL69260IRAZT(CHIPS)':
 'PWM5': CDS_PINID='PWM5';
NET_NAME
'NC_P0V9_RETIMER_CPU1_PWM4'
 '@T6G_MB_LIB.T6G(SCH_1):NC_P0V9_RETIMER_CPU1_PWM4':
 C_SIGNAL='@t6g_mb_lib.t6g(sch_1):nc_p0v9_retimer_cpu1_pwm4';
NODE_NAME     PU6510 5
 '@T6G_MB_LIB.T6G(SCH_1):PAGE477_I88@PURE_QUANTA.ISL69260IRAZT(CHIPS)':
 'PWM4': CDS_PINID='PWM4';
NET_NAME
'NC_P0V9_RETIMER_CPU1_PWM5'
 '@T6G_MB_LIB.T6G(SCH_1):NC_P0V9_RETIMER_CPU1_PWM5':
 C_SIGNAL='@t6g_mb_lib.t6g(sch_1):nc_p0v9_retimer_cpu1_pwm5';
NODE_NAME     PU6510 4
 '@T6G_MB_LIB.T6G(SCH_1):PAGE477_I88@PURE_QUANTA.ISL69260IRAZT(CHIPS)':
 'PWM3': CDS_PINID='PWM3';
NET_NAME
'NC_P0V9_RETIMER_CPU1_PWM6'
 '@T6G_MB_LIB.T6G(SCH_1):NC_P0V9_RETIMER_CPU1_PWM6':
 C_SIGNAL='@t6g_mb_lib.t6g(sch_1):nc_p0v9_retimer_cpu1_pwm6';
NODE_NAME     PU6510 3
 '@T6G_MB_LIB.T6G(SCH_1):PAGE477_I88@PURE_QUANTA.ISL69260IRAZT(CHIPS)':
 'PWM2': CDS_PINID='PWM2';
NET_NAME
'NC_P0V9_RETIMER_CPU1_PWM7'
 '@T6G_MB_LIB.T6G(SCH_1):NC_P0V9_RETIMER_CPU1_PWM7':
 C_SIGNAL='@t6g_mb_lib.t6g(sch_1):nc_p0v9_retimer_cpu1_pwm7';
NODE_NAME     PU6510 2
 '@T6G_MB_LIB.T6G(SCH_1):PAGE477_I88@PURE_QUANTA.ISL69260IRAZT(CHIPS)':
 'PWM1': CDS_PINID='PWM1';
NET_NAME
'NC_P0V9_RETIMER_CPU1_PWM8'
 '@T6G_MB_LIB.T6G(SCH_1):NC_P0V9_RETIMER_CPU1_PWM8':
 C_SIGNAL='@t6g_mb_lib.t6g(sch_1):nc_p0v9_retimer_cpu1_pwm8';
NODE_NAME     PU6510 1
 '@T6G_MB_LIB.T6G(SCH_1):PAGE477_I88@PURE_QUANTA.ISL69260IRAZT(CHIPS)':
 'PWM0': CDS_PINID='PWM0';
NET_NAME
'NC_PU9_1'
 '@T6G_MB_LIB.T6G(SCH_1):NC_PU9_1':
 C_SIGNAL='@t6g_mb_lib.t6g(sch_1):nc_pu9_1';
NODE_NAME     PU9 33
 '@T6G_MB_LIB.T6G(SCH_1):PAGE245_I21@PURE_QUANTA.NCP3284AMNTXG(CHIPS)':
 'NC1': CDS_PINID='NC1';
NET_NAME
'NC_PU9_2'
 '@T6G_MB_LIB.T6G(SCH_1):NC_PU9_2':
 C_SIGNAL='@t6g_mb_lib.t6g(sch_1):nc_pu9_2';
NODE_NAME     PU9 34
 '@T6G_MB_LIB.T6G(SCH_1):PAGE245_I21@PURE_QUANTA.NCP3284AMNTXG(CHIPS)':
 'NC2': CDS_PINID='NC2';
NET_NAME
'NC_PU9_3'
 '@T6G_MB_LIB.T6G(SCH_1):NC_PU9_3':
 C_SIGNAL='@t6g_mb_lib.t6g(sch_1):nc_pu9_3';
NODE_NAME     PU9 6
 '@T6G_MB_LIB.T6G(SCH_1):PAGE245_I21@PURE_QUANTA.NCP3284AMNTXG(CHIPS)':
 'GL1': CDS_PINID='GL1';
NET_NAME
'NC_PU9_4'
 '@T6G_MB_LIB.T6G(SCH_1):NC_PU9_4':
 C_SIGNAL='@t6g_mb_lib.t6g(sch_1):nc_pu9_4';
NODE_NAME     PU9 37
 '@T6G_MB_LIB.T6G(SCH_1):PAGE245_I21@PURE_QUANTA.NCP3284AMNTXG(CHIPS)':
 'GL2': CDS_PINID='GL2';
NET_NAME
'NC_PV09_RETIMER_CPU0_DNC1'
 '@T6G_MB_LIB.T6G(SCH_1):NC_PV09_RETIMER_CPU0_DNC1':
 C_SIGNAL='@t6g_mb_lib.t6g(sch_1):nc_pv09_retimer_cpu0_dnc1';
NODE_NAME     PU6503 31
 '@T6G_MB_LIB.T6G(SCH_1):PAGE476_I53@PURE_QUANTA.ISL99390FRZTR5935(CHIPS)':
 'DNC': CDS_PINID='DNC';
NET_NAME
'NC_PV09_RETIMER_CPU0_DNC2'
 '@T6G_MB_LIB.T6G(SCH_1):NC_PV09_RETIMER_CPU0_DNC2':
 C_SIGNAL='@t6g_mb_lib.t6g(sch_1):nc_pv09_retimer_cpu0_dnc2';
NODE_NAME     PU6504 31
 '@T6G_MB_LIB.T6G(SCH_1):PAGE476_I270@PURE_QUANTA.ISL99390FRZTR5935(CHIPS)':
 'DNC': CDS_PINID='DNC';
NET_NAME
'NC_PV09_RETIMER_CPU0_GL1_1'
 '@T6G_MB_LIB.T6G(SCH_1):NC_PV09_RETIMER_CPU0_GL1_1':
 C_SIGNAL='@t6g_mb_lib.t6g(sch_1):nc_pv09_retimer_cpu0_gl1_1';
NODE_NAME     PU6503 6
 '@T6G_MB_LIB.T6G(SCH_1):PAGE476_I53@PURE_QUANTA.ISL99390FRZTR5935(CHIPS)':
 'GL1': CDS_PINID='GL1';
NET_NAME
'NC_PV09_RETIMER_CPU0_GL1_2'
 '@T6G_MB_LIB.T6G(SCH_1):NC_PV09_RETIMER_CPU0_GL1_2':
 C_SIGNAL='@t6g_mb_lib.t6g(sch_1):nc_pv09_retimer_cpu0_gl1_2';
NODE_NAME     PU6504 6
 '@T6G_MB_LIB.T6G(SCH_1):PAGE476_I270@PURE_QUANTA.ISL99390FRZTR5935(CHIPS)':
 'GL1': CDS_PINID='GL1';
NET_NAME
'NC_PV09_RETIMER_CPU0_GL2_1'
 '@T6G_MB_LIB.T6G(SCH_1):NC_PV09_RETIMER_CPU0_GL2_1':
 C_SIGNAL='@t6g_mb_lib.t6g(sch_1):nc_pv09_retimer_cpu0_gl2_1';
NODE_NAME     PU6503 41
 '@T6G_MB_LIB.T6G(SCH_1):PAGE476_I53@PURE_QUANTA.ISL99390FRZTR5935(CHIPS)':
 'GL2': CDS_PINID='GL2';
NET_NAME
'NC_PV09_RETIMER_CPU0_GL2_2'
 '@T6G_MB_LIB.T6G(SCH_1):NC_PV09_RETIMER_CPU0_GL2_2':
 C_SIGNAL='@t6g_mb_lib.t6g(sch_1):nc_pv09_retimer_cpu0_gl2_2';
NODE_NAME     PU6504 41
 '@T6G_MB_LIB.T6G(SCH_1):PAGE476_I270@PURE_QUANTA.ISL99390FRZTR5935(CHIPS)':
 'GL2': CDS_PINID='GL2';
NET_NAME
'NC_PV09_RETIMER_CPU1_DNC1'
 '@T6G_MB_LIB.T6G(SCH_1):NC_PV09_RETIMER_CPU1_DNC1':
 C_SIGNAL='@t6g_mb_lib.t6g(sch_1):nc_pv09_retimer_cpu1_dnc1';
NODE_NAME     PU6511 31
 '@T6G_MB_LIB.T6G(SCH_1):PAGE478_I51@PURE_QUANTA.ISL99390FRZTR5935(CHIPS)':
 'DNC': CDS_PINID='DNC';
NET_NAME
'NC_PV09_RETIMER_CPU1_DNC2'
 '@T6G_MB_LIB.T6G(SCH_1):NC_PV09_RETIMER_CPU1_DNC2':
 C_SIGNAL='@t6g_mb_lib.t6g(sch_1):nc_pv09_retimer_cpu1_dnc2';
NODE_NAME     PU6512 31
 '@T6G_MB_LIB.T6G(SCH_1):PAGE478_I12@PURE_QUANTA.ISL99390FRZTR5935(CHIPS)':
 'DNC': CDS_PINID='DNC';
NET_NAME
'NC_PV09_RETIMER_CPU1_GL1_1'
 '@T6G_MB_LIB.T6G(SCH_1):NC_PV09_RETIMER_CPU1_GL1_1':
 C_SIGNAL='@t6g_mb_lib.t6g(sch_1):nc_pv09_retimer_cpu1_gl1_1';
NODE_NAME     PU6511 6
 '@T6G_MB_LIB.T6G(SCH_1):PAGE478_I51@PURE_QUANTA.ISL99390FRZTR5935(CHIPS)':
 'GL1': CDS_PINID='GL1';
NET_NAME
'NC_PV09_RETIMER_CPU1_GL1_2'
 '@T6G_MB_LIB.T6G(SCH_1):NC_PV09_RETIMER_CPU1_GL1_2':
 C_SIGNAL='@t6g_mb_lib.t6g(sch_1):nc_pv09_retimer_cpu1_gl1_2';
NODE_NAME     PU6512 6
 '@T6G_MB_LIB.T6G(SCH_1):PAGE478_I12@PURE_QUANTA.ISL99390FRZTR5935(CHIPS)':
 'GL1': CDS_PINID='GL1';
NET_NAME
'NC_PV09_RETIMER_CPU1_GL2_1'
 '@T6G_MB_LIB.T6G(SCH_1):NC_PV09_RETIMER_CPU1_GL2_1':
 C_SIGNAL='@t6g_mb_lib.t6g(sch_1):nc_pv09_retimer_cpu1_gl2_1';
NODE_NAME     PU6511 41
 '@T6G_MB_LIB.T6G(SCH_1):PAGE478_I51@PURE_QUANTA.ISL99390FRZTR5935(CHIPS)':
 'GL2': CDS_PINID='GL2';
NET_NAME
'NC_PV09_RETIMER_CPU1_GL2_2'
 '@T6G_MB_LIB.T6G(SCH_1):NC_PV09_RETIMER_CPU1_GL2_2':
 C_SIGNAL='@t6g_mb_lib.t6g(sch_1):nc_pv09_retimer_cpu1_gl2_2';
NODE_NAME     PU6512 41
 '@T6G_MB_LIB.T6G(SCH_1):PAGE478_I12@PURE_QUANTA.ISL99390FRZTR5935(CHIPS)':
 'GL2': CDS_PINID='GL2';
NET_NAME
'NC_PVDD11_S3_P0_DNC1'
 '@T6G_MB_LIB.T6G(SCH_1):NC_PVDD11_S3_P0_DNC1':
 C_SIGNAL='@t6g_mb_lib.t6g(sch_1):nc_pvdd11_s3_p0_dnc1';
NODE_NAME     PU22 31
 '@T6G_MB_LIB.T6G(SCH_1):PAGE183_I92@PURE_QUANTA.ISL99390FRZTR5935(CHIPS)':
 'DNC': CDS_PINID='DNC';
NET_NAME
'NC_PVDD11_S3_P0_DNC2'
 '@T6G_MB_LIB.T6G(SCH_1):NC_PVDD11_S3_P0_DNC2':
 C_SIGNAL='@t6g_mb_lib.t6g(sch_1):nc_pvdd11_s3_p0_dnc2';
NODE_NAME     PU23 31
 '@T6G_MB_LIB.T6G(SCH_1):PAGE183_I13@PURE_QUANTA.ISL99390FRZTR5935(CHIPS)':
 'DNC': CDS_PINID='DNC';
NET_NAME
'NC_PVDD11_S3_P0_GL1_1'
 '@T6G_MB_LIB.T6G(SCH_1):NC_PVDD11_S3_P0_GL1_1':
 C_SIGNAL='@t6g_mb_lib.t6g(sch_1):nc_pvdd11_s3_p0_gl1_1';
NODE_NAME     PU22 6
 '@T6G_MB_LIB.T6G(SCH_1):PAGE183_I92@PURE_QUANTA.ISL99390FRZTR5935(CHIPS)':
 'GL1': CDS_PINID='GL1';
NET_NAME
'NC_PVDD11_S3_P0_GL1_2'
 '@T6G_MB_LIB.T6G(SCH_1):NC_PVDD11_S3_P0_GL1_2':
 C_SIGNAL='@t6g_mb_lib.t6g(sch_1):nc_pvdd11_s3_p0_gl1_2';
NODE_NAME     PU23 6
 '@T6G_MB_LIB.T6G(SCH_1):PAGE183_I13@PURE_QUANTA.ISL99390FRZTR5935(CHIPS)':
 'GL1': CDS_PINID='GL1';
NET_NAME
'NC_PVDD11_S3_P0_GL2_1'
 '@T6G_MB_LIB.T6G(SCH_1):NC_PVDD11_S3_P0_GL2_1':
 C_SIGNAL='@t6g_mb_lib.t6g(sch_1):nc_pvdd11_s3_p0_gl2_1';
NODE_NAME     PU22 41
 '@T6G_MB_LIB.T6G(SCH_1):PAGE183_I92@PURE_QUANTA.ISL99390FRZTR5935(CHIPS)':
 'GL2': CDS_PINID='GL2';
NET_NAME
'NC_PVDD11_S3_P0_GL2_2'
 '@T6G_MB_LIB.T6G(SCH_1):NC_PVDD11_S3_P0_GL2_2':
 C_SIGNAL='@t6g_mb_lib.t6g(sch_1):nc_pvdd11_s3_p0_gl2_2';
NODE_NAME     PU23 41
 '@T6G_MB_LIB.T6G(SCH_1):PAGE183_I13@PURE_QUANTA.ISL99390FRZTR5935(CHIPS)':
 'GL2': CDS_PINID='GL2';
NET_NAME
'NC_PVDD11_S3_P0_IMON3'
 '@T6G_MB_LIB.T6G(SCH_1):NC_PVDD11_S3_P0_IMON3':
 C_SIGNAL='@t6g_mb_lib.t6g(sch_1):nc_pvdd11_s3_p0_imon3';
NODE_NAME     PU21 25
 '@T6G_MB_LIB.T6G(SCH_1):PAGE182_I24@PURE_QUANTA.RAA229621GNPHA0(CHIPS)':
 'CS5': CDS_PINID='CS5';
NODE_NAME     PR37 1
 '@T6G_MB_LIB.T6G(SCH_1):PAGE182_I71@PURE_QUANTA.Q_RES(CHIPS)':
 'A': CDS_PINID='A';
NET_NAME
'NC_PVDD11_S3_P0_IMON4'
 '@T6G_MB_LIB.T6G(SCH_1):NC_PVDD11_S3_P0_IMON4':
 C_SIGNAL='@t6g_mb_lib.t6g(sch_1):nc_pvdd11_s3_p0_imon4';
NODE_NAME     PU21 26
 '@T6G_MB_LIB.T6G(SCH_1):PAGE182_I24@PURE_QUANTA.RAA229621GNPHA0(CHIPS)':
 'CS4': CDS_PINID='CS4';
NODE_NAME     PR33 1
 '@T6G_MB_LIB.T6G(SCH_1):PAGE182_I61@PURE_QUANTA.Q_RES(CHIPS)':
 'A': CDS_PINID='A';
NET_NAME
'NC_PVDD11_S3_P0_IMON5'
 '@T6G_MB_LIB.T6G(SCH_1):NC_PVDD11_S3_P0_IMON5':
 C_SIGNAL='@t6g_mb_lib.t6g(sch_1):nc_pvdd11_s3_p0_imon5';
NODE_NAME     PU21 27
 '@T6G_MB_LIB.T6G(SCH_1):PAGE182_I24@PURE_QUANTA.RAA229621GNPHA0(CHIPS)':
 'CS3': CDS_PINID='CS3';
NODE_NAME     PR34 1
 '@T6G_MB_LIB.T6G(SCH_1):PAGE182_I60@PURE_QUANTA.Q_RES(CHIPS)':
 'A': CDS_PINID='A';
NET_NAME
'NC_PVDD11_S3_P0_IMON6'
 '@T6G_MB_LIB.T6G(SCH_1):NC_PVDD11_S3_P0_IMON6':
 C_SIGNAL='@t6g_mb_lib.t6g(sch_1):nc_pvdd11_s3_p0_imon6';
NODE_NAME     PU21 28
 '@T6G_MB_LIB.T6G(SCH_1):PAGE182_I24@PURE_QUANTA.RAA229621GNPHA0(CHIPS)':
 'CS2': CDS_PINID='CS2';
NODE_NAME     PR35 1
 '@T6G_MB_LIB.T6G(SCH_1):PAGE182_I59@PURE_QUANTA.Q_RES(CHIPS)':
 'A': CDS_PINID='A';
NET_NAME
'NC_PVDD11_S3_P0_IMON7'
 '@T6G_MB_LIB.T6G(SCH_1):NC_PVDD11_S3_P0_IMON7':
 C_SIGNAL='@t6g_mb_lib.t6g(sch_1):nc_pvdd11_s3_p0_imon7';
NODE_NAME     PU21 29
 '@T6G_MB_LIB.T6G(SCH_1):PAGE182_I24@PURE_QUANTA.RAA229621GNPHA0(CHIPS)':
 'CS1': CDS_PINID='CS1';
NODE_NAME     PR419 1
 '@T6G_MB_LIB.T6G(SCH_1):PAGE182_I58@PURE_QUANTA.Q_RES(CHIPS)':
 'A': CDS_PINID='A';
NET_NAME
'NC_PVDD11_S3_P0_IMON8'
 '@T6G_MB_LIB.T6G(SCH_1):NC_PVDD11_S3_P0_IMON8':
 C_SIGNAL='@t6g_mb_lib.t6g(sch_1):nc_pvdd11_s3_p0_imon8';
NODE_NAME     PU21 30
 '@T6G_MB_LIB.T6G(SCH_1):PAGE182_I24@PURE_QUANTA.RAA229621GNPHA0(CHIPS)':
 'CS0': CDS_PINID='CS0';
NODE_NAME     PR36 1
 '@T6G_MB_LIB.T6G(SCH_1):PAGE182_I53@PURE_QUANTA.Q_RES(CHIPS)':
 'A': CDS_PINID='A';
NET_NAME
'NC_PVDD11_S3_P0_PG1'
 '@T6G_MB_LIB.T6G(SCH_1):NC_PVDD11_S3_P0_PG1':
 C_SIGNAL='@t6g_mb_lib.t6g(sch_1):nc_pvdd11_s3_p0_pg1';
NODE_NAME     PU21 16
 '@T6G_MB_LIB.T6G(SCH_1):PAGE182_I24@PURE_QUANTA.RAA229621GNPHA0(CHIPS)':
 'PG1': CDS_PINID='PG1';
NET_NAME
'NC_PVDD11_S3_P0_PWM3'
 '@T6G_MB_LIB.T6G(SCH_1):NC_PVDD11_S3_P0_PWM3':
 C_SIGNAL='@t6g_mb_lib.t6g(sch_1):nc_pvdd11_s3_p0_pwm3';
NODE_NAME     PU21 6
 '@T6G_MB_LIB.T6G(SCH_1):PAGE182_I24@PURE_QUANTA.RAA229621GNPHA0(CHIPS)':
 'PWM5': CDS_PINID='PWM5';
NET_NAME
'NC_PVDD11_S3_P0_PWM4'
 '@T6G_MB_LIB.T6G(SCH_1):NC_PVDD11_S3_P0_PWM4':
 C_SIGNAL='@t6g_mb_lib.t6g(sch_1):nc_pvdd11_s3_p0_pwm4';
NODE_NAME     PU21 5
 '@T6G_MB_LIB.T6G(SCH_1):PAGE182_I24@PURE_QUANTA.RAA229621GNPHA0(CHIPS)':
 'PWM4': CDS_PINID='PWM4';
NET_NAME
'NC_PVDD11_S3_P0_PWM5'
 '@T6G_MB_LIB.T6G(SCH_1):NC_PVDD11_S3_P0_PWM5':
 C_SIGNAL='@t6g_mb_lib.t6g(sch_1):nc_pvdd11_s3_p0_pwm5';
NODE_NAME     PU21 4
 '@T6G_MB_LIB.T6G(SCH_1):PAGE182_I24@PURE_QUANTA.RAA229621GNPHA0(CHIPS)':
 'PWM3': CDS_PINID='PWM3';
NET_NAME
'NC_PVDD11_S3_P0_PWM6'
 '@T6G_MB_LIB.T6G(SCH_1):NC_PVDD11_S3_P0_PWM6':
 C_SIGNAL='@t6g_mb_lib.t6g(sch_1):nc_pvdd11_s3_p0_pwm6';
NODE_NAME     PU21 3
 '@T6G_MB_LIB.T6G(SCH_1):PAGE182_I24@PURE_QUANTA.RAA229621GNPHA0(CHIPS)':
 'PWM2': CDS_PINID='PWM2';
NET_NAME
'NC_PVDD11_S3_P0_PWM7'
 '@T6G_MB_LIB.T6G(SCH_1):NC_PVDD11_S3_P0_PWM7':
 C_SIGNAL='@t6g_mb_lib.t6g(sch_1):nc_pvdd11_s3_p0_pwm7';
NODE_NAME     PU21 2
 '@T6G_MB_LIB.T6G(SCH_1):PAGE182_I24@PURE_QUANTA.RAA229621GNPHA0(CHIPS)':
 'PWM1': CDS_PINID='PWM1';
NET_NAME
'NC_PVDD11_S3_P0_PWM8'
 '@T6G_MB_LIB.T6G(SCH_1):NC_PVDD11_S3_P0_PWM8':
 C_SIGNAL='@t6g_mb_lib.t6g(sch_1):nc_pvdd11_s3_p0_pwm8';
NODE_NAME     PU21 1
 '@T6G_MB_LIB.T6G(SCH_1):PAGE182_I24@PURE_QUANTA.RAA229621GNPHA0(CHIPS)':
 'PWM0': CDS_PINID='PWM0';
NET_NAME
'NC_PVDD11_S3_P0_SVTO'
 '@T6G_MB_LIB.T6G(SCH_1):NC_PVDD11_S3_P0_SVTO':
 C_SIGNAL='@t6g_mb_lib.t6g(sch_1):nc_pvdd11_s3_p0_svto';
NODE_NAME     PU21 19
 '@T6G_MB_LIB.T6G(SCH_1):PAGE182_I24@PURE_QUANTA.RAA229621GNPHA0(CHIPS)':
 'SVTO': CDS_PINID='SVTO';
NET_NAME
'NC_PVDD11_S3_P1_DNC1'
 '@T6G_MB_LIB.T6G(SCH_1):NC_PVDD11_S3_P1_DNC1':
 C_SIGNAL='@t6g_mb_lib.t6g(sch_1):nc_pvdd11_s3_p1_dnc1';
NODE_NAME     PU44 31
 '@T6G_MB_LIB.T6G(SCH_1):PAGE200_I22@PURE_QUANTA.ISL99390FRZTR5935(CHIPS)':
 'DNC': CDS_PINID='DNC';
NET_NAME
'NC_PVDD11_S3_P1_DNC2'
 '@T6G_MB_LIB.T6G(SCH_1):NC_PVDD11_S3_P1_DNC2':
 C_SIGNAL='@t6g_mb_lib.t6g(sch_1):nc_pvdd11_s3_p1_dnc2';
NODE_NAME     PU45 31
 '@T6G_MB_LIB.T6G(SCH_1):PAGE200_I92@PURE_QUANTA.ISL99390FRZTR5935(CHIPS)':
 'DNC': CDS_PINID='DNC';
NET_NAME
'NC_PVDD11_S3_P1_GL1_1'
 '@T6G_MB_LIB.T6G(SCH_1):NC_PVDD11_S3_P1_GL1_1':
 C_SIGNAL='@t6g_mb_lib.t6g(sch_1):nc_pvdd11_s3_p1_gl1_1';
NODE_NAME     PU44 6
 '@T6G_MB_LIB.T6G(SCH_1):PAGE200_I22@PURE_QUANTA.ISL99390FRZTR5935(CHIPS)':
 'GL1': CDS_PINID='GL1';
NET_NAME
'NC_PVDD11_S3_P1_GL1_2'
 '@T6G_MB_LIB.T6G(SCH_1):NC_PVDD11_S3_P1_GL1_2':
 C_SIGNAL='@t6g_mb_lib.t6g(sch_1):nc_pvdd11_s3_p1_gl1_2';
NODE_NAME     PU45 6
 '@T6G_MB_LIB.T6G(SCH_1):PAGE200_I92@PURE_QUANTA.ISL99390FRZTR5935(CHIPS)':
 'GL1': CDS_PINID='GL1';
NET_NAME
'NC_PVDD11_S3_P1_GL2_1'
 '@T6G_MB_LIB.T6G(SCH_1):NC_PVDD11_S3_P1_GL2_1':
 C_SIGNAL='@t6g_mb_lib.t6g(sch_1):nc_pvdd11_s3_p1_gl2_1';
NODE_NAME     PU44 41
 '@T6G_MB_LIB.T6G(SCH_1):PAGE200_I22@PURE_QUANTA.ISL99390FRZTR5935(CHIPS)':
 'GL2': CDS_PINID='GL2';
NET_NAME
'NC_PVDD11_S3_P1_GL2_2'
 '@T6G_MB_LIB.T6G(SCH_1):NC_PVDD11_S3_P1_GL2_2':
 C_SIGNAL='@t6g_mb_lib.t6g(sch_1):nc_pvdd11_s3_p1_gl2_2';
NODE_NAME     PU45 41
 '@T6G_MB_LIB.T6G(SCH_1):PAGE200_I92@PURE_QUANTA.ISL99390FRZTR5935(CHIPS)':
 'GL2': CDS_PINID='GL2';
NET_NAME
'NC_PVDD11_S3_P1_IMON3'
 '@T6G_MB_LIB.T6G(SCH_1):NC_PVDD11_S3_P1_IMON3':
 C_SIGNAL='@t6g_mb_lib.t6g(sch_1):nc_pvdd11_s3_p1_imon3';
NODE_NAME     PR406 1
 '@T6G_MB_LIB.T6G(SCH_1):PAGE199_I70@PURE_QUANTA.Q_RES(CHIPS)':
 'A': CDS_PINID='A';
NODE_NAME     PU54 25
 '@T6G_MB_LIB.T6G(SCH_1):PAGE199_I86@PURE_QUANTA.RAA229621GNPHA0(CHIPS)':
 'CS5': CDS_PINID='CS5';
NET_NAME
'NC_PVDD11_S3_P1_IMON4'
 '@T6G_MB_LIB.T6G(SCH_1):NC_PVDD11_S3_P1_IMON4':
 C_SIGNAL='@t6g_mb_lib.t6g(sch_1):nc_pvdd11_s3_p1_imon4';
NODE_NAME     PR407 1
 '@T6G_MB_LIB.T6G(SCH_1):PAGE199_I60@PURE_QUANTA.Q_RES(CHIPS)':
 'A': CDS_PINID='A';
NODE_NAME     PU54 26
 '@T6G_MB_LIB.T6G(SCH_1):PAGE199_I86@PURE_QUANTA.RAA229621GNPHA0(CHIPS)':
 'CS4': CDS_PINID='CS4';
NET_NAME
'NC_PVDD11_S3_P1_IMON5'
 '@T6G_MB_LIB.T6G(SCH_1):NC_PVDD11_S3_P1_IMON5':
 C_SIGNAL='@t6g_mb_lib.t6g(sch_1):nc_pvdd11_s3_p1_imon5';
NODE_NAME     PR13 1
 '@T6G_MB_LIB.T6G(SCH_1):PAGE199_I59@PURE_QUANTA.Q_RES(CHIPS)':
 'A': CDS_PINID='A';
NODE_NAME     PU54 27
 '@T6G_MB_LIB.T6G(SCH_1):PAGE199_I86@PURE_QUANTA.RAA229621GNPHA0(CHIPS)':
 'CS3': CDS_PINID='CS3';
NET_NAME
'NC_PVDD11_S3_P1_IMON6'
 '@T6G_MB_LIB.T6G(SCH_1):NC_PVDD11_S3_P1_IMON6':
 C_SIGNAL='@t6g_mb_lib.t6g(sch_1):nc_pvdd11_s3_p1_imon6';
NODE_NAME     PR14 1
 '@T6G_MB_LIB.T6G(SCH_1):PAGE199_I58@PURE_QUANTA.Q_RES(CHIPS)':
 'A': CDS_PINID='A';
NODE_NAME     PU54 28
 '@T6G_MB_LIB.T6G(SCH_1):PAGE199_I86@PURE_QUANTA.RAA229621GNPHA0(CHIPS)':
 'CS2': CDS_PINID='CS2';
NET_NAME
'NC_PVDD11_S3_P1_IMON7'
 '@T6G_MB_LIB.T6G(SCH_1):NC_PVDD11_S3_P1_IMON7':
 C_SIGNAL='@t6g_mb_lib.t6g(sch_1):nc_pvdd11_s3_p1_imon7';
NODE_NAME     PR408 1
 '@T6G_MB_LIB.T6G(SCH_1):PAGE199_I57@PURE_QUANTA.Q_RES(CHIPS)':
 'A': CDS_PINID='A';
NODE_NAME     PU54 29
 '@T6G_MB_LIB.T6G(SCH_1):PAGE199_I86@PURE_QUANTA.RAA229621GNPHA0(CHIPS)':
 'CS1': CDS_PINID='CS1';
NET_NAME
'NC_PVDD11_S3_P1_IMON8'
 '@T6G_MB_LIB.T6G(SCH_1):NC_PVDD11_S3_P1_IMON8':
 C_SIGNAL='@t6g_mb_lib.t6g(sch_1):nc_pvdd11_s3_p1_imon8';
NODE_NAME     PR409 1
 '@T6G_MB_LIB.T6G(SCH_1):PAGE199_I52@PURE_QUANTA.Q_RES(CHIPS)':
 'A': CDS_PINID='A';
NODE_NAME     PU54 30
 '@T6G_MB_LIB.T6G(SCH_1):PAGE199_I86@PURE_QUANTA.RAA229621GNPHA0(CHIPS)':
 'CS0': CDS_PINID='CS0';
NET_NAME
'NC_PVDD11_S3_P1_PG1'
 '@T6G_MB_LIB.T6G(SCH_1):NC_PVDD11_S3_P1_PG1':
 C_SIGNAL='@t6g_mb_lib.t6g(sch_1):nc_pvdd11_s3_p1_pg1';
NODE_NAME     PU54 16
 '@T6G_MB_LIB.T6G(SCH_1):PAGE199_I86@PURE_QUANTA.RAA229621GNPHA0(CHIPS)':
 'PG1': CDS_PINID='PG1';
NET_NAME
'NC_PVDD11_S3_P1_PWM3'
 '@T6G_MB_LIB.T6G(SCH_1):NC_PVDD11_S3_P1_PWM3':
 C_SIGNAL='@t6g_mb_lib.t6g(sch_1):nc_pvdd11_s3_p1_pwm3';
NODE_NAME     PU54 6
 '@T6G_MB_LIB.T6G(SCH_1):PAGE199_I86@PURE_QUANTA.RAA229621GNPHA0(CHIPS)':
 'PWM5': CDS_PINID='PWM5';
NET_NAME
'NC_PVDD11_S3_P1_PWM4'
 '@T6G_MB_LIB.T6G(SCH_1):NC_PVDD11_S3_P1_PWM4':
 C_SIGNAL='@t6g_mb_lib.t6g(sch_1):nc_pvdd11_s3_p1_pwm4';
NODE_NAME     PU54 5
 '@T6G_MB_LIB.T6G(SCH_1):PAGE199_I86@PURE_QUANTA.RAA229621GNPHA0(CHIPS)':
 'PWM4': CDS_PINID='PWM4';
NET_NAME
'NC_PVDD11_S3_P1_PWM5'
 '@T6G_MB_LIB.T6G(SCH_1):NC_PVDD11_S3_P1_PWM5':
 C_SIGNAL='@t6g_mb_lib.t6g(sch_1):nc_pvdd11_s3_p1_pwm5';
NODE_NAME     PU54 4
 '@T6G_MB_LIB.T6G(SCH_1):PAGE199_I86@PURE_QUANTA.RAA229621GNPHA0(CHIPS)':
 'PWM3': CDS_PINID='PWM3';
NET_NAME
'NC_PVDD11_S3_P1_PWM6'
 '@T6G_MB_LIB.T6G(SCH_1):NC_PVDD11_S3_P1_PWM6':
 C_SIGNAL='@t6g_mb_lib.t6g(sch_1):nc_pvdd11_s3_p1_pwm6';
NODE_NAME     PU54 3
 '@T6G_MB_LIB.T6G(SCH_1):PAGE199_I86@PURE_QUANTA.RAA229621GNPHA0(CHIPS)':
 'PWM2': CDS_PINID='PWM2';
NET_NAME
'NC_PVDD11_S3_P1_PWM7'
 '@T6G_MB_LIB.T6G(SCH_1):NC_PVDD11_S3_P1_PWM7':
 C_SIGNAL='@t6g_mb_lib.t6g(sch_1):nc_pvdd11_s3_p1_pwm7';
NODE_NAME     PU54 2
 '@T6G_MB_LIB.T6G(SCH_1):PAGE199_I86@PURE_QUANTA.RAA229621GNPHA0(CHIPS)':
 'PWM1': CDS_PINID='PWM1';
NET_NAME
'NC_PVDD11_S3_P1_PWM8'
 '@T6G_MB_LIB.T6G(SCH_1):NC_PVDD11_S3_P1_PWM8':
 C_SIGNAL='@t6g_mb_lib.t6g(sch_1):nc_pvdd11_s3_p1_pwm8';
NODE_NAME     PU54 1
 '@T6G_MB_LIB.T6G(SCH_1):PAGE199_I86@PURE_QUANTA.RAA229621GNPHA0(CHIPS)':
 'PWM0': CDS_PINID='PWM0';
NET_NAME
'NC_PVDD11_S3_P1_SVTO'
 '@T6G_MB_LIB.T6G(SCH_1):NC_PVDD11_S3_P1_SVTO':
 C_SIGNAL='@t6g_mb_lib.t6g(sch_1):nc_pvdd11_s3_p1_svto';
NODE_NAME     PU54 19
 '@T6G_MB_LIB.T6G(SCH_1):PAGE199_I86@PURE_QUANTA.RAA229621GNPHA0(CHIPS)':
 'SVTO': CDS_PINID='SVTO';
NET_NAME
'NC_PVDDCR_CPU0_P0_DNC1'
 '@T6G_MB_LIB.T6G(SCH_1):NC_PVDDCR_CPU0_P0_DNC1':
 C_SIGNAL='@t6g_mb_lib.t6g(sch_1):nc_pvddcr_cpu0_p0_dnc1';
NODE_NAME     PU6 31
 '@T6G_MB_LIB.T6G(SCH_1):PAGE169_I26@PURE_QUANTA.ISL99390FRZTR5935(CHIPS)':
 'DNC': CDS_PINID='DNC';
NET_NAME
'NC_PVDDCR_CPU0_P0_DNC2'
 '@T6G_MB_LIB.T6G(SCH_1):NC_PVDDCR_CPU0_P0_DNC2':
 C_SIGNAL='@t6g_mb_lib.t6g(sch_1):nc_pvddcr_cpu0_p0_dnc2';
NODE_NAME     PU43 31
 '@T6G_MB_LIB.T6G(SCH_1):PAGE169_I16@PURE_QUANTA.ISL99390FRZTR5935(CHIPS)':
 'DNC': CDS_PINID='DNC';
NET_NAME
'NC_PVDDCR_CPU0_P0_DNC3'
 '@T6G_MB_LIB.T6G(SCH_1):NC_PVDDCR_CPU0_P0_DNC3':
 C_SIGNAL='@t6g_mb_lib.t6g(sch_1):nc_pvddcr_cpu0_p0_dnc3';
NODE_NAME     PU46 31
 '@T6G_MB_LIB.T6G(SCH_1):PAGE170_I38@PURE_QUANTA.ISL99390FRZTR5935(CHIPS)':
 'DNC': CDS_PINID='DNC';
NET_NAME
'NC_PVDDCR_CPU0_P0_DNC4'
 '@T6G_MB_LIB.T6G(SCH_1):NC_PVDDCR_CPU0_P0_DNC4':
 C_SIGNAL='@t6g_mb_lib.t6g(sch_1):nc_pvddcr_cpu0_p0_dnc4';
NODE_NAME     PU47 31
 '@T6G_MB_LIB.T6G(SCH_1):PAGE170_I9@PURE_QUANTA.ISL99390FRZTR5935(CHIPS)':
 'DNC': CDS_PINID='DNC';
NET_NAME
'NC_PVDDCR_CPU0_P0_DNC5'
 '@T6G_MB_LIB.T6G(SCH_1):NC_PVDDCR_CPU0_P0_DNC5':
 C_SIGNAL='@t6g_mb_lib.t6g(sch_1):nc_pvddcr_cpu0_p0_dnc5';
NODE_NAME     PU48 31
 '@T6G_MB_LIB.T6G(SCH_1):PAGE171_I18@PURE_QUANTA.ISL99390FRZTR5935(CHIPS)':
 'DNC': CDS_PINID='DNC';
NET_NAME
'NC_PVDDCR_CPU0_P0_DNC6'
 '@T6G_MB_LIB.T6G(SCH_1):NC_PVDDCR_CPU0_P0_DNC6':
 C_SIGNAL='@t6g_mb_lib.t6g(sch_1):nc_pvddcr_cpu0_p0_dnc6';
NODE_NAME     PU10 31
 '@T6G_MB_LIB.T6G(SCH_1):PAGE171_I73@PURE_QUANTA.ISL99390FRZTR5935(CHIPS)':
 'DNC': CDS_PINID='DNC';
NET_NAME
'NC_PVDDCR_CPU0_P0_GL1_1'
 '@T6G_MB_LIB.T6G(SCH_1):NC_PVDDCR_CPU0_P0_GL1_1':
 C_SIGNAL='@t6g_mb_lib.t6g(sch_1):nc_pvddcr_cpu0_p0_gl1_1';
NODE_NAME     PU6 6
 '@T6G_MB_LIB.T6G(SCH_1):PAGE169_I26@PURE_QUANTA.ISL99390FRZTR5935(CHIPS)':
 'GL1': CDS_PINID='GL1';
NET_NAME
'NC_PVDDCR_CPU0_P0_GL1_2'
 '@T6G_MB_LIB.T6G(SCH_1):NC_PVDDCR_CPU0_P0_GL1_2':
 C_SIGNAL='@t6g_mb_lib.t6g(sch_1):nc_pvddcr_cpu0_p0_gl1_2';
NODE_NAME     PU43 6
 '@T6G_MB_LIB.T6G(SCH_1):PAGE169_I16@PURE_QUANTA.ISL99390FRZTR5935(CHIPS)':
 'GL1': CDS_PINID='GL1';
NET_NAME
'NC_PVDDCR_CPU0_P0_GL1_3'
 '@T6G_MB_LIB.T6G(SCH_1):NC_PVDDCR_CPU0_P0_GL1_3':
 C_SIGNAL='@t6g_mb_lib.t6g(sch_1):nc_pvddcr_cpu0_p0_gl1_3';
NODE_NAME     PU46 6
 '@T6G_MB_LIB.T6G(SCH_1):PAGE170_I38@PURE_QUANTA.ISL99390FRZTR5935(CHIPS)':
 'GL1': CDS_PINID='GL1';
NET_NAME
'NC_PVDDCR_CPU0_P0_GL1_4'
 '@T6G_MB_LIB.T6G(SCH_1):NC_PVDDCR_CPU0_P0_GL1_4':
 C_SIGNAL='@t6g_mb_lib.t6g(sch_1):nc_pvddcr_cpu0_p0_gl1_4';
NODE_NAME     PU47 6
 '@T6G_MB_LIB.T6G(SCH_1):PAGE170_I9@PURE_QUANTA.ISL99390FRZTR5935(CHIPS)':
 'GL1': CDS_PINID='GL1';
NET_NAME
'NC_PVDDCR_CPU0_P0_GL1_5'
 '@T6G_MB_LIB.T6G(SCH_1):NC_PVDDCR_CPU0_P0_GL1_5':
 C_SIGNAL='@t6g_mb_lib.t6g(sch_1):nc_pvddcr_cpu0_p0_gl1_5';
NODE_NAME     PU48 6
 '@T6G_MB_LIB.T6G(SCH_1):PAGE171_I18@PURE_QUANTA.ISL99390FRZTR5935(CHIPS)':
 'GL1': CDS_PINID='GL1';
NET_NAME
'NC_PVDDCR_CPU0_P0_GL1_6'
 '@T6G_MB_LIB.T6G(SCH_1):NC_PVDDCR_CPU0_P0_GL1_6':
 C_SIGNAL='@t6g_mb_lib.t6g(sch_1):nc_pvddcr_cpu0_p0_gl1_6';
NODE_NAME     PU10 6
 '@T6G_MB_LIB.T6G(SCH_1):PAGE171_I73@PURE_QUANTA.ISL99390FRZTR5935(CHIPS)':
 'GL1': CDS_PINID='GL1';
NET_NAME
'NC_PVDDCR_CPU0_P0_GL2_1'
 '@T6G_MB_LIB.T6G(SCH_1):NC_PVDDCR_CPU0_P0_GL2_1':
 C_SIGNAL='@t6g_mb_lib.t6g(sch_1):nc_pvddcr_cpu0_p0_gl2_1';
NODE_NAME     PU6 41
 '@T6G_MB_LIB.T6G(SCH_1):PAGE169_I26@PURE_QUANTA.ISL99390FRZTR5935(CHIPS)':
 'GL2': CDS_PINID='GL2';
NET_NAME
'NC_PVDDCR_CPU0_P0_GL2_2'
 '@T6G_MB_LIB.T6G(SCH_1):NC_PVDDCR_CPU0_P0_GL2_2':
 C_SIGNAL='@t6g_mb_lib.t6g(sch_1):nc_pvddcr_cpu0_p0_gl2_2';
NODE_NAME     PU43 41
 '@T6G_MB_LIB.T6G(SCH_1):PAGE169_I16@PURE_QUANTA.ISL99390FRZTR5935(CHIPS)':
 'GL2': CDS_PINID='GL2';
NET_NAME
'NC_PVDDCR_CPU0_P0_GL2_3'
 '@T6G_MB_LIB.T6G(SCH_1):NC_PVDDCR_CPU0_P0_GL2_3':
 C_SIGNAL='@t6g_mb_lib.t6g(sch_1):nc_pvddcr_cpu0_p0_gl2_3';
NODE_NAME     PU46 41
 '@T6G_MB_LIB.T6G(SCH_1):PAGE170_I38@PURE_QUANTA.ISL99390FRZTR5935(CHIPS)':
 'GL2': CDS_PINID='GL2';
NET_NAME
'NC_PVDDCR_CPU0_P0_GL2_4'
 '@T6G_MB_LIB.T6G(SCH_1):NC_PVDDCR_CPU0_P0_GL2_4':
 C_SIGNAL='@t6g_mb_lib.t6g(sch_1):nc_pvddcr_cpu0_p0_gl2_4';
NODE_NAME     PU47 41
 '@T6G_MB_LIB.T6G(SCH_1):PAGE170_I9@PURE_QUANTA.ISL99390FRZTR5935(CHIPS)':
 'GL2': CDS_PINID='GL2';
NET_NAME
'NC_PVDDCR_CPU0_P0_GL2_5'
 '@T6G_MB_LIB.T6G(SCH_1):NC_PVDDCR_CPU0_P0_GL2_5':
 C_SIGNAL='@t6g_mb_lib.t6g(sch_1):nc_pvddcr_cpu0_p0_gl2_5';
NODE_NAME     PU48 41
 '@T6G_MB_LIB.T6G(SCH_1):PAGE171_I18@PURE_QUANTA.ISL99390FRZTR5935(CHIPS)':
 'GL2': CDS_PINID='GL2';
NET_NAME
'NC_PVDDCR_CPU0_P0_GL2_6'
 '@T6G_MB_LIB.T6G(SCH_1):NC_PVDDCR_CPU0_P0_GL2_6':
 C_SIGNAL='@t6g_mb_lib.t6g(sch_1):nc_pvddcr_cpu0_p0_gl2_6';
NODE_NAME     PU10 41
 '@T6G_MB_LIB.T6G(SCH_1):PAGE171_I73@PURE_QUANTA.ISL99390FRZTR5935(CHIPS)':
 'GL2': CDS_PINID='GL2';
NET_NAME
'NC_PVDDCR_CPU0_P0_IMON7'
 '@T6G_MB_LIB.T6G(SCH_1):NC_PVDDCR_CPU0_P0_IMON7':
 C_SIGNAL='@t6g_mb_lib.t6g(sch_1):nc_pvddcr_cpu0_p0_imon7';
NODE_NAME     PR531 1
 '@T6G_MB_LIB.T6G(SCH_1):PAGE168_I111@PURE_QUANTA.Q_RES(CHIPS)':
 'A': CDS_PINID='A';
NODE_NAME     PU42 33
 '@T6G_MB_LIB.T6G(SCH_1):PAGE168_I135@PURE_QUANTA.RAA229620GNPHA0(CHIPS)':
 'CS5': CDS_PINID='CS5';
NET_NAME
'NC_PVDDCR_CPU0_P0_IMON8'
 '@T6G_MB_LIB.T6G(SCH_1):NC_PVDDCR_CPU0_P0_IMON8':
 C_SIGNAL='@t6g_mb_lib.t6g(sch_1):nc_pvddcr_cpu0_p0_imon8';
NODE_NAME     PR440 1
 '@T6G_MB_LIB.T6G(SCH_1):PAGE168_I108@PURE_QUANTA.Q_RES(CHIPS)':
 'A': CDS_PINID='A';
NODE_NAME     PU42 34
 '@T6G_MB_LIB.T6G(SCH_1):PAGE168_I135@PURE_QUANTA.RAA229620GNPHA0(CHIPS)':
 'CS4': CDS_PINID='CS4';
NET_NAME
'NC_PVDDCR_CPU0_P0_IMON9'
 '@T6G_MB_LIB.T6G(SCH_1):NC_PVDDCR_CPU0_P0_IMON9':
 C_SIGNAL='@t6g_mb_lib.t6g(sch_1):nc_pvddcr_cpu0_p0_imon9';
NODE_NAME     PR441 1
 '@T6G_MB_LIB.T6G(SCH_1):PAGE168_I107@PURE_QUANTA.Q_RES(CHIPS)':
 'A': CDS_PINID='A';
NODE_NAME     PU42 35
 '@T6G_MB_LIB.T6G(SCH_1):PAGE168_I135@PURE_QUANTA.RAA229620GNPHA0(CHIPS)':
 'CS3': CDS_PINID='CS3';
NET_NAME
'NC_PVDDCR_CPU0_P0_PWM7'
 '@T6G_MB_LIB.T6G(SCH_1):NC_PVDDCR_CPU0_P0_PWM7':
 C_SIGNAL='@t6g_mb_lib.t6g(sch_1):nc_pvddcr_cpu0_p0_pwm7';
NODE_NAME     PU42 6
 '@T6G_MB_LIB.T6G(SCH_1):PAGE168_I135@PURE_QUANTA.RAA229620GNPHA0(CHIPS)':
 'PWM5': CDS_PINID='PWM5';
NET_NAME
'NC_PVDDCR_CPU0_P0_PWM8'
 '@T6G_MB_LIB.T6G(SCH_1):NC_PVDDCR_CPU0_P0_PWM8':
 C_SIGNAL='@t6g_mb_lib.t6g(sch_1):nc_pvddcr_cpu0_p0_pwm8';
NODE_NAME     PU42 5
 '@T6G_MB_LIB.T6G(SCH_1):PAGE168_I135@PURE_QUANTA.RAA229620GNPHA0(CHIPS)':
 'PWM4': CDS_PINID='PWM4';
NET_NAME
'NC_PVDDCR_CPU0_P0_PWM9'
 '@T6G_MB_LIB.T6G(SCH_1):NC_PVDDCR_CPU0_P0_PWM9':
 C_SIGNAL='@t6g_mb_lib.t6g(sch_1):nc_pvddcr_cpu0_p0_pwm9';
NODE_NAME     PU42 4
 '@T6G_MB_LIB.T6G(SCH_1):PAGE168_I135@PURE_QUANTA.RAA229620GNPHA0(CHIPS)':
 'PWM3': CDS_PINID='PWM3';
NET_NAME
'NC_PVDDCR_CPU0_P1_DNC1'
 '@T6G_MB_LIB.T6G(SCH_1):NC_PVDDCR_CPU0_P1_DNC1':
 C_SIGNAL='@t6g_mb_lib.t6g(sch_1):nc_pvddcr_cpu0_p1_dnc1';
NODE_NAME     PU4 31
 '@T6G_MB_LIB.T6G(SCH_1):PAGE186_I88@PURE_QUANTA.ISL99390FRZTR5935(CHIPS)':
 'DNC': CDS_PINID='DNC';
NET_NAME
'NC_PVDDCR_CPU0_P1_DNC2'
 '@T6G_MB_LIB.T6G(SCH_1):NC_PVDDCR_CPU0_P1_DNC2':
 C_SIGNAL='@t6g_mb_lib.t6g(sch_1):nc_pvddcr_cpu0_p1_dnc2';
NODE_NAME     PU26 31
 '@T6G_MB_LIB.T6G(SCH_1):PAGE186_I91@PURE_QUANTA.ISL99390FRZTR5935(CHIPS)':
 'DNC': CDS_PINID='DNC';
NET_NAME
'NC_PVDDCR_CPU0_P1_DNC3'
 '@T6G_MB_LIB.T6G(SCH_1):NC_PVDDCR_CPU0_P1_DNC3':
 C_SIGNAL='@t6g_mb_lib.t6g(sch_1):nc_pvddcr_cpu0_p1_dnc3';
NODE_NAME     PU27 31
 '@T6G_MB_LIB.T6G(SCH_1):PAGE187_I39@PURE_QUANTA.ISL99390FRZTR5935(CHIPS)':
 'DNC': CDS_PINID='DNC';
NET_NAME
'NC_PVDDCR_CPU0_P1_DNC4'
 '@T6G_MB_LIB.T6G(SCH_1):NC_PVDDCR_CPU0_P1_DNC4':
 C_SIGNAL='@t6g_mb_lib.t6g(sch_1):nc_pvddcr_cpu0_p1_dnc4';
NODE_NAME     PU28 31
 '@T6G_MB_LIB.T6G(SCH_1):PAGE187_I9@PURE_QUANTA.ISL99390FRZTR5935(CHIPS)':
 'DNC': CDS_PINID='DNC';
NET_NAME
'NC_PVDDCR_CPU0_P1_DNC5'
 '@T6G_MB_LIB.T6G(SCH_1):NC_PVDDCR_CPU0_P1_DNC5':
 C_SIGNAL='@t6g_mb_lib.t6g(sch_1):nc_pvddcr_cpu0_p1_dnc5';
NODE_NAME     PU29 31
 '@T6G_MB_LIB.T6G(SCH_1):PAGE188_I18@PURE_QUANTA.ISL99390FRZTR5935(CHIPS)':
 'DNC': CDS_PINID='DNC';
NET_NAME
'NC_PVDDCR_CPU0_P1_DNC6'
 '@T6G_MB_LIB.T6G(SCH_1):NC_PVDDCR_CPU0_P1_DNC6':
 C_SIGNAL='@t6g_mb_lib.t6g(sch_1):nc_pvddcr_cpu0_p1_dnc6';
NODE_NAME     PU24 31
 '@T6G_MB_LIB.T6G(SCH_1):PAGE188_I73@PURE_QUANTA.ISL99390FRZTR5935(CHIPS)':
 'DNC': CDS_PINID='DNC';
NET_NAME
'NC_PVDDCR_CPU0_P1_GL1_1'
 '@T6G_MB_LIB.T6G(SCH_1):NC_PVDDCR_CPU0_P1_GL1_1':
 C_SIGNAL='@t6g_mb_lib.t6g(sch_1):nc_pvddcr_cpu0_p1_gl1_1';
NODE_NAME     PU4 6
 '@T6G_MB_LIB.T6G(SCH_1):PAGE186_I88@PURE_QUANTA.ISL99390FRZTR5935(CHIPS)':
 'GL1': CDS_PINID='GL1';
NET_NAME
'NC_PVDDCR_CPU0_P1_GL1_2'
 '@T6G_MB_LIB.T6G(SCH_1):NC_PVDDCR_CPU0_P1_GL1_2':
 C_SIGNAL='@t6g_mb_lib.t6g(sch_1):nc_pvddcr_cpu0_p1_gl1_2';
NODE_NAME     PU26 6
 '@T6G_MB_LIB.T6G(SCH_1):PAGE186_I91@PURE_QUANTA.ISL99390FRZTR5935(CHIPS)':
 'GL1': CDS_PINID='GL1';
NET_NAME
'NC_PVDDCR_CPU0_P1_GL1_3'
 '@T6G_MB_LIB.T6G(SCH_1):NC_PVDDCR_CPU0_P1_GL1_3':
 C_SIGNAL='@t6g_mb_lib.t6g(sch_1):nc_pvddcr_cpu0_p1_gl1_3';
NODE_NAME     PU27 6
 '@T6G_MB_LIB.T6G(SCH_1):PAGE187_I39@PURE_QUANTA.ISL99390FRZTR5935(CHIPS)':
 'GL1': CDS_PINID='GL1';
NET_NAME
'NC_PVDDCR_CPU0_P1_GL1_4'
 '@T6G_MB_LIB.T6G(SCH_1):NC_PVDDCR_CPU0_P1_GL1_4':
 C_SIGNAL='@t6g_mb_lib.t6g(sch_1):nc_pvddcr_cpu0_p1_gl1_4';
NODE_NAME     PU28 6
 '@T6G_MB_LIB.T6G(SCH_1):PAGE187_I9@PURE_QUANTA.ISL99390FRZTR5935(CHIPS)':
 'GL1': CDS_PINID='GL1';
NET_NAME
'NC_PVDDCR_CPU0_P1_GL1_5'
 '@T6G_MB_LIB.T6G(SCH_1):NC_PVDDCR_CPU0_P1_GL1_5':
 C_SIGNAL='@t6g_mb_lib.t6g(sch_1):nc_pvddcr_cpu0_p1_gl1_5';
NODE_NAME     PU29 6
 '@T6G_MB_LIB.T6G(SCH_1):PAGE188_I18@PURE_QUANTA.ISL99390FRZTR5935(CHIPS)':
 'GL1': CDS_PINID='GL1';
NET_NAME
'NC_PVDDCR_CPU0_P1_GL1_6'
 '@T6G_MB_LIB.T6G(SCH_1):NC_PVDDCR_CPU0_P1_GL1_6':
 C_SIGNAL='@t6g_mb_lib.t6g(sch_1):nc_pvddcr_cpu0_p1_gl1_6';
NODE_NAME     PU24 6
 '@T6G_MB_LIB.T6G(SCH_1):PAGE188_I73@PURE_QUANTA.ISL99390FRZTR5935(CHIPS)':
 'GL1': CDS_PINID='GL1';
NET_NAME
'NC_PVDDCR_CPU0_P1_GL2_1'
 '@T6G_MB_LIB.T6G(SCH_1):NC_PVDDCR_CPU0_P1_GL2_1':
 C_SIGNAL='@t6g_mb_lib.t6g(sch_1):nc_pvddcr_cpu0_p1_gl2_1';
NODE_NAME     PU4 41
 '@T6G_MB_LIB.T6G(SCH_1):PAGE186_I88@PURE_QUANTA.ISL99390FRZTR5935(CHIPS)':
 'GL2': CDS_PINID='GL2';
NET_NAME
'NC_PVDDCR_CPU0_P1_GL2_2'
 '@T6G_MB_LIB.T6G(SCH_1):NC_PVDDCR_CPU0_P1_GL2_2':
 C_SIGNAL='@t6g_mb_lib.t6g(sch_1):nc_pvddcr_cpu0_p1_gl2_2';
NODE_NAME     PU26 41
 '@T6G_MB_LIB.T6G(SCH_1):PAGE186_I91@PURE_QUANTA.ISL99390FRZTR5935(CHIPS)':
 'GL2': CDS_PINID='GL2';
NET_NAME
'NC_PVDDCR_CPU0_P1_GL2_3'
 '@T6G_MB_LIB.T6G(SCH_1):NC_PVDDCR_CPU0_P1_GL2_3':
 C_SIGNAL='@t6g_mb_lib.t6g(sch_1):nc_pvddcr_cpu0_p1_gl2_3';
NODE_NAME     PU27 41
 '@T6G_MB_LIB.T6G(SCH_1):PAGE187_I39@PURE_QUANTA.ISL99390FRZTR5935(CHIPS)':
 'GL2': CDS_PINID='GL2';
NET_NAME
'NC_PVDDCR_CPU0_P1_GL2_4'
 '@T6G_MB_LIB.T6G(SCH_1):NC_PVDDCR_CPU0_P1_GL2_4':
 C_SIGNAL='@t6g_mb_lib.t6g(sch_1):nc_pvddcr_cpu0_p1_gl2_4';
NODE_NAME     PU28 41
 '@T6G_MB_LIB.T6G(SCH_1):PAGE187_I9@PURE_QUANTA.ISL99390FRZTR5935(CHIPS)':
 'GL2': CDS_PINID='GL2';
NET_NAME
'NC_PVDDCR_CPU0_P1_GL2_5'
 '@T6G_MB_LIB.T6G(SCH_1):NC_PVDDCR_CPU0_P1_GL2_5':
 C_SIGNAL='@t6g_mb_lib.t6g(sch_1):nc_pvddcr_cpu0_p1_gl2_5';
NODE_NAME     PU29 41
 '@T6G_MB_LIB.T6G(SCH_1):PAGE188_I18@PURE_QUANTA.ISL99390FRZTR5935(CHIPS)':
 'GL2': CDS_PINID='GL2';
NET_NAME
'NC_PVDDCR_CPU0_P1_GL2_6'
 '@T6G_MB_LIB.T6G(SCH_1):NC_PVDDCR_CPU0_P1_GL2_6':
 C_SIGNAL='@t6g_mb_lib.t6g(sch_1):nc_pvddcr_cpu0_p1_gl2_6';
NODE_NAME     PU24 41
 '@T6G_MB_LIB.T6G(SCH_1):PAGE188_I73@PURE_QUANTA.ISL99390FRZTR5935(CHIPS)':
 'GL2': CDS_PINID='GL2';
NET_NAME
'NC_PVDDCR_CPU0_P1_IMON7'
 '@T6G_MB_LIB.T6G(SCH_1):NC_PVDDCR_CPU0_P1_IMON7':
 C_SIGNAL='@t6g_mb_lib.t6g(sch_1):nc_pvddcr_cpu0_p1_imon7';
NODE_NAME     PR530 1
 '@T6G_MB_LIB.T6G(SCH_1):PAGE185_I107@PURE_QUANTA.Q_RES(CHIPS)':
 'A': CDS_PINID='A';
NODE_NAME     PU25 33
 '@T6G_MB_LIB.T6G(SCH_1):PAGE185_I133@PURE_QUANTA.RAA229620GNPHA0(CHIPS)':
 'CS5': CDS_PINID='CS5';
NET_NAME
'NC_PVDDCR_CPU0_P1_IMON8'
 '@T6G_MB_LIB.T6G(SCH_1):NC_PVDDCR_CPU0_P1_IMON8':
 C_SIGNAL='@t6g_mb_lib.t6g(sch_1):nc_pvddcr_cpu0_p1_imon8';
NODE_NAME     PR436 1
 '@T6G_MB_LIB.T6G(SCH_1):PAGE185_I103@PURE_QUANTA.Q_RES(CHIPS)':
 'A': CDS_PINID='A';
NODE_NAME     PU25 34
 '@T6G_MB_LIB.T6G(SCH_1):PAGE185_I133@PURE_QUANTA.RAA229620GNPHA0(CHIPS)':
 'CS4': CDS_PINID='CS4';
NET_NAME
'NC_PVDDCR_CPU0_P1_IMON9'
 '@T6G_MB_LIB.T6G(SCH_1):NC_PVDDCR_CPU0_P1_IMON9':
 C_SIGNAL='@t6g_mb_lib.t6g(sch_1):nc_pvddcr_cpu0_p1_imon9';
NODE_NAME     PR437 1
 '@T6G_MB_LIB.T6G(SCH_1):PAGE185_I102@PURE_QUANTA.Q_RES(CHIPS)':
 'A': CDS_PINID='A';
NODE_NAME     PU25 35
 '@T6G_MB_LIB.T6G(SCH_1):PAGE185_I133@PURE_QUANTA.RAA229620GNPHA0(CHIPS)':
 'CS3': CDS_PINID='CS3';
NET_NAME
'NC_PVDDCR_CPU0_P1_PWM7'
 '@T6G_MB_LIB.T6G(SCH_1):NC_PVDDCR_CPU0_P1_PWM7':
 C_SIGNAL='@t6g_mb_lib.t6g(sch_1):nc_pvddcr_cpu0_p1_pwm7';
NODE_NAME     PU25 6
 '@T6G_MB_LIB.T6G(SCH_1):PAGE185_I133@PURE_QUANTA.RAA229620GNPHA0(CHIPS)':
 'PWM5': CDS_PINID='PWM5';
NET_NAME
'NC_PVDDCR_CPU0_P1_PWM8'
 '@T6G_MB_LIB.T6G(SCH_1):NC_PVDDCR_CPU0_P1_PWM8':
 C_SIGNAL='@t6g_mb_lib.t6g(sch_1):nc_pvddcr_cpu0_p1_pwm8';
NODE_NAME     PU25 5
 '@T6G_MB_LIB.T6G(SCH_1):PAGE185_I133@PURE_QUANTA.RAA229620GNPHA0(CHIPS)':
 'PWM4': CDS_PINID='PWM4';
NET_NAME
'NC_PVDDCR_CPU0_P1_PWM9'
 '@T6G_MB_LIB.T6G(SCH_1):NC_PVDDCR_CPU0_P1_PWM9':
 C_SIGNAL='@t6g_mb_lib.t6g(sch_1):nc_pvddcr_cpu0_p1_pwm9';
NODE_NAME     PU25 4
 '@T6G_MB_LIB.T6G(SCH_1):PAGE185_I133@PURE_QUANTA.RAA229620GNPHA0(CHIPS)':
 'PWM3': CDS_PINID='PWM3';
NET_NAME
'NC_PVDDCR_CPU1_P0_DNC1'
 '@T6G_MB_LIB.T6G(SCH_1):NC_PVDDCR_CPU1_P0_DNC1':
 C_SIGNAL='@t6g_mb_lib.t6g(sch_1):nc_pvddcr_cpu1_p0_dnc1';
NODE_NAME     PU13 31
 '@T6G_MB_LIB.T6G(SCH_1):PAGE176_I35@PURE_QUANTA.ISL99390FRZTR5935(CHIPS)':
 'DNC': CDS_PINID='DNC';
NET_NAME
'NC_PVDDCR_CPU1_P0_DNC2'
 '@T6G_MB_LIB.T6G(SCH_1):NC_PVDDCR_CPU1_P0_DNC2':
 C_SIGNAL='@t6g_mb_lib.t6g(sch_1):nc_pvddcr_cpu1_p0_dnc2';
NODE_NAME     PU2 31
 '@T6G_MB_LIB.T6G(SCH_1):PAGE176_I33@PURE_QUANTA.ISL99390FRZTR5935(CHIPS)':
 'DNC': CDS_PINID='DNC';
NET_NAME
'NC_PVDDCR_CPU1_P0_DNC3'
 '@T6G_MB_LIB.T6G(SCH_1):NC_PVDDCR_CPU1_P0_DNC3':
 C_SIGNAL='@t6g_mb_lib.t6g(sch_1):nc_pvddcr_cpu1_p0_dnc3';
NODE_NAME     PU15 31
 '@T6G_MB_LIB.T6G(SCH_1):PAGE177_I23@PURE_QUANTA.ISL99390FRZTR5935(CHIPS)':
 'DNC': CDS_PINID='DNC';
NET_NAME
'NC_PVDDCR_CPU1_P0_DNC4'
 '@T6G_MB_LIB.T6G(SCH_1):NC_PVDDCR_CPU1_P0_DNC4':
 C_SIGNAL='@t6g_mb_lib.t6g(sch_1):nc_pvddcr_cpu1_p0_dnc4';
NODE_NAME     PU14 31
 '@T6G_MB_LIB.T6G(SCH_1):PAGE177_I21@PURE_QUANTA.ISL99390FRZTR5935(CHIPS)':
 'DNC': CDS_PINID='DNC';
NET_NAME
'NC_PVDDCR_CPU1_P0_DNC5'
 '@T6G_MB_LIB.T6G(SCH_1):NC_PVDDCR_CPU1_P0_DNC5':
 C_SIGNAL='@t6g_mb_lib.t6g(sch_1):nc_pvddcr_cpu1_p0_dnc5';
NODE_NAME     PU16 31
 '@T6G_MB_LIB.T6G(SCH_1):PAGE178_I22@PURE_QUANTA.ISL99390FRZTR5935(CHIPS)':
 'DNC': CDS_PINID='DNC';
NET_NAME
'NC_PVDDCR_CPU1_P0_DNC6'
 '@T6G_MB_LIB.T6G(SCH_1):NC_PVDDCR_CPU1_P0_DNC6':
 C_SIGNAL='@t6g_mb_lib.t6g(sch_1):nc_pvddcr_cpu1_p0_dnc6';
NODE_NAME     PU11 31
 '@T6G_MB_LIB.T6G(SCH_1):PAGE178_I73@PURE_QUANTA.ISL99390FRZTR5935(CHIPS)':
 'DNC': CDS_PINID='DNC';
NET_NAME
'NC_PVDDCR_CPU1_P0_GL1_1'
 '@T6G_MB_LIB.T6G(SCH_1):NC_PVDDCR_CPU1_P0_GL1_1':
 C_SIGNAL='@t6g_mb_lib.t6g(sch_1):nc_pvddcr_cpu1_p0_gl1_1';
NODE_NAME     PU13 6
 '@T6G_MB_LIB.T6G(SCH_1):PAGE176_I35@PURE_QUANTA.ISL99390FRZTR5935(CHIPS)':
 'GL1': CDS_PINID='GL1';
NET_NAME
'NC_PVDDCR_CPU1_P0_GL1_2'
 '@T6G_MB_LIB.T6G(SCH_1):NC_PVDDCR_CPU1_P0_GL1_2':
 C_SIGNAL='@t6g_mb_lib.t6g(sch_1):nc_pvddcr_cpu1_p0_gl1_2';
NODE_NAME     PU2 6
 '@T6G_MB_LIB.T6G(SCH_1):PAGE176_I33@PURE_QUANTA.ISL99390FRZTR5935(CHIPS)':
 'GL1': CDS_PINID='GL1';
NET_NAME
'NC_PVDDCR_CPU1_P0_GL1_3'
 '@T6G_MB_LIB.T6G(SCH_1):NC_PVDDCR_CPU1_P0_GL1_3':
 C_SIGNAL='@t6g_mb_lib.t6g(sch_1):nc_pvddcr_cpu1_p0_gl1_3';
NODE_NAME     PU15 6
 '@T6G_MB_LIB.T6G(SCH_1):PAGE177_I23@PURE_QUANTA.ISL99390FRZTR5935(CHIPS)':
 'GL1': CDS_PINID='GL1';
NET_NAME
'NC_PVDDCR_CPU1_P0_GL1_4'
 '@T6G_MB_LIB.T6G(SCH_1):NC_PVDDCR_CPU1_P0_GL1_4':
 C_SIGNAL='@t6g_mb_lib.t6g(sch_1):nc_pvddcr_cpu1_p0_gl1_4';
NODE_NAME     PU14 6
 '@T6G_MB_LIB.T6G(SCH_1):PAGE177_I21@PURE_QUANTA.ISL99390FRZTR5935(CHIPS)':
 'GL1': CDS_PINID='GL1';
NET_NAME
'NC_PVDDCR_CPU1_P0_GL1_5'
 '@T6G_MB_LIB.T6G(SCH_1):NC_PVDDCR_CPU1_P0_GL1_5':
 C_SIGNAL='@t6g_mb_lib.t6g(sch_1):nc_pvddcr_cpu1_p0_gl1_5';
NODE_NAME     PU16 6
 '@T6G_MB_LIB.T6G(SCH_1):PAGE178_I22@PURE_QUANTA.ISL99390FRZTR5935(CHIPS)':
 'GL1': CDS_PINID='GL1';
NET_NAME
'NC_PVDDCR_CPU1_P0_GL1_6'
 '@T6G_MB_LIB.T6G(SCH_1):NC_PVDDCR_CPU1_P0_GL1_6':
 C_SIGNAL='@t6g_mb_lib.t6g(sch_1):nc_pvddcr_cpu1_p0_gl1_6';
NODE_NAME     PU11 6
 '@T6G_MB_LIB.T6G(SCH_1):PAGE178_I73@PURE_QUANTA.ISL99390FRZTR5935(CHIPS)':
 'GL1': CDS_PINID='GL1';
NET_NAME
'NC_PVDDCR_CPU1_P0_GL2_1'
 '@T6G_MB_LIB.T6G(SCH_1):NC_PVDDCR_CPU1_P0_GL2_1':
 C_SIGNAL='@t6g_mb_lib.t6g(sch_1):nc_pvddcr_cpu1_p0_gl2_1';
NODE_NAME     PU13 41
 '@T6G_MB_LIB.T6G(SCH_1):PAGE176_I35@PURE_QUANTA.ISL99390FRZTR5935(CHIPS)':
 'GL2': CDS_PINID='GL2';
NET_NAME
'NC_PVDDCR_CPU1_P0_GL2_2'
 '@T6G_MB_LIB.T6G(SCH_1):NC_PVDDCR_CPU1_P0_GL2_2':
 C_SIGNAL='@t6g_mb_lib.t6g(sch_1):nc_pvddcr_cpu1_p0_gl2_2';
NODE_NAME     PU2 41
 '@T6G_MB_LIB.T6G(SCH_1):PAGE176_I33@PURE_QUANTA.ISL99390FRZTR5935(CHIPS)':
 'GL2': CDS_PINID='GL2';
NET_NAME
'NC_PVDDCR_CPU1_P0_GL2_3'
 '@T6G_MB_LIB.T6G(SCH_1):NC_PVDDCR_CPU1_P0_GL2_3':
 C_SIGNAL='@t6g_mb_lib.t6g(sch_1):nc_pvddcr_cpu1_p0_gl2_3';
NODE_NAME     PU15 41
 '@T6G_MB_LIB.T6G(SCH_1):PAGE177_I23@PURE_QUANTA.ISL99390FRZTR5935(CHIPS)':
 'GL2': CDS_PINID='GL2';
NET_NAME
'NC_PVDDCR_CPU1_P0_GL2_4'
 '@T6G_MB_LIB.T6G(SCH_1):NC_PVDDCR_CPU1_P0_GL2_4':
 C_SIGNAL='@t6g_mb_lib.t6g(sch_1):nc_pvddcr_cpu1_p0_gl2_4';
NODE_NAME     PU14 41
 '@T6G_MB_LIB.T6G(SCH_1):PAGE177_I21@PURE_QUANTA.ISL99390FRZTR5935(CHIPS)':
 'GL2': CDS_PINID='GL2';
NET_NAME
'NC_PVDDCR_CPU1_P0_GL2_5'
 '@T6G_MB_LIB.T6G(SCH_1):NC_PVDDCR_CPU1_P0_GL2_5':
 C_SIGNAL='@t6g_mb_lib.t6g(sch_1):nc_pvddcr_cpu1_p0_gl2_5';
NODE_NAME     PU16 41
 '@T6G_MB_LIB.T6G(SCH_1):PAGE178_I22@PURE_QUANTA.ISL99390FRZTR5935(CHIPS)':
 'GL2': CDS_PINID='GL2';
NET_NAME
'NC_PVDDCR_CPU1_P0_GL2_6'
 '@T6G_MB_LIB.T6G(SCH_1):NC_PVDDCR_CPU1_P0_GL2_6':
 C_SIGNAL='@t6g_mb_lib.t6g(sch_1):nc_pvddcr_cpu1_p0_gl2_6';
NODE_NAME     PU11 41
 '@T6G_MB_LIB.T6G(SCH_1):PAGE178_I73@PURE_QUANTA.ISL99390FRZTR5935(CHIPS)':
 'GL2': CDS_PINID='GL2';
NET_NAME
'NC_PVDDCR_CPU1_P0_IMON7'
 '@T6G_MB_LIB.T6G(SCH_1):NC_PVDDCR_CPU1_P0_IMON7':
 C_SIGNAL='@t6g_mb_lib.t6g(sch_1):nc_pvddcr_cpu1_p0_imon7';
NODE_NAME     PR532 1
 '@T6G_MB_LIB.T6G(SCH_1):PAGE175_I76@PURE_QUANTA.Q_RES(CHIPS)':
 'A': CDS_PINID='A';
NODE_NAME     PU12 33
 '@T6G_MB_LIB.T6G(SCH_1):PAGE175_I128@PURE_QUANTA.RAA229620GNPHA0(CHIPS)':
 'CS5': CDS_PINID='CS5';
NET_NAME
'NC_PVDDCR_CPU1_P0_IMON8'
 '@T6G_MB_LIB.T6G(SCH_1):NC_PVDDCR_CPU1_P0_IMON8':
 C_SIGNAL='@t6g_mb_lib.t6g(sch_1):nc_pvddcr_cpu1_p0_imon8';
NODE_NAME     PR32 1
 '@T6G_MB_LIB.T6G(SCH_1):PAGE175_I77@PURE_QUANTA.Q_RES(CHIPS)':
 'A': CDS_PINID='A';
NODE_NAME     PU12 34
 '@T6G_MB_LIB.T6G(SCH_1):PAGE175_I128@PURE_QUANTA.RAA229620GNPHA0(CHIPS)':
 'CS4': CDS_PINID='CS4';
NET_NAME
'NC_PVDDCR_CPU1_P0_PWM7'
 '@T6G_MB_LIB.T6G(SCH_1):NC_PVDDCR_CPU1_P0_PWM7':
 C_SIGNAL='@t6g_mb_lib.t6g(sch_1):nc_pvddcr_cpu1_p0_pwm7';
NODE_NAME     PU12 6
 '@T6G_MB_LIB.T6G(SCH_1):PAGE175_I128@PURE_QUANTA.RAA229620GNPHA0(CHIPS)':
 'PWM5': CDS_PINID='PWM5';
NET_NAME
'NC_PVDDCR_CPU1_P0_PWM8'
 '@T6G_MB_LIB.T6G(SCH_1):NC_PVDDCR_CPU1_P0_PWM8':
 C_SIGNAL='@t6g_mb_lib.t6g(sch_1):nc_pvddcr_cpu1_p0_pwm8';
NODE_NAME     PU12 5
 '@T6G_MB_LIB.T6G(SCH_1):PAGE175_I128@PURE_QUANTA.RAA229620GNPHA0(CHIPS)':
 'PWM4': CDS_PINID='PWM4';
NET_NAME
'NC_PVDDCR_CPU1_P1_DNC1'
 '@T6G_MB_LIB.T6G(SCH_1):NC_PVDDCR_CPU1_P1_DNC1':
 C_SIGNAL='@t6g_mb_lib.t6g(sch_1):nc_pvddcr_cpu1_p1_dnc1';
NODE_NAME     PU35 31
 '@T6G_MB_LIB.T6G(SCH_1):PAGE193_I91@PURE_QUANTA.ISL99390FRZTR5935(CHIPS)':
 'DNC': CDS_PINID='DNC';
NET_NAME
'NC_PVDDCR_CPU1_P1_DNC2'
 '@T6G_MB_LIB.T6G(SCH_1):NC_PVDDCR_CPU1_P1_DNC2':
 C_SIGNAL='@t6g_mb_lib.t6g(sch_1):nc_pvddcr_cpu1_p1_dnc2';
NODE_NAME     PU5 31
 '@T6G_MB_LIB.T6G(SCH_1):PAGE193_I31@PURE_QUANTA.ISL99390FRZTR5935(CHIPS)':
 'DNC': CDS_PINID='DNC';
NET_NAME
'NC_PVDDCR_CPU1_P1_DNC3'
 '@T6G_MB_LIB.T6G(SCH_1):NC_PVDDCR_CPU1_P1_DNC3':
 C_SIGNAL='@t6g_mb_lib.t6g(sch_1):nc_pvddcr_cpu1_p1_dnc3';
NODE_NAME     PU37 31
 '@T6G_MB_LIB.T6G(SCH_1):PAGE194_I72@PURE_QUANTA.ISL99390FRZTR5935(CHIPS)':
 'DNC': CDS_PINID='DNC';
NET_NAME
'NC_PVDDCR_CPU1_P1_DNC4'
 '@T6G_MB_LIB.T6G(SCH_1):NC_PVDDCR_CPU1_P1_DNC4':
 C_SIGNAL='@t6g_mb_lib.t6g(sch_1):nc_pvddcr_cpu1_p1_dnc4';
NODE_NAME     PU36 31
 '@T6G_MB_LIB.T6G(SCH_1):PAGE194_I21@PURE_QUANTA.ISL99390FRZTR5935(CHIPS)':
 'DNC': CDS_PINID='DNC';
NET_NAME
'NC_PVDDCR_CPU1_P1_DNC5'
 '@T6G_MB_LIB.T6G(SCH_1):NC_PVDDCR_CPU1_P1_DNC5':
 C_SIGNAL='@t6g_mb_lib.t6g(sch_1):nc_pvddcr_cpu1_p1_dnc5';
NODE_NAME     PU38 31
 '@T6G_MB_LIB.T6G(SCH_1):PAGE195_I73@PURE_QUANTA.ISL99390FRZTR5935(CHIPS)':
 'DNC': CDS_PINID='DNC';
NET_NAME
'NC_PVDDCR_CPU1_P1_DNC6'
 '@T6G_MB_LIB.T6G(SCH_1):NC_PVDDCR_CPU1_P1_DNC6':
 C_SIGNAL='@t6g_mb_lib.t6g(sch_1):nc_pvddcr_cpu1_p1_dnc6';
NODE_NAME     PU33 31
 '@T6G_MB_LIB.T6G(SCH_1):PAGE195_I19@PURE_QUANTA.ISL99390FRZTR5935(CHIPS)':
 'DNC': CDS_PINID='DNC';
NET_NAME
'NC_PVDDCR_CPU1_P1_GL1_1'
 '@T6G_MB_LIB.T6G(SCH_1):NC_PVDDCR_CPU1_P1_GL1_1':
 C_SIGNAL='@t6g_mb_lib.t6g(sch_1):nc_pvddcr_cpu1_p1_gl1_1';
NODE_NAME     PU35 6
 '@T6G_MB_LIB.T6G(SCH_1):PAGE193_I91@PURE_QUANTA.ISL99390FRZTR5935(CHIPS)':
 'GL1': CDS_PINID='GL1';
NET_NAME
'NC_PVDDCR_CPU1_P1_GL1_2'
 '@T6G_MB_LIB.T6G(SCH_1):NC_PVDDCR_CPU1_P1_GL1_2':
 C_SIGNAL='@t6g_mb_lib.t6g(sch_1):nc_pvddcr_cpu1_p1_gl1_2';
NODE_NAME     PU5 6
 '@T6G_MB_LIB.T6G(SCH_1):PAGE193_I31@PURE_QUANTA.ISL99390FRZTR5935(CHIPS)':
 'GL1': CDS_PINID='GL1';
NET_NAME
'NC_PVDDCR_CPU1_P1_GL1_3'
 '@T6G_MB_LIB.T6G(SCH_1):NC_PVDDCR_CPU1_P1_GL1_3':
 C_SIGNAL='@t6g_mb_lib.t6g(sch_1):nc_pvddcr_cpu1_p1_gl1_3';
NODE_NAME     PU37 6
 '@T6G_MB_LIB.T6G(SCH_1):PAGE194_I72@PURE_QUANTA.ISL99390FRZTR5935(CHIPS)':
 'GL1': CDS_PINID='GL1';
NET_NAME
'NC_PVDDCR_CPU1_P1_GL1_4'
 '@T6G_MB_LIB.T6G(SCH_1):NC_PVDDCR_CPU1_P1_GL1_4':
 C_SIGNAL='@t6g_mb_lib.t6g(sch_1):nc_pvddcr_cpu1_p1_gl1_4';
NODE_NAME     PU36 6
 '@T6G_MB_LIB.T6G(SCH_1):PAGE194_I21@PURE_QUANTA.ISL99390FRZTR5935(CHIPS)':
 'GL1': CDS_PINID='GL1';
NET_NAME
'NC_PVDDCR_CPU1_P1_GL1_5'
 '@T6G_MB_LIB.T6G(SCH_1):NC_PVDDCR_CPU1_P1_GL1_5':
 C_SIGNAL='@t6g_mb_lib.t6g(sch_1):nc_pvddcr_cpu1_p1_gl1_5';
NODE_NAME     PU38 6
 '@T6G_MB_LIB.T6G(SCH_1):PAGE195_I73@PURE_QUANTA.ISL99390FRZTR5935(CHIPS)':
 'GL1': CDS_PINID='GL1';
NET_NAME
'NC_PVDDCR_CPU1_P1_GL1_6'
 '@T6G_MB_LIB.T6G(SCH_1):NC_PVDDCR_CPU1_P1_GL1_6':
 C_SIGNAL='@t6g_mb_lib.t6g(sch_1):nc_pvddcr_cpu1_p1_gl1_6';
NODE_NAME     PU33 6
 '@T6G_MB_LIB.T6G(SCH_1):PAGE195_I19@PURE_QUANTA.ISL99390FRZTR5935(CHIPS)':
 'GL1': CDS_PINID='GL1';
NET_NAME
'NC_PVDDCR_CPU1_P1_GL2_1'
 '@T6G_MB_LIB.T6G(SCH_1):NC_PVDDCR_CPU1_P1_GL2_1':
 C_SIGNAL='@t6g_mb_lib.t6g(sch_1):nc_pvddcr_cpu1_p1_gl2_1';
NODE_NAME     PU35 41
 '@T6G_MB_LIB.T6G(SCH_1):PAGE193_I91@PURE_QUANTA.ISL99390FRZTR5935(CHIPS)':
 'GL2': CDS_PINID='GL2';
NET_NAME
'NC_PVDDCR_CPU1_P1_GL2_2'
 '@T6G_MB_LIB.T6G(SCH_1):NC_PVDDCR_CPU1_P1_GL2_2':
 C_SIGNAL='@t6g_mb_lib.t6g(sch_1):nc_pvddcr_cpu1_p1_gl2_2';
NODE_NAME     PU5 41
 '@T6G_MB_LIB.T6G(SCH_1):PAGE193_I31@PURE_QUANTA.ISL99390FRZTR5935(CHIPS)':
 'GL2': CDS_PINID='GL2';
NET_NAME
'NC_PVDDCR_CPU1_P1_GL2_3'
 '@T6G_MB_LIB.T6G(SCH_1):NC_PVDDCR_CPU1_P1_GL2_3':
 C_SIGNAL='@t6g_mb_lib.t6g(sch_1):nc_pvddcr_cpu1_p1_gl2_3';
NODE_NAME     PU37 41
 '@T6G_MB_LIB.T6G(SCH_1):PAGE194_I72@PURE_QUANTA.ISL99390FRZTR5935(CHIPS)':
 'GL2': CDS_PINID='GL2';
NET_NAME
'NC_PVDDCR_CPU1_P1_GL2_4'
 '@T6G_MB_LIB.T6G(SCH_1):NC_PVDDCR_CPU1_P1_GL2_4':
 C_SIGNAL='@t6g_mb_lib.t6g(sch_1):nc_pvddcr_cpu1_p1_gl2_4';
NODE_NAME     PU36 41
 '@T6G_MB_LIB.T6G(SCH_1):PAGE194_I21@PURE_QUANTA.ISL99390FRZTR5935(CHIPS)':
 'GL2': CDS_PINID='GL2';
NET_NAME
'NC_PVDDCR_CPU1_P1_GL2_5'
 '@T6G_MB_LIB.T6G(SCH_1):NC_PVDDCR_CPU1_P1_GL2_5':
 C_SIGNAL='@t6g_mb_lib.t6g(sch_1):nc_pvddcr_cpu1_p1_gl2_5';
NODE_NAME     PU38 41
 '@T6G_MB_LIB.T6G(SCH_1):PAGE195_I73@PURE_QUANTA.ISL99390FRZTR5935(CHIPS)':
 'GL2': CDS_PINID='GL2';
NET_NAME
'NC_PVDDCR_CPU1_P1_GL2_6'
 '@T6G_MB_LIB.T6G(SCH_1):NC_PVDDCR_CPU1_P1_GL2_6':
 C_SIGNAL='@t6g_mb_lib.t6g(sch_1):nc_pvddcr_cpu1_p1_gl2_6';
NODE_NAME     PU33 41
 '@T6G_MB_LIB.T6G(SCH_1):PAGE195_I19@PURE_QUANTA.ISL99390FRZTR5935(CHIPS)':
 'GL2': CDS_PINID='GL2';
NET_NAME
'NC_PVDDCR_CPU1_P1_IMON7'
 '@T6G_MB_LIB.T6G(SCH_1):NC_PVDDCR_CPU1_P1_IMON7':
 C_SIGNAL='@t6g_mb_lib.t6g(sch_1):nc_pvddcr_cpu1_p1_imon7';
NODE_NAME     PR533 1
 '@T6G_MB_LIB.T6G(SCH_1):PAGE192_I76@PURE_QUANTA.Q_RES(CHIPS)':
 'A': CDS_PINID='A';
NODE_NAME     PU34 33
 '@T6G_MB_LIB.T6G(SCH_1):PAGE192_I128@PURE_QUANTA.RAA229620GNPHA0(CHIPS)':
 'CS5': CDS_PINID='CS5';
NET_NAME
'NC_PVDDCR_CPU1_P1_IMON8'
 '@T6G_MB_LIB.T6G(SCH_1):NC_PVDDCR_CPU1_P1_IMON8':
 C_SIGNAL='@t6g_mb_lib.t6g(sch_1):nc_pvddcr_cpu1_p1_imon8';
NODE_NAME     PR12 1
 '@T6G_MB_LIB.T6G(SCH_1):PAGE192_I127@PURE_QUANTA.Q_RES(CHIPS)':
 'A': CDS_PINID='A';
NODE_NAME     PU34 34
 '@T6G_MB_LIB.T6G(SCH_1):PAGE192_I128@PURE_QUANTA.RAA229620GNPHA0(CHIPS)':
 'CS4': CDS_PINID='CS4';
NET_NAME
'NC_PVDDCR_CPU1_P1_PWM7'
 '@T6G_MB_LIB.T6G(SCH_1):NC_PVDDCR_CPU1_P1_PWM7':
 C_SIGNAL='@t6g_mb_lib.t6g(sch_1):nc_pvddcr_cpu1_p1_pwm7';
NODE_NAME     PU34 6
 '@T6G_MB_LIB.T6G(SCH_1):PAGE192_I128@PURE_QUANTA.RAA229620GNPHA0(CHIPS)':
 'PWM5': CDS_PINID='PWM5';
NET_NAME
'NC_PVDDCR_CPU1_P1_PWM8'
 '@T6G_MB_LIB.T6G(SCH_1):NC_PVDDCR_CPU1_P1_PWM8':
 C_SIGNAL='@t6g_mb_lib.t6g(sch_1):nc_pvddcr_cpu1_p1_pwm8';
NODE_NAME     PU34 5
 '@T6G_MB_LIB.T6G(SCH_1):PAGE192_I128@PURE_QUANTA.RAA229620GNPHA0(CHIPS)':
 'PWM4': CDS_PINID='PWM4';
NET_NAME
'NC_PVDDCR_SOC_P0_DNC1'
 '@T6G_MB_LIB.T6G(SCH_1):NC_PVDDCR_SOC_P0_DNC1':
 C_SIGNAL='@t6g_mb_lib.t6g(sch_1):nc_pvddcr_soc_p0_dnc1';
NODE_NAME     PU49 31
 '@T6G_MB_LIB.T6G(SCH_1):PAGE173_I41@PURE_QUANTA.ISL99390FRZTR5935(CHIPS)':
 'DNC': CDS_PINID='DNC';
NET_NAME
'NC_PVDDCR_SOC_P0_DNC2'
 '@T6G_MB_LIB.T6G(SCH_1):NC_PVDDCR_SOC_P0_DNC2':
 C_SIGNAL='@t6g_mb_lib.t6g(sch_1):nc_pvddcr_soc_p0_dnc2';
NODE_NAME     PU50 31
 '@T6G_MB_LIB.T6G(SCH_1):PAGE173_I86@PURE_QUANTA.ISL99390FRZTR5935(CHIPS)':
 'DNC': CDS_PINID='DNC';
NET_NAME
'NC_PVDDCR_SOC_P0_DNC3'
 '@T6G_MB_LIB.T6G(SCH_1):NC_PVDDCR_SOC_P0_DNC3':
 C_SIGNAL='@t6g_mb_lib.t6g(sch_1):nc_pvddcr_soc_p0_dnc3';
NODE_NAME     PU51 31
 '@T6G_MB_LIB.T6G(SCH_1):PAGE174_I38@PURE_QUANTA.ISL99390FRZTR5935(CHIPS)':
 'DNC': CDS_PINID='DNC';
NET_NAME
'NC_PVDDCR_SOC_P0_GL1_1'
 '@T6G_MB_LIB.T6G(SCH_1):NC_PVDDCR_SOC_P0_GL1_1':
 C_SIGNAL='@t6g_mb_lib.t6g(sch_1):nc_pvddcr_soc_p0_gl1_1';
NODE_NAME     PU49 6
 '@T6G_MB_LIB.T6G(SCH_1):PAGE173_I41@PURE_QUANTA.ISL99390FRZTR5935(CHIPS)':
 'GL1': CDS_PINID='GL1';
NET_NAME
'NC_PVDDCR_SOC_P0_GL1_2'
 '@T6G_MB_LIB.T6G(SCH_1):NC_PVDDCR_SOC_P0_GL1_2':
 C_SIGNAL='@t6g_mb_lib.t6g(sch_1):nc_pvddcr_soc_p0_gl1_2';
NODE_NAME     PU50 6
 '@T6G_MB_LIB.T6G(SCH_1):PAGE173_I86@PURE_QUANTA.ISL99390FRZTR5935(CHIPS)':
 'GL1': CDS_PINID='GL1';
NET_NAME
'NC_PVDDCR_SOC_P0_GL1_3'
 '@T6G_MB_LIB.T6G(SCH_1):NC_PVDDCR_SOC_P0_GL1_3':
 C_SIGNAL='@t6g_mb_lib.t6g(sch_1):nc_pvddcr_soc_p0_gl1_3';
NODE_NAME     PU51 6
 '@T6G_MB_LIB.T6G(SCH_1):PAGE174_I38@PURE_QUANTA.ISL99390FRZTR5935(CHIPS)':
 'GL1': CDS_PINID='GL1';
NET_NAME
'NC_PVDDCR_SOC_P0_GL2_1'
 '@T6G_MB_LIB.T6G(SCH_1):NC_PVDDCR_SOC_P0_GL2_1':
 C_SIGNAL='@t6g_mb_lib.t6g(sch_1):nc_pvddcr_soc_p0_gl2_1';
NODE_NAME     PU49 41
 '@T6G_MB_LIB.T6G(SCH_1):PAGE173_I41@PURE_QUANTA.ISL99390FRZTR5935(CHIPS)':
 'GL2': CDS_PINID='GL2';
NET_NAME
'NC_PVDDCR_SOC_P0_GL2_2'
 '@T6G_MB_LIB.T6G(SCH_1):NC_PVDDCR_SOC_P0_GL2_2':
 C_SIGNAL='@t6g_mb_lib.t6g(sch_1):nc_pvddcr_soc_p0_gl2_2';
NODE_NAME     PU50 41
 '@T6G_MB_LIB.T6G(SCH_1):PAGE173_I86@PURE_QUANTA.ISL99390FRZTR5935(CHIPS)':
 'GL2': CDS_PINID='GL2';
NET_NAME
'NC_PVDDCR_SOC_P0_GL2_3'
 '@T6G_MB_LIB.T6G(SCH_1):NC_PVDDCR_SOC_P0_GL2_3':
 C_SIGNAL='@t6g_mb_lib.t6g(sch_1):nc_pvddcr_soc_p0_gl2_3';
NODE_NAME     PU51 41
 '@T6G_MB_LIB.T6G(SCH_1):PAGE174_I38@PURE_QUANTA.ISL99390FRZTR5935(CHIPS)':
 'GL2': CDS_PINID='GL2';
NET_NAME
'NC_PVDDCR_SOC_P1_DNC1'
 '@T6G_MB_LIB.T6G(SCH_1):NC_PVDDCR_SOC_P1_DNC1':
 C_SIGNAL='@t6g_mb_lib.t6g(sch_1):nc_pvddcr_soc_p1_dnc1';
NODE_NAME     PU30 31
 '@T6G_MB_LIB.T6G(SCH_1):PAGE190_I17@PURE_QUANTA.ISL99390FRZTR5935(CHIPS)':
 'DNC': CDS_PINID='DNC';
NET_NAME
'NC_PVDDCR_SOC_P1_DNC2'
 '@T6G_MB_LIB.T6G(SCH_1):NC_PVDDCR_SOC_P1_DNC2':
 C_SIGNAL='@t6g_mb_lib.t6g(sch_1):nc_pvddcr_soc_p1_dnc2';
NODE_NAME     PU31 31
 '@T6G_MB_LIB.T6G(SCH_1):PAGE190_I86@PURE_QUANTA.ISL99390FRZTR5935(CHIPS)':
 'DNC': CDS_PINID='DNC';
NET_NAME
'NC_PVDDCR_SOC_P1_DNC3'
 '@T6G_MB_LIB.T6G(SCH_1):NC_PVDDCR_SOC_P1_DNC3':
 C_SIGNAL='@t6g_mb_lib.t6g(sch_1):nc_pvddcr_soc_p1_dnc3';
NODE_NAME     PU32 31
 '@T6G_MB_LIB.T6G(SCH_1):PAGE191_I38@PURE_QUANTA.ISL99390FRZTR5935(CHIPS)':
 'DNC': CDS_PINID='DNC';
NET_NAME
'NC_PVDDCR_SOC_P1_GL1_1'
 '@T6G_MB_LIB.T6G(SCH_1):NC_PVDDCR_SOC_P1_GL1_1':
 C_SIGNAL='@t6g_mb_lib.t6g(sch_1):nc_pvddcr_soc_p1_gl1_1';
NODE_NAME     PU30 6
 '@T6G_MB_LIB.T6G(SCH_1):PAGE190_I17@PURE_QUANTA.ISL99390FRZTR5935(CHIPS)':
 'GL1': CDS_PINID='GL1';
NET_NAME
'NC_PVDDCR_SOC_P1_GL1_2'
 '@T6G_MB_LIB.T6G(SCH_1):NC_PVDDCR_SOC_P1_GL1_2':
 C_SIGNAL='@t6g_mb_lib.t6g(sch_1):nc_pvddcr_soc_p1_gl1_2';
NODE_NAME     PU31 6
 '@T6G_MB_LIB.T6G(SCH_1):PAGE190_I86@PURE_QUANTA.ISL99390FRZTR5935(CHIPS)':
 'GL1': CDS_PINID='GL1';
NET_NAME
'NC_PVDDCR_SOC_P1_GL1_3'
 '@T6G_MB_LIB.T6G(SCH_1):NC_PVDDCR_SOC_P1_GL1_3':
 C_SIGNAL='@t6g_mb_lib.t6g(sch_1):nc_pvddcr_soc_p1_gl1_3';
NODE_NAME     PU32 6
 '@T6G_MB_LIB.T6G(SCH_1):PAGE191_I38@PURE_QUANTA.ISL99390FRZTR5935(CHIPS)':
 'GL1': CDS_PINID='GL1';
NET_NAME
'NC_PVDDCR_SOC_P1_GL2_1'
 '@T6G_MB_LIB.T6G(SCH_1):NC_PVDDCR_SOC_P1_GL2_1':
 C_SIGNAL='@t6g_mb_lib.t6g(sch_1):nc_pvddcr_soc_p1_gl2_1';
NODE_NAME     PU30 41
 '@T6G_MB_LIB.T6G(SCH_1):PAGE190_I17@PURE_QUANTA.ISL99390FRZTR5935(CHIPS)':
 'GL2': CDS_PINID='GL2';
NET_NAME
'NC_PVDDCR_SOC_P1_GL2_2'
 '@T6G_MB_LIB.T6G(SCH_1):NC_PVDDCR_SOC_P1_GL2_2':
 C_SIGNAL='@t6g_mb_lib.t6g(sch_1):nc_pvddcr_soc_p1_gl2_2';
NODE_NAME     PU31 41
 '@T6G_MB_LIB.T6G(SCH_1):PAGE190_I86@PURE_QUANTA.ISL99390FRZTR5935(CHIPS)':
 'GL2': CDS_PINID='GL2';
NET_NAME
'NC_PVDDCR_SOC_P1_GL2_3'
 '@T6G_MB_LIB.T6G(SCH_1):NC_PVDDCR_SOC_P1_GL2_3':
 C_SIGNAL='@t6g_mb_lib.t6g(sch_1):nc_pvddcr_soc_p1_gl2_3';
NODE_NAME     PU32 41
 '@T6G_MB_LIB.T6G(SCH_1):PAGE191_I38@PURE_QUANTA.ISL99390FRZTR5935(CHIPS)':
 'GL2': CDS_PINID='GL2';
NET_NAME
'NC_PVDDIO_P0_DNC1'
 '@T6G_MB_LIB.T6G(SCH_1):NC_PVDDIO_P0_DNC1':
 C_SIGNAL='@t6g_mb_lib.t6g(sch_1):nc_pvddio_p0_dnc1';
NODE_NAME     PU17 31
 '@T6G_MB_LIB.T6G(SCH_1):PAGE180_I84@PURE_QUANTA.ISL99390FRZTR5935(CHIPS)':
 'DNC': CDS_PINID='DNC';
NET_NAME
'NC_PVDDIO_P0_DNC2'
 '@T6G_MB_LIB.T6G(SCH_1):NC_PVDDIO_P0_DNC2':
 C_SIGNAL='@t6g_mb_lib.t6g(sch_1):nc_pvddio_p0_dnc2';
NODE_NAME     PU18 31
 '@T6G_MB_LIB.T6G(SCH_1):PAGE180_I15@PURE_QUANTA.ISL99390FRZTR5935(CHIPS)':
 'DNC': CDS_PINID='DNC';
NET_NAME
'NC_PVDDIO_P0_DNC3'
 '@T6G_MB_LIB.T6G(SCH_1):NC_PVDDIO_P0_DNC3':
 C_SIGNAL='@t6g_mb_lib.t6g(sch_1):nc_pvddio_p0_dnc3';
NODE_NAME     PU19 31
 '@T6G_MB_LIB.T6G(SCH_1):PAGE181_I32@PURE_QUANTA.ISL99390FRZTR5935(CHIPS)':
 'DNC': CDS_PINID='DNC';
NET_NAME
'NC_PVDDIO_P0_DNC4'
 '@T6G_MB_LIB.T6G(SCH_1):NC_PVDDIO_P0_DNC4':
 C_SIGNAL='@t6g_mb_lib.t6g(sch_1):nc_pvddio_p0_dnc4';
NODE_NAME     PU20 31
 '@T6G_MB_LIB.T6G(SCH_1):PAGE181_I73@PURE_QUANTA.ISL99390FRZTR5935(CHIPS)':
 'DNC': CDS_PINID='DNC';
NET_NAME
'NC_PVDDIO_P0_GL1_1'
 '@T6G_MB_LIB.T6G(SCH_1):NC_PVDDIO_P0_GL1_1':
 C_SIGNAL='@t6g_mb_lib.t6g(sch_1):nc_pvddio_p0_gl1_1';
NODE_NAME     PU17 6
 '@T6G_MB_LIB.T6G(SCH_1):PAGE180_I84@PURE_QUANTA.ISL99390FRZTR5935(CHIPS)':
 'GL1': CDS_PINID='GL1';
NET_NAME
'NC_PVDDIO_P0_GL1_2'
 '@T6G_MB_LIB.T6G(SCH_1):NC_PVDDIO_P0_GL1_2':
 C_SIGNAL='@t6g_mb_lib.t6g(sch_1):nc_pvddio_p0_gl1_2';
NODE_NAME     PU18 6
 '@T6G_MB_LIB.T6G(SCH_1):PAGE180_I15@PURE_QUANTA.ISL99390FRZTR5935(CHIPS)':
 'GL1': CDS_PINID='GL1';
NET_NAME
'NC_PVDDIO_P0_GL1_3'
 '@T6G_MB_LIB.T6G(SCH_1):NC_PVDDIO_P0_GL1_3':
 C_SIGNAL='@t6g_mb_lib.t6g(sch_1):nc_pvddio_p0_gl1_3';
NODE_NAME     PU19 6
 '@T6G_MB_LIB.T6G(SCH_1):PAGE181_I32@PURE_QUANTA.ISL99390FRZTR5935(CHIPS)':
 'GL1': CDS_PINID='GL1';
NET_NAME
'NC_PVDDIO_P0_GL1_4'
 '@T6G_MB_LIB.T6G(SCH_1):NC_PVDDIO_P0_GL1_4':
 C_SIGNAL='@t6g_mb_lib.t6g(sch_1):nc_pvddio_p0_gl1_4';
NODE_NAME     PU20 6
 '@T6G_MB_LIB.T6G(SCH_1):PAGE181_I73@PURE_QUANTA.ISL99390FRZTR5935(CHIPS)':
 'GL1': CDS_PINID='GL1';
NET_NAME
'NC_PVDDIO_P0_GL2_1'
 '@T6G_MB_LIB.T6G(SCH_1):NC_PVDDIO_P0_GL2_1':
 C_SIGNAL='@t6g_mb_lib.t6g(sch_1):nc_pvddio_p0_gl2_1';
NODE_NAME     PU17 41
 '@T6G_MB_LIB.T6G(SCH_1):PAGE180_I84@PURE_QUANTA.ISL99390FRZTR5935(CHIPS)':
 'GL2': CDS_PINID='GL2';
NET_NAME
'NC_PVDDIO_P0_GL2_2'
 '@T6G_MB_LIB.T6G(SCH_1):NC_PVDDIO_P0_GL2_2':
 C_SIGNAL='@t6g_mb_lib.t6g(sch_1):nc_pvddio_p0_gl2_2';
NODE_NAME     PU18 41
 '@T6G_MB_LIB.T6G(SCH_1):PAGE180_I15@PURE_QUANTA.ISL99390FRZTR5935(CHIPS)':
 'GL2': CDS_PINID='GL2';
NET_NAME
'NC_PVDDIO_P0_GL2_3'
 '@T6G_MB_LIB.T6G(SCH_1):NC_PVDDIO_P0_GL2_3':
 C_SIGNAL='@t6g_mb_lib.t6g(sch_1):nc_pvddio_p0_gl2_3';
NODE_NAME     PU19 41
 '@T6G_MB_LIB.T6G(SCH_1):PAGE181_I32@PURE_QUANTA.ISL99390FRZTR5935(CHIPS)':
 'GL2': CDS_PINID='GL2';
NET_NAME
'NC_PVDDIO_P0_GL2_4'
 '@T6G_MB_LIB.T6G(SCH_1):NC_PVDDIO_P0_GL2_4':
 C_SIGNAL='@t6g_mb_lib.t6g(sch_1):nc_pvddio_p0_gl2_4';
NODE_NAME     PU20 41
 '@T6G_MB_LIB.T6G(SCH_1):PAGE181_I73@PURE_QUANTA.ISL99390FRZTR5935(CHIPS)':
 'GL2': CDS_PINID='GL2';
NET_NAME
'NC_PVDDIO_P1_DNC1'
 '@T6G_MB_LIB.T6G(SCH_1):NC_PVDDIO_P1_DNC1':
 C_SIGNAL='@t6g_mb_lib.t6g(sch_1):nc_pvddio_p1_dnc1';
NODE_NAME     PU39 31
 '@T6G_MB_LIB.T6G(SCH_1):PAGE197_I39@PURE_QUANTA.ISL99390FRZTR5935(CHIPS)':
 'DNC': CDS_PINID='DNC';
NET_NAME
'NC_PVDDIO_P1_DNC2'
 '@T6G_MB_LIB.T6G(SCH_1):NC_PVDDIO_P1_DNC2':
 C_SIGNAL='@t6g_mb_lib.t6g(sch_1):nc_pvddio_p1_dnc2';
NODE_NAME     PU40 31
 '@T6G_MB_LIB.T6G(SCH_1):PAGE197_I84@PURE_QUANTA.ISL99390FRZTR5935(CHIPS)':
 'DNC': CDS_PINID='DNC';
NET_NAME
'NC_PVDDIO_P1_DNC3'
 '@T6G_MB_LIB.T6G(SCH_1):NC_PVDDIO_P1_DNC3':
 C_SIGNAL='@t6g_mb_lib.t6g(sch_1):nc_pvddio_p1_dnc3';
NODE_NAME     PU52 31
 '@T6G_MB_LIB.T6G(SCH_1):PAGE198_I73@PURE_QUANTA.ISL99390FRZTR5935(CHIPS)':
 'DNC': CDS_PINID='DNC';
NET_NAME
'NC_PVDDIO_P1_DNC4'
 '@T6G_MB_LIB.T6G(SCH_1):NC_PVDDIO_P1_DNC4':
 C_SIGNAL='@t6g_mb_lib.t6g(sch_1):nc_pvddio_p1_dnc4';
NODE_NAME     PU53 31
 '@T6G_MB_LIB.T6G(SCH_1):PAGE198_I15@PURE_QUANTA.ISL99390FRZTR5935(CHIPS)':
 'DNC': CDS_PINID='DNC';
NET_NAME
'NC_PVDDIO_P1_GL1_1'
 '@T6G_MB_LIB.T6G(SCH_1):NC_PVDDIO_P1_GL1_1':
 C_SIGNAL='@t6g_mb_lib.t6g(sch_1):nc_pvddio_p1_gl1_1';
NODE_NAME     PU39 6
 '@T6G_MB_LIB.T6G(SCH_1):PAGE197_I39@PURE_QUANTA.ISL99390FRZTR5935(CHIPS)':
 'GL1': CDS_PINID='GL1';
NET_NAME
'NC_PVDDIO_P1_GL1_2'
 '@T6G_MB_LIB.T6G(SCH_1):NC_PVDDIO_P1_GL1_2':
 C_SIGNAL='@t6g_mb_lib.t6g(sch_1):nc_pvddio_p1_gl1_2';
NODE_NAME     PU40 6
 '@T6G_MB_LIB.T6G(SCH_1):PAGE197_I84@PURE_QUANTA.ISL99390FRZTR5935(CHIPS)':
 'GL1': CDS_PINID='GL1';
NET_NAME
'NC_PVDDIO_P1_GL1_3'
 '@T6G_MB_LIB.T6G(SCH_1):NC_PVDDIO_P1_GL1_3':
 C_SIGNAL='@t6g_mb_lib.t6g(sch_1):nc_pvddio_p1_gl1_3';
NODE_NAME     PU52 6
 '@T6G_MB_LIB.T6G(SCH_1):PAGE198_I73@PURE_QUANTA.ISL99390FRZTR5935(CHIPS)':
 'GL1': CDS_PINID='GL1';
NET_NAME
'NC_PVDDIO_P1_GL1_4'
 '@T6G_MB_LIB.T6G(SCH_1):NC_PVDDIO_P1_GL1_4':
 C_SIGNAL='@t6g_mb_lib.t6g(sch_1):nc_pvddio_p1_gl1_4';
NODE_NAME     PU53 6
 '@T6G_MB_LIB.T6G(SCH_1):PAGE198_I15@PURE_QUANTA.ISL99390FRZTR5935(CHIPS)':
 'GL1': CDS_PINID='GL1';
NET_NAME
'NC_PVDDIO_P1_GL2_1'
 '@T6G_MB_LIB.T6G(SCH_1):NC_PVDDIO_P1_GL2_1':
 C_SIGNAL='@t6g_mb_lib.t6g(sch_1):nc_pvddio_p1_gl2_1';
NODE_NAME     PU39 41
 '@T6G_MB_LIB.T6G(SCH_1):PAGE197_I39@PURE_QUANTA.ISL99390FRZTR5935(CHIPS)':
 'GL2': CDS_PINID='GL2';
NET_NAME
'NC_PVDDIO_P1_GL2_2'
 '@T6G_MB_LIB.T6G(SCH_1):NC_PVDDIO_P1_GL2_2':
 C_SIGNAL='@t6g_mb_lib.t6g(sch_1):nc_pvddio_p1_gl2_2';
NODE_NAME     PU40 41
 '@T6G_MB_LIB.T6G(SCH_1):PAGE197_I84@PURE_QUANTA.ISL99390FRZTR5935(CHIPS)':
 'GL2': CDS_PINID='GL2';
NET_NAME
'NC_PVDDIO_P1_GL2_3'
 '@T6G_MB_LIB.T6G(SCH_1):NC_PVDDIO_P1_GL2_3':
 C_SIGNAL='@t6g_mb_lib.t6g(sch_1):nc_pvddio_p1_gl2_3';
NODE_NAME     PU52 41
 '@T6G_MB_LIB.T6G(SCH_1):PAGE198_I73@PURE_QUANTA.ISL99390FRZTR5935(CHIPS)':
 'GL2': CDS_PINID='GL2';
NET_NAME
'NC_PVDDIO_P1_GL2_4'
 '@T6G_MB_LIB.T6G(SCH_1):NC_PVDDIO_P1_GL2_4':
 C_SIGNAL='@t6g_mb_lib.t6g(sch_1):nc_pvddio_p1_gl2_4';
NODE_NAME     PU53 41
 '@T6G_MB_LIB.T6G(SCH_1):PAGE198_I15@PURE_QUANTA.ISL99390FRZTR5935(CHIPS)':
 'GL2': CDS_PINID='GL2';
NET_NAME
'NC_Q83_D2'
 '@T6G_MB_LIB.T6G(SCH_1):NC_Q83_D2':
 C_SIGNAL='@t6g_mb_lib.t6g(sch_1):nc_q83_d2';
NODE_NAME     Q83 3
 '@T6G_MB_LIB.T6G(SCH_1):PAGE374_I43@PURE_QUANTA.MOSFET_NCH_DUAL(CHIPS)':
 'D2': CDS_PINID='D2';
NET_NAME
'NC_Q83_G2'
 '@T6G_MB_LIB.T6G(SCH_1):NC_Q83_G2':
 C_SIGNAL='@t6g_mb_lib.t6g(sch_1):nc_q83_g2';
NODE_NAME     Q83 5
 '@T6G_MB_LIB.T6G(SCH_1):PAGE374_I43@PURE_QUANTA.MOSFET_NCH_DUAL(CHIPS)':
 'G2': CDS_PINID='G2';
NET_NAME
'NC_Q83_S2'
 '@T6G_MB_LIB.T6G(SCH_1):NC_Q83_S2':
 C_SIGNAL='@t6g_mb_lib.t6g(sch_1):nc_q83_s2';
NODE_NAME     Q83 4
 '@T6G_MB_LIB.T6G(SCH_1):PAGE374_I43@PURE_QUANTA.MOSFET_NCH_DUAL(CHIPS)':
 'S2': CDS_PINID='S2';
NET_NAME
'NC_Q95_D2'
 '@T6G_MB_LIB.T6G(SCH_1):NC_Q95_D2':
 C_SIGNAL='@t6g_mb_lib.t6g(sch_1):nc_q95_d2';
NODE_NAME     Q95 3
 '@T6G_MB_LIB.T6G(SCH_1):PAGE345_I89@PURE_QUANTA.MOSFET_NCH_DUAL(CHIPS)':
 'D2': CDS_PINID='D2';
NET_NAME
'NC_Q95_G2'
 '@T6G_MB_LIB.T6G(SCH_1):NC_Q95_G2':
 C_SIGNAL='@t6g_mb_lib.t6g(sch_1):nc_q95_g2';
NODE_NAME     Q95 5
 '@T6G_MB_LIB.T6G(SCH_1):PAGE345_I89@PURE_QUANTA.MOSFET_NCH_DUAL(CHIPS)':
 'G2': CDS_PINID='G2';
NET_NAME
'NC_Q95_S2'
 '@T6G_MB_LIB.T6G(SCH_1):NC_Q95_S2':
 C_SIGNAL='@t6g_mb_lib.t6g(sch_1):nc_q95_s2';
NODE_NAME     Q95 4
 '@T6G_MB_LIB.T6G(SCH_1):PAGE345_I89@PURE_QUANTA.MOSFET_NCH_DUAL(CHIPS)':
 'S2': CDS_PINID='S2';
NET_NAME
'NC_RES'
 '@T6G_MB_LIB.T6G(SCH_1):NC_RES':
 C_SIGNAL='@t6g_mb_lib.t6g(sch_1):nc_res';
NODE_NAME     U6000 13
 '@T6G_MB_LIB.T6G(SCH_1):PAGE111_I1@PURE_QUANTA.DS125BR111RTWR(CHIPS)':
 'RES': CDS_PINID='RES';
NET_NAME
'NC_U104_NC1'
 '@T6G_MB_LIB.T6G(SCH_1):NC_U104_NC1':
 C_SIGNAL='@t6g_mb_lib.t6g(sch_1):nc_u104_nc1';
NODE_NAME     U104 1
 '@T6G_MB_LIB.T6G(SCH_1):PAGE337_I38@PURE_QUANTA.74LVC1G07GV(CHIPS)':
 'NC1': CDS_PINID='NC1';
NET_NAME
'NC_U10_FBOUT'
 '@T6G_MB_LIB.T6G(SCH_1):NC_U10_FBOUT':
 C_SIGNAL='@t6g_mb_lib.t6g(sch_1):nc_u10_fbout';
NODE_NAME     U10 9
 '@T6G_MB_LIB.T6G(SCH_1):PAGE379_I63@PURE_QUANTA.9ZXL0451EKILFT(CHIPS)':
 'FBOUT_NC': CDS_PINID='FBOUT_NC';
NET_NAME
'NC_U10_FBOUT_N'
 '@T6G_MB_LIB.T6G(SCH_1):NC_U10_FBOUT_N':
 C_SIGNAL='@t6g_mb_lib.t6g(sch_1):nc_u10_fbout_n';
NODE_NAME     U10 8
 '@T6G_MB_LIB.T6G(SCH_1):PAGE379_I63@PURE_QUANTA.9ZXL0451EKILFT(CHIPS)':
 'FBOUT_NC#': CDS_PINID='\fbout_nc#\';
NET_NAME
'NC_U10_NC0'
 '@T6G_MB_LIB.T6G(SCH_1):NC_U10_NC0':
 C_SIGNAL='@t6g_mb_lib.t6g(sch_1):nc_u10_nc0';
NODE_NAME     U10 10
 '@T6G_MB_LIB.T6G(SCH_1):PAGE379_I63@PURE_QUANTA.9ZXL0451EKILFT(CHIPS)':
 'NC0': CDS_PINID='NC0';
NET_NAME
'NC_U10_NC1'
 '@T6G_MB_LIB.T6G(SCH_1):NC_U10_NC1':
 C_SIGNAL='@t6g_mb_lib.t6g(sch_1):nc_u10_nc1';
NODE_NAME     U10 11
 '@T6G_MB_LIB.T6G(SCH_1):PAGE379_I63@PURE_QUANTA.9ZXL0451EKILFT(CHIPS)':
 'NC1': CDS_PINID='NC1';
NET_NAME
'NC_U10_NC2'
 '@T6G_MB_LIB.T6G(SCH_1):NC_U10_NC2':
 C_SIGNAL='@t6g_mb_lib.t6g(sch_1):nc_u10_nc2';
NODE_NAME     U10 17
 '@T6G_MB_LIB.T6G(SCH_1):PAGE379_I63@PURE_QUANTA.9ZXL0451EKILFT(CHIPS)':
 'NC2': CDS_PINID='NC2';
NET_NAME
'NC_U10_NC3'
 '@T6G_MB_LIB.T6G(SCH_1):NC_U10_NC3':
 C_SIGNAL='@t6g_mb_lib.t6g(sch_1):nc_u10_nc3';
NODE_NAME     U10 30
 '@T6G_MB_LIB.T6G(SCH_1):PAGE379_I63@PURE_QUANTA.9ZXL0451EKILFT(CHIPS)':
 'NC3': CDS_PINID='NC3';
NET_NAME
'NC_U157_NC1'
 '@T6G_MB_LIB.T6G(SCH_1):NC_U157_NC1':
 C_SIGNAL='@t6g_mb_lib.t6g(sch_1):nc_u157_nc1';
NODE_NAME     U157 1
 '@T6G_MB_LIB.T6G(SCH_1):PAGE337_I25@PURE_QUANTA.74LVC1G07GV(CHIPS)':
 'NC1': CDS_PINID='NC1';
NET_NAME
'NC_U218_NC1'
 '@T6G_MB_LIB.T6G(SCH_1):NC_U218_NC1':
 C_SIGNAL='@t6g_mb_lib.t6g(sch_1):nc_u218_nc1';
NODE_NAME     U218 1
 '@T6G_MB_LIB.T6G(SCH_1):PAGE342_I22@PURE_QUANTA.74LVC1G07GV(CHIPS)':
 'NC1': CDS_PINID='NC1';
NET_NAME
'NC_U219_NC1'
 '@T6G_MB_LIB.T6G(SCH_1):NC_U219_NC1':
 C_SIGNAL='@t6g_mb_lib.t6g(sch_1):nc_u219_nc1';
NODE_NAME     U219 1
 '@T6G_MB_LIB.T6G(SCH_1):PAGE342_I32@PURE_QUANTA.74LVC1G07GV(CHIPS)':
 'NC1': CDS_PINID='NC1';
NET_NAME
'NC_U257_2Y'
 '@T6G_MB_LIB.T6G(SCH_1):NC_U257_2Y':
 C_SIGNAL='@t6g_mb_lib.t6g(sch_1):nc_u257_2y';
NODE_NAME     U257 4
 '@T6G_MB_LIB.T6G(SCH_1):PAGE255_I50@PURE_QUANTA.74LVC2G07DW7(CHIPS)':
 '2Y': CDS_PINID='\2y\';
NET_NAME
'NC_U314_FBOUT'
 '@T6G_MB_LIB.T6G(SCH_1):NC_U314_FBOUT':
 C_SIGNAL='@t6g_mb_lib.t6g(sch_1):nc_u314_fbout';
NODE_NAME     U314 9
 '@T6G_MB_LIB.T6G(SCH_1):PAGE160_I63@PURE_QUANTA.9ZXL0451EKILFT(CHIPS)':
 'FBOUT_NC': CDS_PINID='FBOUT_NC';
NET_NAME
'NC_U314_FBOUT_N'
 '@T6G_MB_LIB.T6G(SCH_1):NC_U314_FBOUT_N':
 C_SIGNAL='@t6g_mb_lib.t6g(sch_1):nc_u314_fbout_n';
NODE_NAME     U314 8
 '@T6G_MB_LIB.T6G(SCH_1):PAGE160_I63@PURE_QUANTA.9ZXL0451EKILFT(CHIPS)':
 'FBOUT_NC#': CDS_PINID='\fbout_nc#\';
NET_NAME
'NC_U314_NC0'
 '@T6G_MB_LIB.T6G(SCH_1):NC_U314_NC0':
 C_SIGNAL='@t6g_mb_lib.t6g(sch_1):nc_u314_nc0';
NODE_NAME     U314 10
 '@T6G_MB_LIB.T6G(SCH_1):PAGE160_I63@PURE_QUANTA.9ZXL0451EKILFT(CHIPS)':
 'NC0': CDS_PINID='NC0';
NET_NAME
'NC_U314_NC1'
 '@T6G_MB_LIB.T6G(SCH_1):NC_U314_NC1':
 C_SIGNAL='@t6g_mb_lib.t6g(sch_1):nc_u314_nc1';
NODE_NAME     U314 11
 '@T6G_MB_LIB.T6G(SCH_1):PAGE160_I63@PURE_QUANTA.9ZXL0451EKILFT(CHIPS)':
 'NC1': CDS_PINID='NC1';
NET_NAME
'NC_U314_NC2'
 '@T6G_MB_LIB.T6G(SCH_1):NC_U314_NC2':
 C_SIGNAL='@t6g_mb_lib.t6g(sch_1):nc_u314_nc2';
NODE_NAME     U314 17
 '@T6G_MB_LIB.T6G(SCH_1):PAGE160_I63@PURE_QUANTA.9ZXL0451EKILFT(CHIPS)':
 'NC2': CDS_PINID='NC2';
NET_NAME
'NC_U314_NC3'
 '@T6G_MB_LIB.T6G(SCH_1):NC_U314_NC3':
 C_SIGNAL='@t6g_mb_lib.t6g(sch_1):nc_u314_nc3';
NODE_NAME     U314 30
 '@T6G_MB_LIB.T6G(SCH_1):PAGE160_I63@PURE_QUANTA.9ZXL0451EKILFT(CHIPS)':
 'NC3': CDS_PINID='NC3';
NET_NAME
'NC_U316_2Y'
 '@T6G_MB_LIB.T6G(SCH_1):NC_U316_2Y':
 C_SIGNAL='@t6g_mb_lib.t6g(sch_1):nc_u316_2y';
NODE_NAME     U316 4
 '@T6G_MB_LIB.T6G(SCH_1):PAGE331_I86@PURE_QUANTA.74LVC2G17GW(CHIPS)':
 'B1': CDS_PINID='B1';
NET_NAME
'NC_U8004_2Y'
 '@T6G_MB_LIB.T6G(SCH_1):NC_U8004_2Y':
 C_SIGNAL='@t6g_mb_lib.t6g(sch_1):nc_u8004_2y';
NODE_NAME     U8004 4
 '@T6G_MB_LIB.T6G(SCH_1):PAGE365_I16@PURE_QUANTA.74LVC2G07DW7(CHIPS)':
 '2Y': CDS_PINID='\2y\';
NET_NAME
'NC_USB_HUB_DM2'
 '@T6G_MB_LIB.T6G(SCH_1):NC_USB_HUB_DM2':
 C_SIGNAL='@t6g_mb_lib.t6g(sch_1):nc_usb_hub_dm2';
NODE_NAME     U268 6
 '@T6G_MB_LIB.T6G(SCH_1):PAGE358_I100@PURE_QUANTA.GL852GOHY60(CHIPS)':
 'DM2': CDS_PINID='DM2';
NET_NAME
'NC_USB_HUB_DM3'
 '@T6G_MB_LIB.T6G(SCH_1):NC_USB_HUB_DM3':
 C_SIGNAL='@t6g_mb_lib.t6g(sch_1):nc_usb_hub_dm3';
NODE_NAME     U268 12
 '@T6G_MB_LIB.T6G(SCH_1):PAGE358_I100@PURE_QUANTA.GL852GOHY60(CHIPS)':
 'DM3': CDS_PINID='DM3';
NET_NAME
'NC_USB_HUB_DM4'
 '@T6G_MB_LIB.T6G(SCH_1):NC_USB_HUB_DM4':
 C_SIGNAL='@t6g_mb_lib.t6g(sch_1):nc_usb_hub_dm4';
NODE_NAME     U268 15
 '@T6G_MB_LIB.T6G(SCH_1):PAGE358_I100@PURE_QUANTA.GL852GOHY60(CHIPS)':
 'DM4': CDS_PINID='DM4';
NET_NAME
'NC_USB_HUB_DP2'
 '@T6G_MB_LIB.T6G(SCH_1):NC_USB_HUB_DP2':
 C_SIGNAL='@t6g_mb_lib.t6g(sch_1):nc_usb_hub_dp2';
NODE_NAME     U268 7
 '@T6G_MB_LIB.T6G(SCH_1):PAGE358_I100@PURE_QUANTA.GL852GOHY60(CHIPS)':
 'DP2': CDS_PINID='DP2';
NET_NAME
'NC_USB_HUB_DP3'
 '@T6G_MB_LIB.T6G(SCH_1):NC_USB_HUB_DP3':
 C_SIGNAL='@t6g_mb_lib.t6g(sch_1):nc_usb_hub_dp3';
NODE_NAME     U268 13
 '@T6G_MB_LIB.T6G(SCH_1):PAGE358_I100@PURE_QUANTA.GL852GOHY60(CHIPS)':
 'DP3': CDS_PINID='DP3';
NET_NAME
'NC_USB_HUB_DP4'
 '@T6G_MB_LIB.T6G(SCH_1):NC_USB_HUB_DP4':
 C_SIGNAL='@t6g_mb_lib.t6g(sch_1):nc_usb_hub_dp4';
NODE_NAME     U268 16
 '@T6G_MB_LIB.T6G(SCH_1):PAGE358_I100@PURE_QUANTA.GL852GOHY60(CHIPS)':
 'DP4': CDS_PINID='DP4';
NET_NAME
'NC_USB_HUB_SDA'
 '@T6G_MB_LIB.T6G(SCH_1):NC_USB_HUB_SDA':
 C_SIGNAL='@t6g_mb_lib.t6g(sch_1):nc_usb_hub_sda';
NODE_NAME     U268 26
 '@T6G_MB_LIB.T6G(SCH_1):PAGE358_I100@PURE_QUANTA.GL852GOHY60(CHIPS)':
 'SDA': CDS_PINID='SDA';
NET_NAME
'OCP_SFF_AUX_PWR_EN'
 '@T6G_MB_LIB.T6G(SCH_1):OCP_SFF_AUX_PWR_EN':
 C_SIGNAL='@t6g_mb_lib.t6g(sch_1):ocp_sff_aux_pwr_en';
NODE_NAME     R1671 1
 '@T6G_MB_LIB.T6G(SCH_1):PAGE335_I54@PURE_QUANTA.Q_RES(CHIPS)':
 'A': CDS_PINID='A';
NODE_NAME     R1719 1
 '@T6G_MB_LIB.T6G(SCH_1):PAGE336_I119@PURE_QUANTA.Q_RES(CHIPS)':
 'A': CDS_PINID='A';
NODE_NAME     R3231 1
 '@T6G_MB_LIB.T6G(SCH_1):PAGE336_I160@PURE_QUANTA.Q_RES(CHIPS)':
 'A': CDS_PINID='A';
NODE_NAME     R1929 2
 '@T6G_MB_LIB.T6G(SCH_1):PAGE335_I8@PURE_QUANTA.Q_RES(CHIPS)':
 'B': CDS_PINID='B';
NODE_NAME     R9031 2
 '@T6G_MB_LIB.T6G(SCH_1):PAGE340_I22@PURE_QUANTA.Q_RES(CHIPS)':
 'B': CDS_PINID='B';
NODE_NAME     R1145 2
 '@T6G_MB_LIB.T6G(SCH_1):PAGE340_I76@PURE_QUANTA.Q_RES(CHIPS)':
 'B': CDS_PINID='B';
NET_NAME
'OCP_SFF_AUX_PWR_EN_R'
 '@T6G_MB_LIB.T6G(SCH_1):OCP_SFF_AUX_PWR_EN_R':
 C_SIGNAL='@t6g_mb_lib.t6g(sch_1):ocp_sff_aux_pwr_en_r';
NODE_NAME     R1671 2
 '@T6G_MB_LIB.T6G(SCH_1):PAGE335_I54@PURE_QUANTA.Q_RES(CHIPS)':
 'B': CDS_PINID='B';
NODE_NAME     J38 B12
 '@T6G_MB_LIB.T6G(SCH_1):PAGE335_I168@PURE_QUANTA.SCONN168_ME1016810202011(CHIPS)':
 'AUX_PWR_EN': CDS_PINID='AUX_PWR_EN';
NET_NAME
'OCP_SFF_AUX_PWR_EN_R1'
 '@T6G_MB_LIB.T6G(SCH_1):OCP_SFF_AUX_PWR_EN_R1':
 C_SIGNAL='@t6g_mb_lib.t6g(sch_1):ocp_sff_aux_pwr_en_r1';
NODE_NAME     R1719 2
 '@T6G_MB_LIB.T6G(SCH_1):PAGE336_I119@PURE_QUANTA.Q_RES(CHIPS)':
 'B': CDS_PINID='B';
NODE_NAME     U66 1
 '@T6G_MB_LIB.T6G(SCH_1):PAGE336_I157@PURE_QUANTA.74LVC1G126SE7(CHIPS)':
 'OE': CDS_PINID='OE';
NET_NAME
'OCP_SFF_AUX_PWR_EN_R2'
 '@T6G_MB_LIB.T6G(SCH_1):OCP_SFF_AUX_PWR_EN_R2':
 C_SIGNAL='@t6g_mb_lib.t6g(sch_1):ocp_sff_aux_pwr_en_r2';
NODE_NAME     U224 1
 '@T6G_MB_LIB.T6G(SCH_1):PAGE336_I159@PURE_QUANTA.74LVC1G126SE7(CHIPS)':
 'OE': CDS_PINID='OE';
NODE_NAME     R3231 2
 '@T6G_MB_LIB.T6G(SCH_1):PAGE336_I160@PURE_QUANTA.Q_RES(CHIPS)':
 'B': CDS_PINID='B';
NET_NAME
'OCP_SFF_AUX_PWR_EN_R3'
 '@T6G_MB_LIB.T6G(SCH_1):OCP_SFF_AUX_PWR_EN_R3':
 C_SIGNAL='@t6g_mb_lib.t6g(sch_1):ocp_sff_aux_pwr_en_r3';
NODE_NAME     R9030 1
 '@T6G_MB_LIB.T6G(SCH_1):PAGE340_I15@PURE_QUANTA.Q_RES(CHIPS)':
 'A': CDS_PINID='A';
NODE_NAME     R9029 1
 '@T6G_MB_LIB.T6G(SCH_1):PAGE340_I18@PURE_QUANTA.Q_RES(CHIPS)':
 'A': CDS_PINID='A';
NODE_NAME     R9031 1
 '@T6G_MB_LIB.T6G(SCH_1):PAGE340_I22@PURE_QUANTA.Q_RES(CHIPS)':
 'A': CDS_PINID='A';
NODE_NAME     U9002 4
 '@T6G_MB_LIB.T6G(SCH_1):PAGE340_I74@PURE_QUANTA.74LVC1G32GW(CHIPS)':
 'O': CDS_PINID='O';
NET_NAME
'OCP_SFF_BIF0_R_N'
 '@T6G_MB_LIB.T6G(SCH_1):OCP_SFF_BIF0_R_N':
 C_SIGNAL='@t6g_mb_lib.t6g(sch_1):ocp_sff_bif0_r_n';
NODE_NAME     J38 B7
 '@T6G_MB_LIB.T6G(SCH_1):PAGE335_I168@PURE_QUANTA.SCONN168_ME1016810202011(CHIPS)':
 'BIF0#': CDS_PINID='\bif0#\';
NODE_NAME     R39 2
 '@T6G_MB_LIB.T6G(SCH_1):PAGE335_I57@PURE_QUANTA.Q_RES(CHIPS)':
 'B': CDS_PINID='B';
NET_NAME
'OCP_SFF_BIF1_R_N'
 '@T6G_MB_LIB.T6G(SCH_1):OCP_SFF_BIF1_R_N':
 C_SIGNAL='@t6g_mb_lib.t6g(sch_1):ocp_sff_bif1_r_n';
NODE_NAME     J38 B8
 '@T6G_MB_LIB.T6G(SCH_1):PAGE335_I168@PURE_QUANTA.SCONN168_ME1016810202011(CHIPS)':
 'BIF1#': CDS_PINID='\bif1#\';
NODE_NAME     R40 2
 '@T6G_MB_LIB.T6G(SCH_1):PAGE335_I56@PURE_QUANTA.Q_RES(CHIPS)':
 'B': CDS_PINID='B';
NET_NAME
'OCP_SFF_BIF2_R_N'
 '@T6G_MB_LIB.T6G(SCH_1):OCP_SFF_BIF2_R_N':
 C_SIGNAL='@t6g_mb_lib.t6g(sch_1):ocp_sff_bif2_r_n';
NODE_NAME     J38 B9
 '@T6G_MB_LIB.T6G(SCH_1):PAGE335_I168@PURE_QUANTA.SCONN168_ME1016810202011(CHIPS)':
 'BIF2#': CDS_PINID='\bif2#\';
NODE_NAME     R41 2
 '@T6G_MB_LIB.T6G(SCH_1):PAGE335_I55@PURE_QUANTA.Q_RES(CHIPS)':
 'B': CDS_PINID='B';
NET_NAME
'OCP_SFF_ID0'
 '@T6G_MB_LIB.T6G(SCH_1):OCP_SFF_ID0':
 C_SIGNAL='@t6g_mb_lib.t6g(sch_1):ocp_sff_id0';
NODE_NAME     R32 1
 '@T6G_MB_LIB.T6G(SCH_1):PAGE335_I2@PURE_QUANTA.Q_RES(CHIPS)':
 'A': CDS_PINID='A';
NODE_NAME     J38 OB7
 '@T6G_MB_LIB.T6G(SCH_1):PAGE335_I168@PURE_QUANTA.SCONN168_ME1016810202011(CHIPS)':
 'SLOT_ID0': CDS_PINID='SLOT_ID0';
NODE_NAME     R31 2
 '@T6G_MB_LIB.T6G(SCH_1):PAGE335_I3@PURE_QUANTA.Q_RES(CHIPS)':
 'B': CDS_PINID='B';
NET_NAME
'OCP_SFF_ID1'
 '@T6G_MB_LIB.T6G(SCH_1):OCP_SFF_ID1':
 C_SIGNAL='@t6g_mb_lib.t6g(sch_1):ocp_sff_id1';
NODE_NAME     J38 OA6
 '@T6G_MB_LIB.T6G(SCH_1):PAGE335_I168@PURE_QUANTA.SCONN168_ME1016810202011(CHIPS)':
 'SLOT_ID1': CDS_PINID='SLOT_ID1';
NODE_NAME     R34 1
 '@T6G_MB_LIB.T6G(SCH_1):PAGE335_I12@PURE_QUANTA.Q_RES(CHIPS)':
 'A': CDS_PINID='A';
NODE_NAME     R33 2
 '@T6G_MB_LIB.T6G(SCH_1):PAGE335_I17@PURE_QUANTA.Q_RES(CHIPS)':
 'B': CDS_PINID='B';
NET_NAME
'OCP_SFF_ISO1_RBT_ARB_IN'
 '@T6G_MB_LIB.T6G(SCH_1):OCP_SFF_ISO1_RBT_ARB_IN':
 C_SIGNAL='@t6g_mb_lib.t6g(sch_1):ocp_sff_iso1_rbt_arb_in';
NODE_NAME     J38 OA4
 '@T6G_MB_LIB.T6G(SCH_1):PAGE335_I168@PURE_QUANTA.SCONN168_ME1016810202011(CHIPS)':
 'RBT_ARB_IN': CDS_PINID='RBT_ARB_IN';
NODE_NAME     U67 11
 '@T6G_MB_LIB.T6G(SCH_1):PAGE336_I1@PURE_QUANTA.74CBTLV3126PW(CHIPS)':
 '4B': CDS_PINID='\4b\';
NET_NAME
'OCP_SFF_ISO2_RBT_ARB_OUT'
 '@T6G_MB_LIB.T6G(SCH_1):OCP_SFF_ISO2_RBT_ARB_OUT':
 C_SIGNAL='@t6g_mb_lib.t6g(sch_1):ocp_sff_iso2_rbt_arb_out';
NODE_NAME     J38 OA5
 '@T6G_MB_LIB.T6G(SCH_1):PAGE335_I168@PURE_QUANTA.SCONN168_ME1016810202011(CHIPS)':
 'RBT_ARB_OUT': CDS_PINID='RBT_ARB_OUT';
NODE_NAME     U7 11
 '@T6G_MB_LIB.T6G(SCH_1):PAGE336_I2@PURE_QUANTA.74CBTLV3126PW(CHIPS)':
 '4B': CDS_PINID='\4b\';
NET_NAME
'OCP_SFF_ISO_BIF0_EN'
 '@T6G_MB_LIB.T6G(SCH_1):OCP_SFF_ISO_BIF0_EN':
 C_SIGNAL='@t6g_mb_lib.t6g(sch_1):ocp_sff_iso_bif0_en';
NODE_NAME     R1896 1
 '@T6G_MB_LIB.T6G(SCH_1):PAGE336_I123@PURE_QUANTA.Q_RES(CHIPS)':
 'A': CDS_PINID='A';
NODE_NAME     R39 1
 '@T6G_MB_LIB.T6G(SCH_1):PAGE335_I57@PURE_QUANTA.Q_RES(CHIPS)':
 'A': CDS_PINID='A';
NET_NAME
'OCP_SFF_ISO_BIF1_EN'
 '@T6G_MB_LIB.T6G(SCH_1):OCP_SFF_ISO_BIF1_EN':
 C_SIGNAL='@t6g_mb_lib.t6g(sch_1):ocp_sff_iso_bif1_en';
NODE_NAME     R1897 1
 '@T6G_MB_LIB.T6G(SCH_1):PAGE336_I124@PURE_QUANTA.Q_RES(CHIPS)':
 'A': CDS_PINID='A';
NODE_NAME     R40 1
 '@T6G_MB_LIB.T6G(SCH_1):PAGE335_I56@PURE_QUANTA.Q_RES(CHIPS)':
 'A': CDS_PINID='A';
NET_NAME
'OCP_SFF_ISO_BIF2_EN'
 '@T6G_MB_LIB.T6G(SCH_1):OCP_SFF_ISO_BIF2_EN':
 C_SIGNAL='@t6g_mb_lib.t6g(sch_1):ocp_sff_iso_bif2_en';
NODE_NAME     R1898 1
 '@T6G_MB_LIB.T6G(SCH_1):PAGE336_I122@PURE_QUANTA.Q_RES(CHIPS)':
 'A': CDS_PINID='A';
NODE_NAME     R41 1
 '@T6G_MB_LIB.T6G(SCH_1):PAGE335_I55@PURE_QUANTA.Q_RES(CHIPS)':
 'A': CDS_PINID='A';
NET_NAME
'OCP_SFF_MAIN_PWR_EN'
 '@T6G_MB_LIB.T6G(SCH_1):OCP_SFF_MAIN_PWR_EN':
 C_SIGNAL='@t6g_mb_lib.t6g(sch_1):ocp_sff_main_pwr_en';
NODE_NAME     R1930 2
 '@T6G_MB_LIB.T6G(SCH_1):PAGE335_I7@PURE_QUANTA.Q_RES(CHIPS)':
 'B': CDS_PINID='B';
NODE_NAME     R38 1
 '@T6G_MB_LIB.T6G(SCH_1):PAGE335_I59@PURE_QUANTA.Q_RES(CHIPS)':
 'A': CDS_PINID='A';
NODE_NAME     R959 1
 '@T6G_MB_LIB.T6G(SCH_1):PAGE81_I81@PURE_QUANTA.Q_RES(CHIPS)':
 'A': CDS_PINID='A';
NET_NAME
'OCP_SFF_MAIN_PWR_EN_R'
 '@T6G_MB_LIB.T6G(SCH_1):OCP_SFF_MAIN_PWR_EN_R':
 C_SIGNAL='@t6g_mb_lib.t6g(sch_1):ocp_sff_main_pwr_en_r';
NODE_NAME     J38 OB2
 '@T6G_MB_LIB.T6G(SCH_1):PAGE335_I168@PURE_QUANTA.SCONN168_ME1016810202011(CHIPS)':
 'MAIN_PWR_EN': CDS_PINID='MAIN_PWR_EN';
NODE_NAME     R38 2
 '@T6G_MB_LIB.T6G(SCH_1):PAGE335_I59@PURE_QUANTA.Q_RES(CHIPS)':
 'B': CDS_PINID='B';
NET_NAME
'OCP_SFF_NOT_PRSNT_RBT_ARB_IN'
 '@T6G_MB_LIB.T6G(SCH_1):OCP_SFF_NOT_PRSNT_RBT_ARB_IN':
 C_SIGNAL='@t6g_mb_lib.t6g(sch_1):ocp_sff_not_prsnt_rbt_arb_in';
NODE_NAME     U243 1
 '@T6G_MB_LIB.T6G(SCH_1):PAGE258_I15@PURE_QUANTA.NC7SB3157(CHIPS)':
 'B1': CDS_PINID='B1';
NODE_NAME     U244 1
 '@T6G_MB_LIB.T6G(SCH_1):PAGE258_I16@PURE_QUANTA.NC7SB3157(CHIPS)':
 'B1': CDS_PINID='B1';
NET_NAME
'OCP_SFF_P3V3_ADC_ALERT_R'
 '@T6G_MB_LIB.T6G(SCH_1):OCP_SFF_P3V3_ADC_ALERT_R':
 C_SIGNAL='@t6g_mb_lib.t6g(sch_1):ocp_sff_p3v3_adc_alert_r';
NODE_NAME     U266 3
 '@T6G_MB_LIB.T6G(SCH_1):PAGE295_I30@PURE_QUANTA.ISL28022FRZT(CHIPS)':
 'EXT_CLK||INT': CDS_PINID='\ext_clk||int\';
NODE_NAME     R3563 1
 '@T6G_MB_LIB.T6G(SCH_1):PAGE295_I35@PURE_QUANTA.Q_RES(CHIPS)':
 'A': CDS_PINID='A';
NODE_NAME     R4094 2
 '@T6G_MB_LIB.T6G(SCH_1):PAGE295_I151@PURE_QUANTA.Q_RES(CHIPS)':
 'B': CDS_PINID='B';
NET_NAME
'OCP_SFF_P3V3_P12V_ADC_ALERT'
 '@T6G_MB_LIB.T6G(SCH_1):OCP_SFF_P3V3_P12V_ADC_ALERT':
 C_SIGNAL='@t6g_mb_lib.t6g(sch_1):ocp_sff_p3v3_p12v_adc_alert';
NODE_NAME     U18 AA1
 '@T6G_MB_LIB.T6G(SCH_1):PAGE81_I143@PURE_QUANTA.LCMXO3LF9400C5BG484C(CHIPS)':
 'PL29B': CDS_PINID='PL29B';
NODE_NAME     R1340 1
 '@T6G_MB_LIB.T6G(SCH_1):PAGE81_I176@PURE_QUANTA.Q_RES(CHIPS)':
 'A': CDS_PINID='A';
NET_NAME
'OCP_SFF_P3V3_P12V_ADC_R_ALERT'
 '@T6G_MB_LIB.T6G(SCH_1):OCP_SFF_P3V3_P12V_ADC_R_ALERT':
 C_SIGNAL='@t6g_mb_lib.t6g(sch_1):ocp_sff_p3v3_p12v_adc_r_alert';
NODE_NAME     R3563 2
 '@T6G_MB_LIB.T6G(SCH_1):PAGE295_I35@PURE_QUANTA.Q_RES(CHIPS)':
 'B': CDS_PINID='B';
NODE_NAME     R1270 2
 '@T6G_MB_LIB.T6G(SCH_1):PAGE466_I23@PURE_QUANTA.Q_RES(CHIPS)':
 'B': CDS_PINID='B';
NODE_NAME     R1340 2
 '@T6G_MB_LIB.T6G(SCH_1):PAGE81_I176@PURE_QUANTA.Q_RES(CHIPS)':
 'B': CDS_PINID='B';
NODE_NAME     R1327 2
 '@T6G_MB_LIB.T6G(SCH_1):PAGE466_I85@PURE_QUANTA.Q_RES(CHIPS)':
 'B': CDS_PINID='B';
NET_NAME
'OCP_SFF_PRSNT01_R1_N'
 '@T6G_MB_LIB.T6G(SCH_1):OCP_SFF_PRSNT01_R1_N':
 C_SIGNAL='@t6g_mb_lib.t6g(sch_1):ocp_sff_prsnt01_r1_n';
NODE_NAME     U242 1
 '@T6G_MB_LIB.T6G(SCH_1):PAGE258_I13@PURE_QUANTA.74LVC2G08DP(CHIPS)':
 '1A': CDS_PINID='\1a\';
NODE_NAME     R8013 2
 '@T6G_MB_LIB.T6G(SCH_1):PAGE258_I64@PURE_QUANTA.Q_RES(CHIPS)':
 'B': CDS_PINID='B';
NODE_NAME     C8001 1
 '@T6G_MB_LIB.T6G(SCH_1):PAGE258_I68@PURE_QUANTA.Q_CAP(CHIPS)':
 'A': CDS_PINID='A';
NET_NAME
'OCP_SFF_PRSNT01_R_N'
 '@T6G_MB_LIB.T6G(SCH_1):OCP_SFF_PRSNT01_R_N':
 C_SIGNAL='@t6g_mb_lib.t6g(sch_1):ocp_sff_prsnt01_r_n';
NODE_NAME     U240 7
 '@T6G_MB_LIB.T6G(SCH_1):PAGE258_I11@PURE_QUANTA.74LVC2G08DP(CHIPS)':
 '1Y': CDS_PINID='\1y\';
NODE_NAME     R8013 1
 '@T6G_MB_LIB.T6G(SCH_1):PAGE258_I64@PURE_QUANTA.Q_RES(CHIPS)':
 'A': CDS_PINID='A';
NET_NAME
'OCP_SFF_PRSNT0_R_N'
 '@T6G_MB_LIB.T6G(SCH_1):OCP_SFF_PRSNT0_R_N':
 C_SIGNAL='@t6g_mb_lib.t6g(sch_1):ocp_sff_prsnt0_r_n';
NODE_NAME     J38 B42
 '@T6G_MB_LIB.T6G(SCH_1):PAGE335_I168@PURE_QUANTA.SCONN168_ME1016810202011(CHIPS)':
 'PRSNTB0#': CDS_PINID='\prsntb0#\';
NODE_NAME     U240 1
 '@T6G_MB_LIB.T6G(SCH_1):PAGE258_I11@PURE_QUANTA.74LVC2G08DP(CHIPS)':
 '1A': CDS_PINID='\1a\';
NODE_NAME     R1905 2
 '@T6G_MB_LIB.T6G(SCH_1):PAGE338_I15@PURE_QUANTA.Q_RES(CHIPS)':
 'B': CDS_PINID='B';
NODE_NAME     U211 1
 '@T6G_MB_LIB.T6G(SCH_1):PAGE338_I29@PURE_QUANTA.74LVC2G07DW7(CHIPS)':
 '1A': CDS_PINID='\1a\';
NET_NAME
'OCP_SFF_PRSNT1_R_N'
 '@T6G_MB_LIB.T6G(SCH_1):OCP_SFF_PRSNT1_R_N':
 C_SIGNAL='@t6g_mb_lib.t6g(sch_1):ocp_sff_prsnt1_r_n';
NODE_NAME     J38 A42
 '@T6G_MB_LIB.T6G(SCH_1):PAGE335_I168@PURE_QUANTA.SCONN168_ME1016810202011(CHIPS)':
 'PRSNTB1#': CDS_PINID='\prsntb1#\';
NODE_NAME     U240 2
 '@T6G_MB_LIB.T6G(SCH_1):PAGE258_I11@PURE_QUANTA.74LVC2G08DP(CHIPS)':
 '1B': CDS_PINID='\1b\';
NODE_NAME     R1907 2
 '@T6G_MB_LIB.T6G(SCH_1):PAGE338_I28@PURE_QUANTA.Q_RES(CHIPS)':
 'B': CDS_PINID='B';
NODE_NAME     U211 3
 '@T6G_MB_LIB.T6G(SCH_1):PAGE338_I29@PURE_QUANTA.74LVC2G07DW7(CHIPS)':
 '2A': CDS_PINID='\2a\';
NET_NAME
'OCP_SFF_PRSNT23_R1_N'
 '@T6G_MB_LIB.T6G(SCH_1):OCP_SFF_PRSNT23_R1_N':
 C_SIGNAL='@t6g_mb_lib.t6g(sch_1):ocp_sff_prsnt23_r1_n';
NODE_NAME     U242 2
 '@T6G_MB_LIB.T6G(SCH_1):PAGE258_I13@PURE_QUANTA.74LVC2G08DP(CHIPS)':
 '1B': CDS_PINID='\1b\';
NODE_NAME     R8014 2
 '@T6G_MB_LIB.T6G(SCH_1):PAGE258_I65@PURE_QUANTA.Q_RES(CHIPS)':
 'B': CDS_PINID='B';
NODE_NAME     C8002 1
 '@T6G_MB_LIB.T6G(SCH_1):PAGE258_I70@PURE_QUANTA.Q_CAP(CHIPS)':
 'A': CDS_PINID='A';
NET_NAME
'OCP_SFF_PRSNT23_R_N'
 '@T6G_MB_LIB.T6G(SCH_1):OCP_SFF_PRSNT23_R_N':
 C_SIGNAL='@t6g_mb_lib.t6g(sch_1):ocp_sff_prsnt23_r_n';
NODE_NAME     U240 3
 '@T6G_MB_LIB.T6G(SCH_1):PAGE258_I12@PURE_QUANTA.74LVC2G08DP(CHIPS)':
 '2Y': CDS_PINID='\2y\';
NODE_NAME     R8014 1
 '@T6G_MB_LIB.T6G(SCH_1):PAGE258_I65@PURE_QUANTA.Q_RES(CHIPS)':
 'A': CDS_PINID='A';
NET_NAME
'OCP_SFF_PRSNT2_R_N'
 '@T6G_MB_LIB.T6G(SCH_1):OCP_SFF_PRSNT2_R_N':
 C_SIGNAL='@t6g_mb_lib.t6g(sch_1):ocp_sff_prsnt2_r_n';
NODE_NAME     J38 A12
 '@T6G_MB_LIB.T6G(SCH_1):PAGE335_I168@PURE_QUANTA.SCONN168_ME1016810202011(CHIPS)':
 'PRSNTB2#': CDS_PINID='\prsntb2#\';
NODE_NAME     U240 5
 '@T6G_MB_LIB.T6G(SCH_1):PAGE258_I12@PURE_QUANTA.74LVC2G08DP(CHIPS)':
 '2A': CDS_PINID='\2a\';
NODE_NAME     R1906 2
 '@T6G_MB_LIB.T6G(SCH_1):PAGE338_I9@PURE_QUANTA.Q_RES(CHIPS)':
 'B': CDS_PINID='B';
NODE_NAME     U8 1
 '@T6G_MB_LIB.T6G(SCH_1):PAGE338_I26@PURE_QUANTA.74LVC2G07DW7(CHIPS)':
 '1A': CDS_PINID='\1a\';
NET_NAME
'OCP_SFF_PRSNT3_R_N'
 '@T6G_MB_LIB.T6G(SCH_1):OCP_SFF_PRSNT3_R_N':
 C_SIGNAL='@t6g_mb_lib.t6g(sch_1):ocp_sff_prsnt3_r_n';
NODE_NAME     J38 B70
 '@T6G_MB_LIB.T6G(SCH_1):PAGE335_I168@PURE_QUANTA.SCONN168_ME1016810202011(CHIPS)':
 'PRSNTB3#': CDS_PINID='\prsntb3#\';
NODE_NAME     U240 6
 '@T6G_MB_LIB.T6G(SCH_1):PAGE258_I12@PURE_QUANTA.74LVC2G08DP(CHIPS)':
 '2B': CDS_PINID='\2b\';
NODE_NAME     R1908 2
 '@T6G_MB_LIB.T6G(SCH_1):PAGE338_I24@PURE_QUANTA.Q_RES(CHIPS)':
 'B': CDS_PINID='B';
NODE_NAME     U8 3
 '@T6G_MB_LIB.T6G(SCH_1):PAGE338_I26@PURE_QUANTA.74LVC2G07DW7(CHIPS)':
 '2A': CDS_PINID='\2a\';
NET_NAME
'OCP_SFF_PRSNTA_R_N'
 '@T6G_MB_LIB.T6G(SCH_1):OCP_SFF_PRSNTA_R_N':
 C_SIGNAL='@t6g_mb_lib.t6g(sch_1):ocp_sff_prsnta_r_n';
NODE_NAME     J38 A10
 '@T6G_MB_LIB.T6G(SCH_1):PAGE335_I168@PURE_QUANTA.SCONN168_ME1016810202011(CHIPS)':
 'PRSNTA#': CDS_PINID='\prsnta#\';
NODE_NAME     R1895 1
 '@T6G_MB_LIB.T6G(SCH_1):PAGE335_I169@PURE_QUANTA.Q_RES(CHIPS)':
 'A': CDS_PINID='A';
NET_NAME
'OCP_SFF_PRSNT_ALL_R1_N'
 '@T6G_MB_LIB.T6G(SCH_1):OCP_SFF_PRSNT_ALL_R1_N':
 C_SIGNAL='@t6g_mb_lib.t6g(sch_1):ocp_sff_prsnt_all_r1_n';
NODE_NAME     U243 6
 '@T6G_MB_LIB.T6G(SCH_1):PAGE258_I15@PURE_QUANTA.NC7SB3157(CHIPS)':
 'S': CDS_PINID='S';
NODE_NAME     R3303 2
 '@T6G_MB_LIB.T6G(SCH_1):PAGE258_I44@PURE_QUANTA.Q_RES(CHIPS)':
 'B': CDS_PINID='B';
NET_NAME
'OCP_SFF_PRSNT_ALL_R3_N'
 '@T6G_MB_LIB.T6G(SCH_1):OCP_SFF_PRSNT_ALL_R3_N':
 C_SIGNAL='@t6g_mb_lib.t6g(sch_1):ocp_sff_prsnt_all_r3_n';
NODE_NAME     U244 6
 '@T6G_MB_LIB.T6G(SCH_1):PAGE258_I16@PURE_QUANTA.NC7SB3157(CHIPS)':
 'S': CDS_PINID='S';
NODE_NAME     R3304 2
 '@T6G_MB_LIB.T6G(SCH_1):PAGE258_I45@PURE_QUANTA.Q_RES(CHIPS)':
 'B': CDS_PINID='B';
NET_NAME
'OCP_SFF_PRSNT_ALL_R_N'
 '@T6G_MB_LIB.T6G(SCH_1):OCP_SFF_PRSNT_ALL_R_N':
 C_SIGNAL='@t6g_mb_lib.t6g(sch_1):ocp_sff_prsnt_all_r_n';
NODE_NAME     U242 7
 '@T6G_MB_LIB.T6G(SCH_1):PAGE258_I13@PURE_QUANTA.74LVC2G08DP(CHIPS)':
 '1Y': CDS_PINID='\1y\';
NODE_NAME     R3303 1
 '@T6G_MB_LIB.T6G(SCH_1):PAGE258_I44@PURE_QUANTA.Q_RES(CHIPS)':
 'A': CDS_PINID='A';
NODE_NAME     R3304 1
 '@T6G_MB_LIB.T6G(SCH_1):PAGE258_I45@PURE_QUANTA.Q_RES(CHIPS)':
 'A': CDS_PINID='A';
NET_NAME
'OCP_SFF_PWRBRK_BUFF_N'
 '@T6G_MB_LIB.T6G(SCH_1):OCP_SFF_PWRBRK_BUFF_N':
 C_SIGNAL='@t6g_mb_lib.t6g(sch_1):ocp_sff_pwrbrk_buff_n';
NODE_NAME     R53 2
 '@T6G_MB_LIB.T6G(SCH_1):PAGE337_I42@PURE_QUANTA.Q_RES(CHIPS)':
 'B': CDS_PINID='B';
NODE_NAME     R1595 1
 '@T6G_MB_LIB.T6G(SCH_1):PAGE337_I44@PURE_QUANTA.Q_RES(CHIPS)':
 'A': CDS_PINID='A';
NODE_NAME     U104 4
 '@T6G_MB_LIB.T6G(SCH_1):PAGE337_I38@PURE_QUANTA.74LVC1G07GV(CHIPS)':
 'Y': CDS_PINID='Y';
NET_NAME
'OCP_SFF_PWRBRK_N'
 '@T6G_MB_LIB.T6G(SCH_1):OCP_SFF_PWRBRK_N':
 C_SIGNAL='@t6g_mb_lib.t6g(sch_1):ocp_sff_pwrbrk_n';
NODE_NAME     J38 A70
 '@T6G_MB_LIB.T6G(SCH_1):PAGE335_I168@PURE_QUANTA.SCONN168_ME1016810202011(CHIPS)':
 'PWRBRK0#': CDS_PINID='\pwrbrk0#\';
NODE_NAME     R1595 2
 '@T6G_MB_LIB.T6G(SCH_1):PAGE337_I44@PURE_QUANTA.Q_RES(CHIPS)':
 'B': CDS_PINID='B';
NET_NAME
'OCP_SFF_RBT_ARB_IN'
 '@T6G_MB_LIB.T6G(SCH_1):OCP_SFF_RBT_ARB_IN':
 C_SIGNAL='@t6g_mb_lib.t6g(sch_1):ocp_sff_rbt_arb_in';
NODE_NAME     R1290 2
 '@T6G_MB_LIB.T6G(SCH_1):PAGE336_I98@PURE_QUANTA.Q_RES(CHIPS)':
 'B': CDS_PINID='B';
NODE_NAME     U244 3
 '@T6G_MB_LIB.T6G(SCH_1):PAGE258_I16@PURE_QUANTA.NC7SB3157(CHIPS)':
 'B0': CDS_PINID='B0';
NET_NAME
'OCP_SFF_RBT_ARB_IN_MUX1'
 '@T6G_MB_LIB.T6G(SCH_1):OCP_SFF_RBT_ARB_IN_MUX1':
 C_SIGNAL='@t6g_mb_lib.t6g(sch_1):ocp_sff_rbt_arb_in_mux1';
NODE_NAME     U246 4
 '@T6G_MB_LIB.T6G(SCH_1):PAGE258_I17@PURE_QUANTA.NC7SB3157(CHIPS)':
 'A': CDS_PINID='A';
NODE_NAME     R3305 1
 '@T6G_MB_LIB.T6G(SCH_1):PAGE258_I50@PURE_QUANTA.Q_RES(CHIPS)':
 'A': CDS_PINID='A';
NET_NAME
'OCP_SFF_RBT_ARB_IN_MUX1_R'
 '@T6G_MB_LIB.T6G(SCH_1):OCP_SFF_RBT_ARB_IN_MUX1_R':
 C_SIGNAL='@t6g_mb_lib.t6g(sch_1):ocp_sff_rbt_arb_in_mux1_r';
NODE_NAME     U244 4
 '@T6G_MB_LIB.T6G(SCH_1):PAGE258_I16@PURE_QUANTA.NC7SB3157(CHIPS)':
 'A': CDS_PINID='A';
NODE_NAME     R3305 2
 '@T6G_MB_LIB.T6G(SCH_1):PAGE258_I50@PURE_QUANTA.Q_RES(CHIPS)':
 'B': CDS_PINID='B';
NET_NAME
'OCP_SFF_RBT_ARB_IN_MUX2'
 '@T6G_MB_LIB.T6G(SCH_1):OCP_SFF_RBT_ARB_IN_MUX2':
 C_SIGNAL='@t6g_mb_lib.t6g(sch_1):ocp_sff_rbt_arb_in_mux2';
NODE_NAME     U243 4
 '@T6G_MB_LIB.T6G(SCH_1):PAGE258_I15@PURE_QUANTA.NC7SB3157(CHIPS)':
 'A': CDS_PINID='A';
NODE_NAME     R3307 1
 '@T6G_MB_LIB.T6G(SCH_1):PAGE258_I52@PURE_QUANTA.Q_RES(CHIPS)':
 'A': CDS_PINID='A';
NET_NAME
'OCP_SFF_RBT_ARB_IN_MUX2_R'
 '@T6G_MB_LIB.T6G(SCH_1):OCP_SFF_RBT_ARB_IN_MUX2_R':
 C_SIGNAL='@t6g_mb_lib.t6g(sch_1):ocp_sff_rbt_arb_in_mux2_r';
NODE_NAME     U245 4
 '@T6G_MB_LIB.T6G(SCH_1):PAGE258_I18@PURE_QUANTA.NC7SB3157(CHIPS)':
 'A': CDS_PINID='A';
NODE_NAME     R3307 2
 '@T6G_MB_LIB.T6G(SCH_1):PAGE258_I52@PURE_QUANTA.Q_RES(CHIPS)':
 'B': CDS_PINID='B';
NET_NAME
'OCP_SFF_RBT_ARB_IN_R'
 '@T6G_MB_LIB.T6G(SCH_1):OCP_SFF_RBT_ARB_IN_R':
 C_SIGNAL='@t6g_mb_lib.t6g(sch_1):ocp_sff_rbt_arb_in_r';
NODE_NAME     U67 12
 '@T6G_MB_LIB.T6G(SCH_1):PAGE336_I1@PURE_QUANTA.74CBTLV3126PW(CHIPS)':
 '4A': CDS_PINID='\4a\';
NODE_NAME     R1290 1
 '@T6G_MB_LIB.T6G(SCH_1):PAGE336_I98@PURE_QUANTA.Q_RES(CHIPS)':
 'A': CDS_PINID='A';
NODE_NAME     R3237 2
 '@T6G_MB_LIB.T6G(SCH_1):PAGE336_I156@PURE_QUANTA.Q_RES(CHIPS)':
 'B': CDS_PINID='B';
NET_NAME
'OCP_SFF_RBT_ARB_OUT'
 '@T6G_MB_LIB.T6G(SCH_1):OCP_SFF_RBT_ARB_OUT':
 C_SIGNAL='@t6g_mb_lib.t6g(sch_1):ocp_sff_rbt_arb_out';
NODE_NAME     U7 12
 '@T6G_MB_LIB.T6G(SCH_1):PAGE336_I2@PURE_QUANTA.74CBTLV3126PW(CHIPS)':
 '4A': CDS_PINID='\4a\';
NODE_NAME     R3237 1
 '@T6G_MB_LIB.T6G(SCH_1):PAGE336_I156@PURE_QUANTA.Q_RES(CHIPS)':
 'A': CDS_PINID='A';
NODE_NAME     U243 3
 '@T6G_MB_LIB.T6G(SCH_1):PAGE258_I15@PURE_QUANTA.NC7SB3157(CHIPS)':
 'B0': CDS_PINID='B0';
NET_NAME
'OCP_SFF_WAKE_BUFF_N'
 '@T6G_MB_LIB.T6G(SCH_1):OCP_SFF_WAKE_BUFF_N':
 C_SIGNAL='@t6g_mb_lib.t6g(sch_1):ocp_sff_wake_buff_n';
NODE_NAME     U8082 4
 '@T6G_MB_LIB.T6G(SCH_1):PAGE337_I8@PURE_QUANTA.74LVC1G126SE7(CHIPS)':
 'Y': CDS_PINID='Y';
NODE_NAME     R1594 1
 '@T6G_MB_LIB.T6G(SCH_1):PAGE337_I31@PURE_QUANTA.Q_RES(CHIPS)':
 'A': CDS_PINID='A';
NODE_NAME     R2488 2
 '@T6G_MB_LIB.T6G(SCH_1):PAGE337_I35@PURE_QUANTA.Q_RES(CHIPS)':
 'B': CDS_PINID='B';
NET_NAME
'OCP_SFF_WAKE_BUFF_R_N'
 '@T6G_MB_LIB.T6G(SCH_1):OCP_SFF_WAKE_BUFF_R_N':
 C_SIGNAL='@t6g_mb_lib.t6g(sch_1):ocp_sff_wake_buff_r_n';
NODE_NAME     U157 2
 '@T6G_MB_LIB.T6G(SCH_1):PAGE337_I25@PURE_QUANTA.74LVC1G07GV(CHIPS)':
 'A': CDS_PINID='A';
NODE_NAME     R1594 2
 '@T6G_MB_LIB.T6G(SCH_1):PAGE337_I31@PURE_QUANTA.Q_RES(CHIPS)':
 'B': CDS_PINID='B';
NET_NAME
'OCP_V3_1_P3V3_PLD_PWRGD'
 '@T6G_MB_LIB.T6G(SCH_1):OCP_V3_1_P3V3_PLD_PWRGD':
 C_SIGNAL='@t6g_mb_lib.t6g(sch_1):ocp_v3_1_p3v3_pld_pwrgd';
NODE_NAME     R1143 1
 '@T6G_MB_LIB.T6G(SCH_1):PAGE340_I65@PURE_QUANTA.Q_RES(CHIPS)':
 'A': CDS_PINID='A';
NODE_NAME     U30 4
 '@T6G_MB_LIB.T6G(SCH_1):PAGE340_I66@PURE_QUANTA.SN74LVC1G07DBVR(CHIPS)':
 'Y': CDS_PINID='Y';
NET_NAME
'OCP_V3_1_P3V3_PLD_R_PWRGD'
 '@T6G_MB_LIB.T6G(SCH_1):OCP_V3_1_P3V3_PLD_R_PWRGD':
 C_SIGNAL='@t6g_mb_lib.t6g(sch_1):ocp_v3_1_p3v3_pld_r_pwrgd';
NODE_NAME     U18 A9
 '@T6G_MB_LIB.T6G(SCH_1):PAGE79_I94@PURE_QUANTA.LCMXO3LF9400C5BG484C(CHIPS)':
 'PT21B': CDS_PINID='PT21B';
NODE_NAME     R1144 2
 '@T6G_MB_LIB.T6G(SCH_1):PAGE340_I64@PURE_QUANTA.Q_RES(CHIPS)':
 'B': CDS_PINID='B';
NODE_NAME     R1143 2
 '@T6G_MB_LIB.T6G(SCH_1):PAGE340_I65@PURE_QUANTA.Q_RES(CHIPS)':
 'B': CDS_PINID='B';
NET_NAME
'OCP_V3_1_P3V3_PWRGD'
 '@T6G_MB_LIB.T6G(SCH_1):OCP_V3_1_P3V3_PWRGD':
 C_SIGNAL='@t6g_mb_lib.t6g(sch_1):ocp_v3_1_p3v3_pwrgd';
NODE_NAME     R1142 1
 '@T6G_MB_LIB.T6G(SCH_1):PAGE340_I71@PURE_QUANTA.Q_RES(CHIPS)':
 'A': CDS_PINID='A';
NODE_NAME     R8094 2
 '@T6G_MB_LIB.T6G(SCH_1):PAGE340_I85@PURE_QUANTA.Q_RES(CHIPS)':
 'B': CDS_PINID='B';
NODE_NAME     R3783 2
 '@T6G_MB_LIB.T6G(SCH_1):PAGE338_I131@PURE_QUANTA.Q_RES(CHIPS)':
 'B': CDS_PINID='B';
NODE_NAME     R3794 2
 '@T6G_MB_LIB.T6G(SCH_1):PAGE338_I132@PURE_QUANTA.Q_RES(CHIPS)':
 'B': CDS_PINID='B';
NODE_NAME     U9050 1
 '@T6G_MB_LIB.T6G(SCH_1):PAGE340_I91@PURE_QUANTA.74LVC1G08W57(CHIPS)':
 'A': CDS_PINID='A';
NODE_NAME     R1519 2
 '@T6G_MB_LIB.T6G(SCH_1):PAGE340_I101@PURE_QUANTA.Q_RES(CHIPS)':
 'B': CDS_PINID='B';
NET_NAME
'OCP_V3_1_P3V3_R1_PWRGD'
 '@T6G_MB_LIB.T6G(SCH_1):OCP_V3_1_P3V3_R1_PWRGD':
 C_SIGNAL='@t6g_mb_lib.t6g(sch_1):ocp_v3_1_p3v3_r1_pwrgd';
NODE_NAME     U8001 2
 '@T6G_MB_LIB.T6G(SCH_1):PAGE340_I80@PURE_QUANTA.APX80929SAG7(CHIPS)':
 'RESET_L': CDS_PINID='RESET_L';
NODE_NAME     R8093 1
 '@T6G_MB_LIB.T6G(SCH_1):PAGE340_I84@PURE_QUANTA.Q_RES(CHIPS)':
 'A': CDS_PINID='A';
NODE_NAME     R8094 1
 '@T6G_MB_LIB.T6G(SCH_1):PAGE340_I85@PURE_QUANTA.Q_RES(CHIPS)':
 'A': CDS_PINID='A';
NODE_NAME     R8092 2
 '@T6G_MB_LIB.T6G(SCH_1):PAGE340_I90@PURE_QUANTA.Q_RES(CHIPS)':
 'B': CDS_PINID='B';
NET_NAME
'OCP_V3_1_P3V3_R2_PWRGD'
 '@T6G_MB_LIB.T6G(SCH_1):OCP_V3_1_P3V3_R2_PWRGD':
 C_SIGNAL='@t6g_mb_lib.t6g(sch_1):ocp_v3_1_p3v3_r2_pwrgd';
NODE_NAME     U30 2
 '@T6G_MB_LIB.T6G(SCH_1):PAGE340_I66@PURE_QUANTA.SN74LVC1G07DBVR(CHIPS)':
 'A': CDS_PINID='A';
NODE_NAME     R1142 2
 '@T6G_MB_LIB.T6G(SCH_1):PAGE340_I71@PURE_QUANTA.Q_RES(CHIPS)':
 'B': CDS_PINID='B';
NET_NAME
'OCP_V3_1_P3V3_R3_PWRGD'
 '@T6G_MB_LIB.T6G(SCH_1):OCP_V3_1_P3V3_R3_PWRGD':
 C_SIGNAL='@t6g_mb_lib.t6g(sch_1):ocp_v3_1_p3v3_r3_pwrgd';
NODE_NAME     R9034 1
 '@T6G_MB_LIB.T6G(SCH_1):PAGE340_I3@PURE_QUANTA.Q_RES(CHIPS)':
 'A': CDS_PINID='A';
NODE_NAME     R9022 1
 '@T6G_MB_LIB.T6G(SCH_1):PAGE340_I13@PURE_QUANTA.Q_RES(CHIPS)':
 'A': CDS_PINID='A';
NODE_NAME     R1519 1
 '@T6G_MB_LIB.T6G(SCH_1):PAGE340_I101@PURE_QUANTA.Q_RES(CHIPS)':
 'A': CDS_PINID='A';
NODE_NAME     R1518 2
 '@T6G_MB_LIB.T6G(SCH_1):PAGE340_I102@PURE_QUANTA.Q_RES(CHIPS)':
 'B': CDS_PINID='B';
NET_NAME
'OCP_V3_2_AUX_PWR_EN'
 '@T6G_MB_LIB.T6G(SCH_1):OCP_V3_2_AUX_PWR_EN':
 C_SIGNAL='@t6g_mb_lib.t6g(sch_1):ocp_v3_2_aux_pwr_en';
NODE_NAME     R3203 1
 '@T6G_MB_LIB.T6G(SCH_1):PAGE307_I81@PURE_QUANTA.Q_RES(CHIPS)':
 'A': CDS_PINID='A';
NODE_NAME     R3234 1
 '@T6G_MB_LIB.T6G(SCH_1):PAGE342_I6@PURE_QUANTA.Q_RES(CHIPS)':
 'A': CDS_PINID='A';
NODE_NAME     R3164 2
 '@T6G_MB_LIB.T6G(SCH_1):PAGE341_I34@PURE_QUANTA.Q_RES(CHIPS)':
 'B': CDS_PINID='B';
NODE_NAME     R3172 1
 '@T6G_MB_LIB.T6G(SCH_1):PAGE341_I42@PURE_QUANTA.Q_RES(CHIPS)':
 'A': CDS_PINID='A';
NODE_NAME     R1175 2
 '@T6G_MB_LIB.T6G(SCH_1):PAGE257_I42@PURE_QUANTA.Q_RES(CHIPS)':
 'B': CDS_PINID='B';
NODE_NAME     R1172 2
 '@T6G_MB_LIB.T6G(SCH_1):PAGE257_I51@PURE_QUANTA.Q_RES(CHIPS)':
 'B': CDS_PINID='B';
NET_NAME
'OCP_V3_2_AUX_PWR_EN_R'
 '@T6G_MB_LIB.T6G(SCH_1):OCP_V3_2_AUX_PWR_EN_R':
 C_SIGNAL='@t6g_mb_lib.t6g(sch_1):ocp_v3_2_aux_pwr_en_r';
NODE_NAME     J35 B12
 '@T6G_MB_LIB.T6G(SCH_1):PAGE341_I168@PURE_QUANTA.SCONN168_ME1016810202011(CHIPS)':
 'AUX_PWR_EN': CDS_PINID='AUX_PWR_EN';
NODE_NAME     R3172 2
 '@T6G_MB_LIB.T6G(SCH_1):PAGE341_I42@PURE_QUANTA.Q_RES(CHIPS)':
 'B': CDS_PINID='B';
NET_NAME
'OCP_V3_2_AUX_PWR_EN_R1'
 '@T6G_MB_LIB.T6G(SCH_1):OCP_V3_2_AUX_PWR_EN_R1':
 C_SIGNAL='@t6g_mb_lib.t6g(sch_1):ocp_v3_2_aux_pwr_en_r1';
NODE_NAME     U286 1
 '@T6G_MB_LIB.T6G(SCH_1):PAGE307_I80@PURE_QUANTA.74LVC1G126SE7(CHIPS)':
 'OE': CDS_PINID='OE';
NODE_NAME     R3203 2
 '@T6G_MB_LIB.T6G(SCH_1):PAGE307_I81@PURE_QUANTA.Q_RES(CHIPS)':
 'B': CDS_PINID='B';
NET_NAME
'OCP_V3_2_AUX_PWR_EN_R2'
 '@T6G_MB_LIB.T6G(SCH_1):OCP_V3_2_AUX_PWR_EN_R2':
 C_SIGNAL='@t6g_mb_lib.t6g(sch_1):ocp_v3_2_aux_pwr_en_r2';
NODE_NAME     R1147 1
 '@T6G_MB_LIB.T6G(SCH_1):PAGE257_I39@PURE_QUANTA.Q_RES(CHIPS)':
 'A': CDS_PINID='A';
NODE_NAME     U37 4
 '@T6G_MB_LIB.T6G(SCH_1):PAGE257_I40@PURE_QUANTA.74LVC1G32GW(CHIPS)':
 'O': CDS_PINID='O';
NODE_NAME     R1146 1
 '@T6G_MB_LIB.T6G(SCH_1):PAGE257_I41@PURE_QUANTA.Q_RES(CHIPS)':
 'A': CDS_PINID='A';
NODE_NAME     R1175 1
 '@T6G_MB_LIB.T6G(SCH_1):PAGE257_I42@PURE_QUANTA.Q_RES(CHIPS)':
 'A': CDS_PINID='A';
NET_NAME
'OCP_V3_2_AUX_PWR_EN_R3'
 '@T6G_MB_LIB.T6G(SCH_1):OCP_V3_2_AUX_PWR_EN_R3':
 C_SIGNAL='@t6g_mb_lib.t6g(sch_1):ocp_v3_2_aux_pwr_en_r3';
NODE_NAME     R3234 2
 '@T6G_MB_LIB.T6G(SCH_1):PAGE342_I6@PURE_QUANTA.Q_RES(CHIPS)':
 'B': CDS_PINID='B';
NODE_NAME     U225 1
 '@T6G_MB_LIB.T6G(SCH_1):PAGE342_I9@PURE_QUANTA.74LVC1G126SE7(CHIPS)':
 'OE': CDS_PINID='OE';
NET_NAME
'OCP_V3_2_BIF0_R_N'
 '@T6G_MB_LIB.T6G(SCH_1):OCP_V3_2_BIF0_R_N':
 C_SIGNAL='@t6g_mb_lib.t6g(sch_1):ocp_v3_2_bif0_r_n';
NODE_NAME     R3169 2
 '@T6G_MB_LIB.T6G(SCH_1):PAGE341_I43@PURE_QUANTA.Q_RES(CHIPS)':
 'B': CDS_PINID='B';
NODE_NAME     J35 B7
 '@T6G_MB_LIB.T6G(SCH_1):PAGE341_I168@PURE_QUANTA.SCONN168_ME1016810202011(CHIPS)':
 'BIF0#': CDS_PINID='\bif0#\';
NET_NAME
'OCP_V3_2_BIF1_R_N'
 '@T6G_MB_LIB.T6G(SCH_1):OCP_V3_2_BIF1_R_N':
 C_SIGNAL='@t6g_mb_lib.t6g(sch_1):ocp_v3_2_bif1_r_n';
NODE_NAME     J35 B8
 '@T6G_MB_LIB.T6G(SCH_1):PAGE341_I168@PURE_QUANTA.SCONN168_ME1016810202011(CHIPS)':
 'BIF1#': CDS_PINID='\bif1#\';
NODE_NAME     R3170 2
 '@T6G_MB_LIB.T6G(SCH_1):PAGE341_I44@PURE_QUANTA.Q_RES(CHIPS)':
 'B': CDS_PINID='B';
NET_NAME
'OCP_V3_2_BIF2_R_N'
 '@T6G_MB_LIB.T6G(SCH_1):OCP_V3_2_BIF2_R_N':
 C_SIGNAL='@t6g_mb_lib.t6g(sch_1):ocp_v3_2_bif2_r_n';
NODE_NAME     J35 B9
 '@T6G_MB_LIB.T6G(SCH_1):PAGE341_I168@PURE_QUANTA.SCONN168_ME1016810202011(CHIPS)':
 'BIF2#': CDS_PINID='\bif2#\';
NODE_NAME     R3171 2
 '@T6G_MB_LIB.T6G(SCH_1):PAGE341_I45@PURE_QUANTA.Q_RES(CHIPS)':
 'B': CDS_PINID='B';
NET_NAME
'OCP_V3_2_ID0'
 '@T6G_MB_LIB.T6G(SCH_1):OCP_V3_2_ID0':
 C_SIGNAL='@t6g_mb_lib.t6g(sch_1):ocp_v3_2_id0';
NODE_NAME     R3162 2
 '@T6G_MB_LIB.T6G(SCH_1):PAGE341_I26@PURE_QUANTA.Q_RES(CHIPS)':
 'B': CDS_PINID='B';
NODE_NAME     J35 OB7
 '@T6G_MB_LIB.T6G(SCH_1):PAGE341_I168@PURE_QUANTA.SCONN168_ME1016810202011(CHIPS)':
 'SLOT_ID0': CDS_PINID='SLOT_ID0';
NODE_NAME     R3163 1
 '@T6G_MB_LIB.T6G(SCH_1):PAGE341_I2@PURE_QUANTA.Q_RES(CHIPS)':
 'A': CDS_PINID='A';
NET_NAME
'OCP_V3_2_ID1'
 '@T6G_MB_LIB.T6G(SCH_1):OCP_V3_2_ID1':
 C_SIGNAL='@t6g_mb_lib.t6g(sch_1):ocp_v3_2_id1';
NODE_NAME     J35 OA6
 '@T6G_MB_LIB.T6G(SCH_1):PAGE341_I168@PURE_QUANTA.SCONN168_ME1016810202011(CHIPS)':
 'SLOT_ID1': CDS_PINID='SLOT_ID1';
NODE_NAME     R3167 1
 '@T6G_MB_LIB.T6G(SCH_1):PAGE341_I3@PURE_QUANTA.Q_RES(CHIPS)':
 'A': CDS_PINID='A';
NODE_NAME     R3166 2
 '@T6G_MB_LIB.T6G(SCH_1):PAGE341_I28@PURE_QUANTA.Q_RES(CHIPS)':
 'B': CDS_PINID='B';
NET_NAME
'OCP_V3_2_ISO1_RBT_ARB_IN'
 '@T6G_MB_LIB.T6G(SCH_1):OCP_V3_2_ISO1_RBT_ARB_IN':
 C_SIGNAL='@t6g_mb_lib.t6g(sch_1):ocp_v3_2_iso1_rbt_arb_in';
NODE_NAME     U222 11
 '@T6G_MB_LIB.T6G(SCH_1):PAGE307_I32@PURE_QUANTA.74CBTLV3126PW(CHIPS)':
 '4B': CDS_PINID='\4b\';
NODE_NAME     J35 OA4
 '@T6G_MB_LIB.T6G(SCH_1):PAGE341_I168@PURE_QUANTA.SCONN168_ME1016810202011(CHIPS)':
 'RBT_ARB_IN': CDS_PINID='RBT_ARB_IN';
NET_NAME
'OCP_V3_2_ISO2_RBT_ARB_OUT'
 '@T6G_MB_LIB.T6G(SCH_1):OCP_V3_2_ISO2_RBT_ARB_OUT':
 C_SIGNAL='@t6g_mb_lib.t6g(sch_1):ocp_v3_2_iso2_rbt_arb_out';
NODE_NAME     U223 11
 '@T6G_MB_LIB.T6G(SCH_1):PAGE307_I78@PURE_QUANTA.74CBTLV3126PW(CHIPS)':
 '4B': CDS_PINID='\4b\';
NODE_NAME     J35 OA5
 '@T6G_MB_LIB.T6G(SCH_1):PAGE341_I168@PURE_QUANTA.SCONN168_ME1016810202011(CHIPS)':
 'RBT_ARB_OUT': CDS_PINID='RBT_ARB_OUT';
NET_NAME
'OCP_V3_2_ISO_BIF0_EN'
 '@T6G_MB_LIB.T6G(SCH_1):OCP_V3_2_ISO_BIF0_EN':
 C_SIGNAL='@t6g_mb_lib.t6g(sch_1):ocp_v3_2_iso_bif0_en';
NODE_NAME     R3208 1
 '@T6G_MB_LIB.T6G(SCH_1):PAGE307_I37@PURE_QUANTA.Q_RES(CHIPS)':
 'A': CDS_PINID='A';
NODE_NAME     R3169 1
 '@T6G_MB_LIB.T6G(SCH_1):PAGE341_I43@PURE_QUANTA.Q_RES(CHIPS)':
 'A': CDS_PINID='A';
NET_NAME
'OCP_V3_2_ISO_BIF1_EN'
 '@T6G_MB_LIB.T6G(SCH_1):OCP_V3_2_ISO_BIF1_EN':
 C_SIGNAL='@t6g_mb_lib.t6g(sch_1):ocp_v3_2_iso_bif1_en';
NODE_NAME     R3216 1
 '@T6G_MB_LIB.T6G(SCH_1):PAGE307_I38@PURE_QUANTA.Q_RES(CHIPS)':
 'A': CDS_PINID='A';
NODE_NAME     R3170 1
 '@T6G_MB_LIB.T6G(SCH_1):PAGE341_I44@PURE_QUANTA.Q_RES(CHIPS)':
 'A': CDS_PINID='A';
NET_NAME
'OCP_V3_2_ISO_BIF2_EN'
 '@T6G_MB_LIB.T6G(SCH_1):OCP_V3_2_ISO_BIF2_EN':
 C_SIGNAL='@t6g_mb_lib.t6g(sch_1):ocp_v3_2_iso_bif2_en';
NODE_NAME     R3217 1
 '@T6G_MB_LIB.T6G(SCH_1):PAGE307_I40@PURE_QUANTA.Q_RES(CHIPS)':
 'A': CDS_PINID='A';
NODE_NAME     R3171 1
 '@T6G_MB_LIB.T6G(SCH_1):PAGE341_I45@PURE_QUANTA.Q_RES(CHIPS)':
 'A': CDS_PINID='A';
NET_NAME
'OCP_V3_2_MAIN_PWR_EN'
 '@T6G_MB_LIB.T6G(SCH_1):OCP_V3_2_MAIN_PWR_EN':
 C_SIGNAL='@t6g_mb_lib.t6g(sch_1):ocp_v3_2_main_pwr_en';
NODE_NAME     R3165 2
 '@T6G_MB_LIB.T6G(SCH_1):PAGE341_I32@PURE_QUANTA.Q_RES(CHIPS)':
 'B': CDS_PINID='B';
NODE_NAME     R3168 1
 '@T6G_MB_LIB.T6G(SCH_1):PAGE341_I86@PURE_QUANTA.Q_RES(CHIPS)':
 'A': CDS_PINID='A';
NODE_NAME     U18 D9
 '@T6G_MB_LIB.T6G(SCH_1):PAGE79_I94@PURE_QUANTA.LCMXO3LF9400C5BG484C(CHIPS)':
 'PT20D': CDS_PINID='PT20D';
NET_NAME
'OCP_V3_2_MAIN_PWR_EN_R'
 '@T6G_MB_LIB.T6G(SCH_1):OCP_V3_2_MAIN_PWR_EN_R':
 C_SIGNAL='@t6g_mb_lib.t6g(sch_1):ocp_v3_2_main_pwr_en_r';
NODE_NAME     J35 OB2
 '@T6G_MB_LIB.T6G(SCH_1):PAGE341_I168@PURE_QUANTA.SCONN168_ME1016810202011(CHIPS)':
 'MAIN_PWR_EN': CDS_PINID='MAIN_PWR_EN';
NODE_NAME     R3168 2
 '@T6G_MB_LIB.T6G(SCH_1):PAGE341_I86@PURE_QUANTA.Q_RES(CHIPS)':
 'B': CDS_PINID='B';
NET_NAME
'OCP_V3_2_NOT_PRSNT_RBT_ARB_IN'
 '@T6G_MB_LIB.T6G(SCH_1):OCP_V3_2_NOT_PRSNT_RBT_ARB_IN':
 C_SIGNAL='@t6g_mb_lib.t6g(sch_1):ocp_v3_2_not_prsnt_rbt_arb_in';
NODE_NAME     U246 1
 '@T6G_MB_LIB.T6G(SCH_1):PAGE258_I17@PURE_QUANTA.NC7SB3157(CHIPS)':
 'B1': CDS_PINID='B1';
NODE_NAME     U245 1
 '@T6G_MB_LIB.T6G(SCH_1):PAGE258_I18@PURE_QUANTA.NC7SB3157(CHIPS)':
 'B1': CDS_PINID='B1';
NET_NAME
'OCP_V3_2_P3V3_ADC_ALERT_R'
 '@T6G_MB_LIB.T6G(SCH_1):OCP_V3_2_P3V3_ADC_ALERT_R':
 C_SIGNAL='@t6g_mb_lib.t6g(sch_1):ocp_v3_2_p3v3_adc_alert_r';
NODE_NAME     U263 3
 '@T6G_MB_LIB.T6G(SCH_1):PAGE360_I94@PURE_QUANTA.ISL28022FRZT(CHIPS)':
 'EXT_CLK||INT': CDS_PINID='\ext_clk||int\';
NODE_NAME     R3559 1
 '@T6G_MB_LIB.T6G(SCH_1):PAGE360_I96@PURE_QUANTA.Q_RES(CHIPS)':
 'A': CDS_PINID='A';
NODE_NAME     R4092 2
 '@T6G_MB_LIB.T6G(SCH_1):PAGE360_I126@PURE_QUANTA.Q_RES(CHIPS)':
 'B': CDS_PINID='B';
NET_NAME
'OCP_V3_2_P3V3_P12V_ADC_ALERT'
 '@T6G_MB_LIB.T6G(SCH_1):OCP_V3_2_P3V3_P12V_ADC_ALERT':
 C_SIGNAL='@t6g_mb_lib.t6g(sch_1):ocp_v3_2_p3v3_p12v_adc_alert';
NODE_NAME     U18 P1
 '@T6G_MB_LIB.T6G(SCH_1):PAGE81_I143@PURE_QUANTA.LCMXO3LF9400C5BG484C(CHIPS)':
 'PL18B': CDS_PINID='PL18B';
NODE_NAME     R1339 2
 '@T6G_MB_LIB.T6G(SCH_1):PAGE81_I180@PURE_QUANTA.Q_RES(CHIPS)':
 'B': CDS_PINID='B';
NET_NAME
'OCP_V3_2_P3V3_P12V_ADC_R_ALERT'
 '@T6G_MB_LIB.T6G(SCH_1):OCP_V3_2_P3V3_P12V_ADC_R_ALERT':
 C_SIGNAL='@t6g_mb_lib.t6g(sch_1):ocp_v3_2_p3v3_p12v_adc_r_alert';
NODE_NAME     R3559 2
 '@T6G_MB_LIB.T6G(SCH_1):PAGE360_I96@PURE_QUANTA.Q_RES(CHIPS)':
 'B': CDS_PINID='B';
NODE_NAME     R1271 2
 '@T6G_MB_LIB.T6G(SCH_1):PAGE466_I33@PURE_QUANTA.Q_RES(CHIPS)':
 'B': CDS_PINID='B';
NODE_NAME     R1339 1
 '@T6G_MB_LIB.T6G(SCH_1):PAGE81_I180@PURE_QUANTA.Q_RES(CHIPS)':
 'A': CDS_PINID='A';
NODE_NAME     R1328 2
 '@T6G_MB_LIB.T6G(SCH_1):PAGE466_I87@PURE_QUANTA.Q_RES(CHIPS)':
 'B': CDS_PINID='B';
NET_NAME
'OCP_V3_2_P3V3_PLD_PWRGD'
 '@T6G_MB_LIB.T6G(SCH_1):OCP_V3_2_P3V3_PLD_PWRGD':
 C_SIGNAL='@t6g_mb_lib.t6g(sch_1):ocp_v3_2_p3v3_pld_pwrgd';
NODE_NAME     U34 4
 '@T6G_MB_LIB.T6G(SCH_1):PAGE257_I45@PURE_QUANTA.SN74LVC1G07DBVR(CHIPS)':
 'Y': CDS_PINID='Y';
NODE_NAME     R1170 1
 '@T6G_MB_LIB.T6G(SCH_1):PAGE257_I58@PURE_QUANTA.Q_RES(CHIPS)':
 'A': CDS_PINID='A';
NET_NAME
'OCP_V3_2_P3V3_PLD_R_PWRGD'
 '@T6G_MB_LIB.T6G(SCH_1):OCP_V3_2_P3V3_PLD_R_PWRGD':
 C_SIGNAL='@t6g_mb_lib.t6g(sch_1):ocp_v3_2_p3v3_pld_r_pwrgd';
NODE_NAME     U18 F15
 '@T6G_MB_LIB.T6G(SCH_1):PAGE79_I94@PURE_QUANTA.LCMXO3LF9400C5BG484C(CHIPS)':
 'PT42C': CDS_PINID='PT42C';
NODE_NAME     R1170 2
 '@T6G_MB_LIB.T6G(SCH_1):PAGE257_I58@PURE_QUANTA.Q_RES(CHIPS)':
 'B': CDS_PINID='B';
NODE_NAME     R1171 2
 '@T6G_MB_LIB.T6G(SCH_1):PAGE257_I60@PURE_QUANTA.Q_RES(CHIPS)':
 'B': CDS_PINID='B';
NET_NAME
'OCP_V3_2_P3V3_PWRGD'
 '@T6G_MB_LIB.T6G(SCH_1):OCP_V3_2_P3V3_PWRGD':
 C_SIGNAL='@t6g_mb_lib.t6g(sch_1):ocp_v3_2_p3v3_pwrgd';
NODE_NAME     R1169 1
 '@T6G_MB_LIB.T6G(SCH_1):PAGE257_I34@PURE_QUANTA.Q_RES(CHIPS)':
 'A': CDS_PINID='A';
NODE_NAME     R8097 2
 '@T6G_MB_LIB.T6G(SCH_1):PAGE257_I73@PURE_QUANTA.Q_RES(CHIPS)':
 'B': CDS_PINID='B';
NODE_NAME     R3832 2
 '@T6G_MB_LIB.T6G(SCH_1):PAGE343_I127@PURE_QUANTA.Q_RES(CHIPS)':
 'B': CDS_PINID='B';
NODE_NAME     R3826 2
 '@T6G_MB_LIB.T6G(SCH_1):PAGE343_I128@PURE_QUANTA.Q_RES(CHIPS)':
 'B': CDS_PINID='B';
NODE_NAME     U9051 1
 '@T6G_MB_LIB.T6G(SCH_1):PAGE257_I78@PURE_QUANTA.74LVC1G08W57(CHIPS)':
 'A': CDS_PINID='A';
NODE_NAME     R1525 1
 '@T6G_MB_LIB.T6G(SCH_1):PAGE257_I88@PURE_QUANTA.Q_RES(CHIPS)':
 'A': CDS_PINID='A';
NET_NAME
'OCP_V3_2_P3V3_R1_PWRGD'
 '@T6G_MB_LIB.T6G(SCH_1):OCP_V3_2_P3V3_R1_PWRGD':
 C_SIGNAL='@t6g_mb_lib.t6g(sch_1):ocp_v3_2_p3v3_r1_pwrgd';
NODE_NAME     U8002 2
 '@T6G_MB_LIB.T6G(SCH_1):PAGE257_I67@PURE_QUANTA.APX80929SAG7(CHIPS)':
 'RESET_L': CDS_PINID='RESET_L';
NODE_NAME     R8096 1
 '@T6G_MB_LIB.T6G(SCH_1):PAGE257_I70@PURE_QUANTA.Q_RES(CHIPS)':
 'A': CDS_PINID='A';
NODE_NAME     R8097 1
 '@T6G_MB_LIB.T6G(SCH_1):PAGE257_I73@PURE_QUANTA.Q_RES(CHIPS)':
 'A': CDS_PINID='A';
NODE_NAME     R8095 2
 '@T6G_MB_LIB.T6G(SCH_1):PAGE257_I77@PURE_QUANTA.Q_RES(CHIPS)':
 'B': CDS_PINID='B';
NET_NAME
'OCP_V3_2_P3V3_R2_PWRGD'
 '@T6G_MB_LIB.T6G(SCH_1):OCP_V3_2_P3V3_R2_PWRGD':
 C_SIGNAL='@t6g_mb_lib.t6g(sch_1):ocp_v3_2_p3v3_r2_pwrgd';
NODE_NAME     R1169 2
 '@T6G_MB_LIB.T6G(SCH_1):PAGE257_I34@PURE_QUANTA.Q_RES(CHIPS)':
 'B': CDS_PINID='B';
NODE_NAME     U34 2
 '@T6G_MB_LIB.T6G(SCH_1):PAGE257_I45@PURE_QUANTA.SN74LVC1G07DBVR(CHIPS)':
 'A': CDS_PINID='A';
NET_NAME
'OCP_V3_2_P3V3_R3_PWRGD'
 '@T6G_MB_LIB.T6G(SCH_1):OCP_V3_2_P3V3_R3_PWRGD':
 C_SIGNAL='@t6g_mb_lib.t6g(sch_1):ocp_v3_2_p3v3_r3_pwrgd';
NODE_NAME     R1178 1
 '@T6G_MB_LIB.T6G(SCH_1):PAGE257_I12@PURE_QUANTA.Q_RES(CHIPS)':
 'A': CDS_PINID='A';
NODE_NAME     R1173 1
 '@T6G_MB_LIB.T6G(SCH_1):PAGE257_I16@PURE_QUANTA.Q_RES(CHIPS)':
 'A': CDS_PINID='A';
NODE_NAME     R1525 2
 '@T6G_MB_LIB.T6G(SCH_1):PAGE257_I88@PURE_QUANTA.Q_RES(CHIPS)':
 'B': CDS_PINID='B';
NODE_NAME     R1524 2
 '@T6G_MB_LIB.T6G(SCH_1):PAGE257_I89@PURE_QUANTA.Q_RES(CHIPS)':
 'B': CDS_PINID='B';
NET_NAME
'OCP_V3_2_PRSNT01_R1_N'
 '@T6G_MB_LIB.T6G(SCH_1):OCP_V3_2_PRSNT01_R1_N':
 C_SIGNAL='@t6g_mb_lib.t6g(sch_1):ocp_v3_2_prsnt01_r1_n';
NODE_NAME     U242 5
 '@T6G_MB_LIB.T6G(SCH_1):PAGE258_I14@PURE_QUANTA.74LVC2G08DP(CHIPS)':
 '2A': CDS_PINID='\2a\';
NODE_NAME     R8015 2
 '@T6G_MB_LIB.T6G(SCH_1):PAGE258_I66@PURE_QUANTA.Q_RES(CHIPS)':
 'B': CDS_PINID='B';
NODE_NAME     C8003 1
 '@T6G_MB_LIB.T6G(SCH_1):PAGE258_I72@PURE_QUANTA.Q_CAP(CHIPS)':
 'A': CDS_PINID='A';
NET_NAME
'OCP_V3_2_PRSNT01_R_N'
 '@T6G_MB_LIB.T6G(SCH_1):OCP_V3_2_PRSNT01_R_N':
 C_SIGNAL='@t6g_mb_lib.t6g(sch_1):ocp_v3_2_prsnt01_r_n';
NODE_NAME     U241 7
 '@T6G_MB_LIB.T6G(SCH_1):PAGE258_I1@PURE_QUANTA.74LVC2G08DP(CHIPS)':
 '1Y': CDS_PINID='\1y\';
NODE_NAME     R8015 1
 '@T6G_MB_LIB.T6G(SCH_1):PAGE258_I66@PURE_QUANTA.Q_RES(CHIPS)':
 'A': CDS_PINID='A';
NET_NAME
'OCP_V3_2_PRSNT0_R_N'
 '@T6G_MB_LIB.T6G(SCH_1):OCP_V3_2_PRSNT0_R_N':
 C_SIGNAL='@t6g_mb_lib.t6g(sch_1):ocp_v3_2_prsnt0_r_n';
NODE_NAME     J35 B42
 '@T6G_MB_LIB.T6G(SCH_1):PAGE341_I168@PURE_QUANTA.SCONN168_ME1016810202011(CHIPS)':
 'PRSNTB0#': CDS_PINID='\prsntb0#\';
NODE_NAME     R3133 2
 '@T6G_MB_LIB.T6G(SCH_1):PAGE343_I14@PURE_QUANTA.Q_RES(CHIPS)':
 'B': CDS_PINID='B';
NODE_NAME     U58 1
 '@T6G_MB_LIB.T6G(SCH_1):PAGE343_I28@PURE_QUANTA.74LVC2G07DW7(CHIPS)':
 '1A': CDS_PINID='\1a\';
NODE_NAME     U241 1
 '@T6G_MB_LIB.T6G(SCH_1):PAGE258_I1@PURE_QUANTA.74LVC2G08DP(CHIPS)':
 '1A': CDS_PINID='\1a\';
NET_NAME
'OCP_V3_2_PRSNT1_R_N'
 '@T6G_MB_LIB.T6G(SCH_1):OCP_V3_2_PRSNT1_R_N':
 C_SIGNAL='@t6g_mb_lib.t6g(sch_1):ocp_v3_2_prsnt1_r_n';
NODE_NAME     J35 A42
 '@T6G_MB_LIB.T6G(SCH_1):PAGE341_I168@PURE_QUANTA.SCONN168_ME1016810202011(CHIPS)':
 'PRSNTB1#': CDS_PINID='\prsntb1#\';
NODE_NAME     R3135 2
 '@T6G_MB_LIB.T6G(SCH_1):PAGE343_I16@PURE_QUANTA.Q_RES(CHIPS)':
 'B': CDS_PINID='B';
NODE_NAME     U58 3
 '@T6G_MB_LIB.T6G(SCH_1):PAGE343_I28@PURE_QUANTA.74LVC2G07DW7(CHIPS)':
 '2A': CDS_PINID='\2a\';
NODE_NAME     U241 2
 '@T6G_MB_LIB.T6G(SCH_1):PAGE258_I1@PURE_QUANTA.74LVC2G08DP(CHIPS)':
 '1B': CDS_PINID='\1b\';
NET_NAME
'OCP_V3_2_PRSNT23_R1_N'
 '@T6G_MB_LIB.T6G(SCH_1):OCP_V3_2_PRSNT23_R1_N':
 C_SIGNAL='@t6g_mb_lib.t6g(sch_1):ocp_v3_2_prsnt23_r1_n';
NODE_NAME     U242 6
 '@T6G_MB_LIB.T6G(SCH_1):PAGE258_I14@PURE_QUANTA.74LVC2G08DP(CHIPS)':
 '2B': CDS_PINID='\2b\';
NODE_NAME     R8016 2
 '@T6G_MB_LIB.T6G(SCH_1):PAGE258_I67@PURE_QUANTA.Q_RES(CHIPS)':
 'B': CDS_PINID='B';
NODE_NAME     C8004 1
 '@T6G_MB_LIB.T6G(SCH_1):PAGE258_I74@PURE_QUANTA.Q_CAP(CHIPS)':
 'A': CDS_PINID='A';
NET_NAME
'OCP_V3_2_PRSNT23_R_N'
 '@T6G_MB_LIB.T6G(SCH_1):OCP_V3_2_PRSNT23_R_N':
 C_SIGNAL='@t6g_mb_lib.t6g(sch_1):ocp_v3_2_prsnt23_r_n';
NODE_NAME     U241 3
 '@T6G_MB_LIB.T6G(SCH_1):PAGE258_I2@PURE_QUANTA.74LVC2G08DP(CHIPS)':
 '2Y': CDS_PINID='\2y\';
NODE_NAME     R8016 1
 '@T6G_MB_LIB.T6G(SCH_1):PAGE258_I67@PURE_QUANTA.Q_RES(CHIPS)':
 'A': CDS_PINID='A';
NET_NAME
'OCP_V3_2_PRSNT2_R_N'
 '@T6G_MB_LIB.T6G(SCH_1):OCP_V3_2_PRSNT2_R_N':
 C_SIGNAL='@t6g_mb_lib.t6g(sch_1):ocp_v3_2_prsnt2_r_n';
NODE_NAME     J35 A12
 '@T6G_MB_LIB.T6G(SCH_1):PAGE341_I168@PURE_QUANTA.SCONN168_ME1016810202011(CHIPS)':
 'PRSNTB2#': CDS_PINID='\prsntb2#\';
NODE_NAME     U241 5
 '@T6G_MB_LIB.T6G(SCH_1):PAGE258_I2@PURE_QUANTA.74LVC2G08DP(CHIPS)':
 '2A': CDS_PINID='\2a\';
NODE_NAME     R3134 2
 '@T6G_MB_LIB.T6G(SCH_1):PAGE343_I4@PURE_QUANTA.Q_RES(CHIPS)':
 'B': CDS_PINID='B';
NODE_NAME     U59 1
 '@T6G_MB_LIB.T6G(SCH_1):PAGE343_I22@PURE_QUANTA.74LVC2G07DW7(CHIPS)':
 '1A': CDS_PINID='\1a\';
NET_NAME
'OCP_V3_2_PRSNT3_R_N'
 '@T6G_MB_LIB.T6G(SCH_1):OCP_V3_2_PRSNT3_R_N':
 C_SIGNAL='@t6g_mb_lib.t6g(sch_1):ocp_v3_2_prsnt3_r_n';
NODE_NAME     J35 B70
 '@T6G_MB_LIB.T6G(SCH_1):PAGE341_I168@PURE_QUANTA.SCONN168_ME1016810202011(CHIPS)':
 'PRSNTB3#': CDS_PINID='\prsntb3#\';
NODE_NAME     R3136 2
 '@T6G_MB_LIB.T6G(SCH_1):PAGE343_I6@PURE_QUANTA.Q_RES(CHIPS)':
 'B': CDS_PINID='B';
NODE_NAME     U241 6
 '@T6G_MB_LIB.T6G(SCH_1):PAGE258_I2@PURE_QUANTA.74LVC2G08DP(CHIPS)':
 '2B': CDS_PINID='\2b\';
NODE_NAME     U59 3
 '@T6G_MB_LIB.T6G(SCH_1):PAGE343_I22@PURE_QUANTA.74LVC2G07DW7(CHIPS)':
 '2A': CDS_PINID='\2a\';
NET_NAME
'OCP_V3_2_PRSNTA_R_N'
 '@T6G_MB_LIB.T6G(SCH_1):OCP_V3_2_PRSNTA_R_N':
 C_SIGNAL='@t6g_mb_lib.t6g(sch_1):ocp_v3_2_prsnta_r_n';
NODE_NAME     J35 A10
 '@T6G_MB_LIB.T6G(SCH_1):PAGE341_I168@PURE_QUANTA.SCONN168_ME1016810202011(CHIPS)':
 'PRSNTA#': CDS_PINID='\prsnta#\';
NODE_NAME     R3180 1
 '@T6G_MB_LIB.T6G(SCH_1):PAGE341_I150@PURE_QUANTA.Q_RES(CHIPS)':
 'A': CDS_PINID='A';
NET_NAME
'OCP_V3_2_PRSNT_ALL_R1_N'
 '@T6G_MB_LIB.T6G(SCH_1):OCP_V3_2_PRSNT_ALL_R1_N':
 C_SIGNAL='@t6g_mb_lib.t6g(sch_1):ocp_v3_2_prsnt_all_r1_n';
NODE_NAME     U246 6
 '@T6G_MB_LIB.T6G(SCH_1):PAGE258_I17@PURE_QUANTA.NC7SB3157(CHIPS)':
 'S': CDS_PINID='S';
NODE_NAME     R3308 2
 '@T6G_MB_LIB.T6G(SCH_1):PAGE258_I46@PURE_QUANTA.Q_RES(CHIPS)':
 'B': CDS_PINID='B';
NET_NAME
'OCP_V3_2_PRSNT_ALL_R3_N'
 '@T6G_MB_LIB.T6G(SCH_1):OCP_V3_2_PRSNT_ALL_R3_N':
 C_SIGNAL='@t6g_mb_lib.t6g(sch_1):ocp_v3_2_prsnt_all_r3_n';
NODE_NAME     U245 6
 '@T6G_MB_LIB.T6G(SCH_1):PAGE258_I18@PURE_QUANTA.NC7SB3157(CHIPS)':
 'S': CDS_PINID='S';
NODE_NAME     R3306 2
 '@T6G_MB_LIB.T6G(SCH_1):PAGE258_I47@PURE_QUANTA.Q_RES(CHIPS)':
 'B': CDS_PINID='B';
NET_NAME
'OCP_V3_2_PRSNT_ALL_R_N'
 '@T6G_MB_LIB.T6G(SCH_1):OCP_V3_2_PRSNT_ALL_R_N':
 C_SIGNAL='@t6g_mb_lib.t6g(sch_1):ocp_v3_2_prsnt_all_r_n';
NODE_NAME     U242 3
 '@T6G_MB_LIB.T6G(SCH_1):PAGE258_I14@PURE_QUANTA.74LVC2G08DP(CHIPS)':
 '2Y': CDS_PINID='\2y\';
NODE_NAME     R3308 1
 '@T6G_MB_LIB.T6G(SCH_1):PAGE258_I46@PURE_QUANTA.Q_RES(CHIPS)':
 'A': CDS_PINID='A';
NODE_NAME     R3306 1
 '@T6G_MB_LIB.T6G(SCH_1):PAGE258_I47@PURE_QUANTA.Q_RES(CHIPS)':
 'A': CDS_PINID='A';
NET_NAME
'OCP_V3_2_PWRBRK_BUFF_N'
 '@T6G_MB_LIB.T6G(SCH_1):OCP_V3_2_PWRBRK_BUFF_N':
 C_SIGNAL='@t6g_mb_lib.t6g(sch_1):ocp_v3_2_pwrbrk_buff_n';
NODE_NAME     R3191 1
 '@T6G_MB_LIB.T6G(SCH_1):PAGE342_I33@PURE_QUANTA.Q_RES(CHIPS)':
 'A': CDS_PINID='A';
NODE_NAME     U218 4
 '@T6G_MB_LIB.T6G(SCH_1):PAGE342_I22@PURE_QUANTA.74LVC1G07GV(CHIPS)':
 'Y': CDS_PINID='Y';
NODE_NAME     R3190 2
 '@T6G_MB_LIB.T6G(SCH_1):PAGE342_I34@PURE_QUANTA.Q_RES(CHIPS)':
 'B': CDS_PINID='B';
NET_NAME
'OCP_V3_2_PWRBRK_N'
 '@T6G_MB_LIB.T6G(SCH_1):OCP_V3_2_PWRBRK_N':
 C_SIGNAL='@t6g_mb_lib.t6g(sch_1):ocp_v3_2_pwrbrk_n';
NODE_NAME     J35 A70
 '@T6G_MB_LIB.T6G(SCH_1):PAGE341_I168@PURE_QUANTA.SCONN168_ME1016810202011(CHIPS)':
 'PWRBRK0#': CDS_PINID='\pwrbrk0#\';
NODE_NAME     R3191 2
 '@T6G_MB_LIB.T6G(SCH_1):PAGE342_I33@PURE_QUANTA.Q_RES(CHIPS)':
 'B': CDS_PINID='B';
NET_NAME
'OCP_V3_2_RBT_ARB_IN'
 '@T6G_MB_LIB.T6G(SCH_1):OCP_V3_2_RBT_ARB_IN':
 C_SIGNAL='@t6g_mb_lib.t6g(sch_1):ocp_v3_2_rbt_arb_in';
NODE_NAME     R3209 2
 '@T6G_MB_LIB.T6G(SCH_1):PAGE307_I64@PURE_QUANTA.Q_RES(CHIPS)':
 'B': CDS_PINID='B';
NODE_NAME     U245 3
 '@T6G_MB_LIB.T6G(SCH_1):PAGE258_I18@PURE_QUANTA.NC7SB3157(CHIPS)':
 'B0': CDS_PINID='B0';
NET_NAME
'OCP_V3_2_RBT_ARB_IN_R'
 '@T6G_MB_LIB.T6G(SCH_1):OCP_V3_2_RBT_ARB_IN_R':
 C_SIGNAL='@t6g_mb_lib.t6g(sch_1):ocp_v3_2_rbt_arb_in_r';
NODE_NAME     U222 12
 '@T6G_MB_LIB.T6G(SCH_1):PAGE307_I32@PURE_QUANTA.74CBTLV3126PW(CHIPS)':
 '4A': CDS_PINID='\4a\';
NODE_NAME     R3209 1
 '@T6G_MB_LIB.T6G(SCH_1):PAGE307_I64@PURE_QUANTA.Q_RES(CHIPS)':
 'A': CDS_PINID='A';
NODE_NAME     R3244 2
 '@T6G_MB_LIB.T6G(SCH_1):PAGE307_I79@PURE_QUANTA.Q_RES(CHIPS)':
 'B': CDS_PINID='B';
NET_NAME
'OCP_V3_2_RBT_ARB_OUT'
 '@T6G_MB_LIB.T6G(SCH_1):OCP_V3_2_RBT_ARB_OUT':
 C_SIGNAL='@t6g_mb_lib.t6g(sch_1):ocp_v3_2_rbt_arb_out';
NODE_NAME     U223 12
 '@T6G_MB_LIB.T6G(SCH_1):PAGE307_I78@PURE_QUANTA.74CBTLV3126PW(CHIPS)':
 '4A': CDS_PINID='\4a\';
NODE_NAME     R3244 1
 '@T6G_MB_LIB.T6G(SCH_1):PAGE307_I79@PURE_QUANTA.Q_RES(CHIPS)':
 'A': CDS_PINID='A';
NODE_NAME     U246 3
 '@T6G_MB_LIB.T6G(SCH_1):PAGE258_I17@PURE_QUANTA.NC7SB3157(CHIPS)':
 'B0': CDS_PINID='B0';
NET_NAME
'OCP_V3_2_WAKE_BUFF_N'
 '@T6G_MB_LIB.T6G(SCH_1):OCP_V3_2_WAKE_BUFF_N':
 C_SIGNAL='@t6g_mb_lib.t6g(sch_1):ocp_v3_2_wake_buff_n';
NODE_NAME     U217 4
 '@T6G_MB_LIB.T6G(SCH_1):PAGE342_I14@PURE_QUANTA.74LVC1G126SE7(CHIPS)':
 'Y': CDS_PINID='Y';
NODE_NAME     R3184 2
 '@T6G_MB_LIB.T6G(SCH_1):PAGE342_I18@PURE_QUANTA.Q_RES(CHIPS)':
 'B': CDS_PINID='B';
NODE_NAME     R3185 1
 '@T6G_MB_LIB.T6G(SCH_1):PAGE342_I29@PURE_QUANTA.Q_RES(CHIPS)':
 'A': CDS_PINID='A';
NET_NAME
'OCP_V3_2_WAKE_BUFF_R_N'
 '@T6G_MB_LIB.T6G(SCH_1):OCP_V3_2_WAKE_BUFF_R_N':
 C_SIGNAL='@t6g_mb_lib.t6g(sch_1):ocp_v3_2_wake_buff_r_n';
NODE_NAME     R3185 2
 '@T6G_MB_LIB.T6G(SCH_1):PAGE342_I29@PURE_QUANTA.Q_RES(CHIPS)':
 'B': CDS_PINID='B';
NODE_NAME     U219 2
 '@T6G_MB_LIB.T6G(SCH_1):PAGE342_I32@PURE_QUANTA.74LVC1G07GV(CHIPS)':
 'A': CDS_PINID='A';
NET_NAME
'OC_ALERT_N'
 '@T6G_MB_LIB.T6G(SCH_1):OC_ALERT_N':
 C_SIGNAL='@t6g_mb_lib.t6g(sch_1):oc_alert_n';
NODE_NAME     R6039 1
 '@T6G_MB_LIB.T6G(SCH_1):PAGE79_I20@PURE_QUANTA.Q_RES(CHIPS)':
 'A': CDS_PINID='A';
NODE_NAME     U18 A10
 '@T6G_MB_LIB.T6G(SCH_1):PAGE79_I94@PURE_QUANTA.LCMXO3LF9400C5BG484C(CHIPS)':
 'PT23B||PCLKC0_1': CDS_PINID='\pt23b||pclkc0_1\';
NET_NAME
'OC_P2V5_COMP'
 '@T6G_MB_LIB.T6G(SCH_1):OC_P2V5_COMP':
 C_SIGNAL='@t6g_mb_lib.t6g(sch_1):oc_p2v5_comp';
NODE_NAME     R8107 2
 '@T6G_MB_LIB.T6G(SCH_1):PAGE371_I81@PURE_QUANTA.Q_RES(CHIPS)':
 'B': CDS_PINID='B';
NODE_NAME     C8014 1
 '@T6G_MB_LIB.T6G(SCH_1):PAGE371_I87@PURE_QUANTA.Q_CAP(CHIPS)':
 'A': CDS_PINID='A';
NODE_NAME     U8005 1
 '@T6G_MB_LIB.T6G(SCH_1):PAGE371_I101@PURE_QUANTA.LM4040AIM3X25NOPB(CHIPS)':
 '1+': CDS_PINID='\1+\';
NODE_NAME     U8006 1
 '@T6G_MB_LIB.T6G(SCH_1):PAGE371_I104@PURE_QUANTA.AP331AWG7(CHIPS)':
 'IN-': CDS_PINID='\in-\';
NET_NAME
'P0V9_CPU0_RT0_2A'
 '@T6G_MB_LIB.T6G(SCH_1):P0V9_CPU0_RT0_2A':
 C_SIGNAL='@t6g_mb_lib.t6g(sch_1):p0v9_cpu0_rt0_2a',
 CDS_GLOBAL_NET='TRUE';
NODE_NAME     U6010 AC17
 '@T6G_MB_LIB.T6G(SCH_1):PAGE386_I3@PURE_QUANTA.PT5161LRS(CHIPS)':
 'PWR_2A_1': CDS_PINID='PWR_2A_1';
NODE_NAME     U6010 AC20
 '@T6G_MB_LIB.T6G(SCH_1):PAGE386_I3@PURE_QUANTA.PT5161LRS(CHIPS)':
 'PWR_2A_2': CDS_PINID='PWR_2A_2';
NODE_NAME     U6010 AK17
 '@T6G_MB_LIB.T6G(SCH_1):PAGE386_I3@PURE_QUANTA.PT5161LRS(CHIPS)':
 'PWR_2A_3': CDS_PINID='PWR_2A_3';
NODE_NAME     U6010 AK20
 '@T6G_MB_LIB.T6G(SCH_1):PAGE386_I3@PURE_QUANTA.PT5161LRS(CHIPS)':
 'PWR_2A_4': CDS_PINID='PWR_2A_4';
NODE_NAME     U6010 AU17
 '@T6G_MB_LIB.T6G(SCH_1):PAGE386_I3@PURE_QUANTA.PT5161LRS(CHIPS)':
 'PWR_2A_5': CDS_PINID='PWR_2A_5';
NODE_NAME     U6010 AU20
 '@T6G_MB_LIB.T6G(SCH_1):PAGE386_I3@PURE_QUANTA.PT5161LRS(CHIPS)':
 'PWR_2A_6': CDS_PINID='PWR_2A_6';
NODE_NAME     U6010 DN17
 '@T6G_MB_LIB.T6G(SCH_1):PAGE386_I3@PURE_QUANTA.PT5161LRS(CHIPS)':
 'PWR_2A_11': CDS_PINID='PWR_2A_11';
NODE_NAME     U6010 DN20
 '@T6G_MB_LIB.T6G(SCH_1):PAGE386_I3@PURE_QUANTA.PT5161LRS(CHIPS)':
 'PWR_2A_12': CDS_PINID='PWR_2A_12';
NODE_NAME     U6010 DY17
 '@T6G_MB_LIB.T6G(SCH_1):PAGE386_I3@PURE_QUANTA.PT5161LRS(CHIPS)':
 'PWR_2A_13': CDS_PINID='PWR_2A_13';
NODE_NAME     U6010 DY20
 '@T6G_MB_LIB.T6G(SCH_1):PAGE386_I3@PURE_QUANTA.PT5161LRS(CHIPS)':
 'PWR_2A_14': CDS_PINID='PWR_2A_14';
NODE_NAME     U6010 EG17
 '@T6G_MB_LIB.T6G(SCH_1):PAGE386_I3@PURE_QUANTA.PT5161LRS(CHIPS)':
 'PWR_2A_15': CDS_PINID='PWR_2A_15';
NODE_NAME     U6010 EG20
 '@T6G_MB_LIB.T6G(SCH_1):PAGE386_I3@PURE_QUANTA.PT5161LRS(CHIPS)':
 'PWR_2A_16': CDS_PINID='PWR_2A_16';
NODE_NAME     U6010 EP17
 '@T6G_MB_LIB.T6G(SCH_1):PAGE386_I3@PURE_QUANTA.PT5161LRS(CHIPS)':
 'PWR_2A_17': CDS_PINID='PWR_2A_17';
NODE_NAME     U6010 EP20
 '@T6G_MB_LIB.T6G(SCH_1):PAGE386_I3@PURE_QUANTA.PT5161LRS(CHIPS)':
 'PWR_2A_18': CDS_PINID='PWR_2A_18';
NODE_NAME     U6010 T17
 '@T6G_MB_LIB.T6G(SCH_1):PAGE386_I3@PURE_QUANTA.PT5161LRS(CHIPS)':
 'PWR_2A_19': CDS_PINID='PWR_2A_19';
NODE_NAME     U6010 T20
 '@T6G_MB_LIB.T6G(SCH_1):PAGE386_I3@PURE_QUANTA.PT5161LRS(CHIPS)':
 'PWR_2A_20': CDS_PINID='PWR_2A_20';
NODE_NAME     R962 2
 '@T6G_MB_LIB.T6G(SCH_1):PAGE388_I11@PURE_QUANTA.Q_RES(CHIPS)':
 'B': CDS_PINID='B';
NODE_NAME     L12 2
 '@T6G_MB_LIB.T6G(SCH_1):PAGE388_I30@PURE_QUANTA.Q_INDUCTOR(CHIPS)':
 '2': CDS_PINID='\2\';
NODE_NAME     C576 1
 '@T6G_MB_LIB.T6G(SCH_1):PAGE388_I38@PURE_QUANTA.Q_CAP(CHIPS)':
 'A': CDS_PINID='A';
NODE_NAME     C580 1
 '@T6G_MB_LIB.T6G(SCH_1):PAGE388_I39@PURE_QUANTA.Q_CAP(CHIPS)':
 'A': CDS_PINID='A';
NODE_NAME     C555 1
 '@T6G_MB_LIB.T6G(SCH_1):PAGE388_I40@PURE_QUANTA.Q_CAP(CHIPS)':
 'A': CDS_PINID='A';
NODE_NAME     C561 1
 '@T6G_MB_LIB.T6G(SCH_1):PAGE388_I41@PURE_QUANTA.Q_CAP(CHIPS)':
 'A': CDS_PINID='A';
NODE_NAME     C539 1
 '@T6G_MB_LIB.T6G(SCH_1):PAGE388_I42@PURE_QUANTA.Q_CAP(CHIPS)':
 'A': CDS_PINID='A';
NODE_NAME     C562 1
 '@T6G_MB_LIB.T6G(SCH_1):PAGE388_I43@PURE_QUANTA.Q_CAP(CHIPS)':
 'A': CDS_PINID='A';
NODE_NAME     C579 1
 '@T6G_MB_LIB.T6G(SCH_1):PAGE388_I44@PURE_QUANTA.Q_CAP(CHIPS)':
 'A': CDS_PINID='A';
NODE_NAME     C554 1
 '@T6G_MB_LIB.T6G(SCH_1):PAGE388_I45@PURE_QUANTA.Q_CAP(CHIPS)':
 'A': CDS_PINID='A';
NODE_NAME     C571 1
 '@T6G_MB_LIB.T6G(SCH_1):PAGE388_I46@PURE_QUANTA.Q_CAP(CHIPS)':
 'A': CDS_PINID='A';
NODE_NAME     C541 1
 '@T6G_MB_LIB.T6G(SCH_1):PAGE388_I48@PURE_QUANTA.Q_CAP(CHIPS)':
 'A': CDS_PINID='A';
NODE_NAME     C582 1
 '@T6G_MB_LIB.T6G(SCH_1):PAGE388_I49@PURE_QUANTA.Q_CAP(CHIPS)':
 'A': CDS_PINID='A';
NODE_NAME     C523 1
 '@T6G_MB_LIB.T6G(SCH_1):PAGE388_I50@PURE_QUANTA.Q_CAP(CHIPS)':
 'A': CDS_PINID='A';
NODE_NAME     C585 1
 '@T6G_MB_LIB.T6G(SCH_1):PAGE388_I51@PURE_QUANTA.Q_CAP(CHIPS)':
 'A': CDS_PINID='A';
NODE_NAME     C570 1
 '@T6G_MB_LIB.T6G(SCH_1):PAGE388_I52@PURE_QUANTA.Q_CAP(CHIPS)':
 'A': CDS_PINID='A';
NODE_NAME     C573 1
 '@T6G_MB_LIB.T6G(SCH_1):PAGE388_I53@PURE_QUANTA.Q_CAP(CHIPS)':
 'A': CDS_PINID='A';
NODE_NAME     C557 1
 '@T6G_MB_LIB.T6G(SCH_1):PAGE388_I54@PURE_QUANTA.Q_CAP(CHIPS)':
 'A': CDS_PINID='A';
NODE_NAME     C572 1
 '@T6G_MB_LIB.T6G(SCH_1):PAGE388_I55@PURE_QUANTA.Q_CAP(CHIPS)':
 'A': CDS_PINID='A';
NODE_NAME     C577 1
 '@T6G_MB_LIB.T6G(SCH_1):PAGE388_I56@PURE_QUANTA.Q_CAP(CHIPS)':
 'A': CDS_PINID='A';
NODE_NAME     C581 1
 '@T6G_MB_LIB.T6G(SCH_1):PAGE388_I57@PURE_QUANTA.Q_CAP(CHIPS)':
 'A': CDS_PINID='A';
NODE_NAME     C525 1
 '@T6G_MB_LIB.T6G(SCH_1):PAGE388_I58@PURE_QUANTA.Q_CAP(CHIPS)':
 'A': CDS_PINID='A';
NODE_NAME     C529 1
 '@T6G_MB_LIB.T6G(SCH_1):PAGE388_I59@PURE_QUANTA.Q_CAP(CHIPS)':
 'A': CDS_PINID='A';
NODE_NAME     C558 1
 '@T6G_MB_LIB.T6G(SCH_1):PAGE388_I60@PURE_QUANTA.Q_CAP(CHIPS)':
 'A': CDS_PINID='A';
NODE_NAME     C543 1
 '@T6G_MB_LIB.T6G(SCH_1):PAGE388_I62@PURE_QUANTA.Q_CAP(CHIPS)':
 'A': CDS_PINID='A';
NODE_NAME     C521 1
 '@T6G_MB_LIB.T6G(SCH_1):PAGE388_I65@PURE_QUANTA.Q_CAP(CHIPS)':
 'A': CDS_PINID='A';
NODE_NAME     C526 1
 '@T6G_MB_LIB.T6G(SCH_1):PAGE388_I66@PURE_QUANTA.Q_CAP(CHIPS)':
 'A': CDS_PINID='A';
NODE_NAME     C550 1
 '@T6G_MB_LIB.T6G(SCH_1):PAGE388_I67@PURE_QUANTA.Q_CAP(CHIPS)':
 'A': CDS_PINID='A';
NODE_NAME     C556 1
 '@T6G_MB_LIB.T6G(SCH_1):PAGE388_I69@PURE_QUANTA.Q_CAP(CHIPS)':
 'A': CDS_PINID='A';
NODE_NAME     C560 1
 '@T6G_MB_LIB.T6G(SCH_1):PAGE388_I70@PURE_QUANTA.Q_CAP(CHIPS)':
 'A': CDS_PINID='A';
NODE_NAME     C564 1
 '@T6G_MB_LIB.T6G(SCH_1):PAGE388_I71@PURE_QUANTA.Q_CAP(CHIPS)':
 'A': CDS_PINID='A';
NODE_NAME     C586 1
 '@T6G_MB_LIB.T6G(SCH_1):PAGE388_I75@PURE_QUANTA.Q_CAP(CHIPS)':
 'A': CDS_PINID='A';
NODE_NAME     C565 1
 '@T6G_MB_LIB.T6G(SCH_1):PAGE388_I76@PURE_QUANTA.Q_CAP(CHIPS)':
 'A': CDS_PINID='A';
NODE_NAME     C575 1
 '@T6G_MB_LIB.T6G(SCH_1):PAGE388_I77@PURE_QUANTA.Q_CAP(CHIPS)':
 'A': CDS_PINID='A';
NODE_NAME     C568 1
 '@T6G_MB_LIB.T6G(SCH_1):PAGE388_I78@PURE_QUANTA.Q_CAP(CHIPS)':
 'A': CDS_PINID='A';
NODE_NAME     C584 1
 '@T6G_MB_LIB.T6G(SCH_1):PAGE388_I82@PURE_QUANTA.Q_CAP(CHIPS)':
 'A': CDS_PINID='A';
NODE_NAME     C567 1
 '@T6G_MB_LIB.T6G(SCH_1):PAGE388_I83@PURE_QUANTA.Q_CAP(CHIPS)':
 'A': CDS_PINID='A';
NODE_NAME     C583 1
 '@T6G_MB_LIB.T6G(SCH_1):PAGE388_I93@PURE_QUANTA.Q_CAP(CHIPS)':
 'A': CDS_PINID='A';
NODE_NAME     C566 1
 '@T6G_MB_LIB.T6G(SCH_1):PAGE388_I94@PURE_QUANTA.Q_CAP(CHIPS)':
 'A': CDS_PINID='A';
NODE_NAME     C7008 1
 '@T6G_MB_LIB.T6G(SCH_1):PAGE388_I99@PURE_QUANTA.Q_CAPP(CHIPS)':
 'A': CDS_PINID='A';
NODE_NAME     C7009 1
 '@T6G_MB_LIB.T6G(SCH_1):PAGE388_I100@PURE_QUANTA.Q_CAPP(CHIPS)':
 'A': CDS_PINID='A';
NODE_NAME     C7010 1
 '@T6G_MB_LIB.T6G(SCH_1):PAGE388_I101@PURE_QUANTA.Q_CAP(CHIPS)':
 'A': CDS_PINID='A';
NET_NAME
'P0V9_CPU0_RT0_2A_2D'
 '@T6G_MB_LIB.T6G(SCH_1):P0V9_CPU0_RT0_2A_2D':
 C_SIGNAL='@t6g_mb_lib.t6g(sch_1):p0v9_cpu0_rt0_2a_2d',
 CDS_GLOBAL_NET='TRUE';
NODE_NAME     U6010 BD17
 '@T6G_MB_LIB.T6G(SCH_1):PAGE386_I3@PURE_QUANTA.PT5161LRS(CHIPS)':
 'PWR_2A_7': CDS_PINID='PWR_2A_7';
NODE_NAME     U6010 BD20
 '@T6G_MB_LIB.T6G(SCH_1):PAGE386_I3@PURE_QUANTA.PT5161LRS(CHIPS)':
 'PWR_2A_8': CDS_PINID='PWR_2A_8';
NODE_NAME     U6010 DF17
 '@T6G_MB_LIB.T6G(SCH_1):PAGE386_I3@PURE_QUANTA.PT5161LRS(CHIPS)':
 'PWR_2A_9': CDS_PINID='PWR_2A_9';
NODE_NAME     U6010 DF20
 '@T6G_MB_LIB.T6G(SCH_1):PAGE386_I3@PURE_QUANTA.PT5161LRS(CHIPS)':
 'PWR_2A_10': CDS_PINID='PWR_2A_10';
NODE_NAME     R961 2
 '@T6G_MB_LIB.T6G(SCH_1):PAGE388_I10@PURE_QUANTA.Q_RES(CHIPS)':
 'B': CDS_PINID='B';
NODE_NAME     R962 1
 '@T6G_MB_LIB.T6G(SCH_1):PAGE388_I11@PURE_QUANTA.Q_RES(CHIPS)':
 'A': CDS_PINID='A';
NODE_NAME     C538 1
 '@T6G_MB_LIB.T6G(SCH_1):PAGE388_I32@PURE_QUANTA.Q_CAP(CHIPS)':
 'A': CDS_PINID='A';
NODE_NAME     C544 1
 '@T6G_MB_LIB.T6G(SCH_1):PAGE388_I36@PURE_QUANTA.Q_CAP(CHIPS)':
 'A': CDS_PINID='A';
NODE_NAME     C542 1
 '@T6G_MB_LIB.T6G(SCH_1):PAGE388_I90@PURE_QUANTA.Q_CAP(CHIPS)':
 'A': CDS_PINID='A';
NODE_NAME     C545 1
 '@T6G_MB_LIB.T6G(SCH_1):PAGE388_I91@PURE_QUANTA.Q_CAP(CHIPS)':
 'A': CDS_PINID='A';
NET_NAME
'P0V9_CPU0_RT1_2A'
 '@T6G_MB_LIB.T6G(SCH_1):P0V9_CPU0_RT1_2A':
 C_SIGNAL='@t6g_mb_lib.t6g(sch_1):p0v9_cpu0_rt1_2a',
 CDS_GLOBAL_NET='TRUE';
NODE_NAME     U6011 AC17
 '@T6G_MB_LIB.T6G(SCH_1):PAGE409_I5@PURE_QUANTA.PT5161LRS(CHIPS)':
 'PWR_2A_1': CDS_PINID='PWR_2A_1';
NODE_NAME     U6011 AC20
 '@T6G_MB_LIB.T6G(SCH_1):PAGE409_I5@PURE_QUANTA.PT5161LRS(CHIPS)':
 'PWR_2A_2': CDS_PINID='PWR_2A_2';
NODE_NAME     U6011 AK17
 '@T6G_MB_LIB.T6G(SCH_1):PAGE409_I5@PURE_QUANTA.PT5161LRS(CHIPS)':
 'PWR_2A_3': CDS_PINID='PWR_2A_3';
NODE_NAME     U6011 AK20
 '@T6G_MB_LIB.T6G(SCH_1):PAGE409_I5@PURE_QUANTA.PT5161LRS(CHIPS)':
 'PWR_2A_4': CDS_PINID='PWR_2A_4';
NODE_NAME     U6011 AU17
 '@T6G_MB_LIB.T6G(SCH_1):PAGE409_I5@PURE_QUANTA.PT5161LRS(CHIPS)':
 'PWR_2A_5': CDS_PINID='PWR_2A_5';
NODE_NAME     U6011 AU20
 '@T6G_MB_LIB.T6G(SCH_1):PAGE409_I5@PURE_QUANTA.PT5161LRS(CHIPS)':
 'PWR_2A_6': CDS_PINID='PWR_2A_6';
NODE_NAME     U6011 DN17
 '@T6G_MB_LIB.T6G(SCH_1):PAGE409_I5@PURE_QUANTA.PT5161LRS(CHIPS)':
 'PWR_2A_11': CDS_PINID='PWR_2A_11';
NODE_NAME     U6011 DN20
 '@T6G_MB_LIB.T6G(SCH_1):PAGE409_I5@PURE_QUANTA.PT5161LRS(CHIPS)':
 'PWR_2A_12': CDS_PINID='PWR_2A_12';
NODE_NAME     U6011 DY17
 '@T6G_MB_LIB.T6G(SCH_1):PAGE409_I5@PURE_QUANTA.PT5161LRS(CHIPS)':
 'PWR_2A_13': CDS_PINID='PWR_2A_13';
NODE_NAME     U6011 DY20
 '@T6G_MB_LIB.T6G(SCH_1):PAGE409_I5@PURE_QUANTA.PT5161LRS(CHIPS)':
 'PWR_2A_14': CDS_PINID='PWR_2A_14';
NODE_NAME     U6011 EG17
 '@T6G_MB_LIB.T6G(SCH_1):PAGE409_I5@PURE_QUANTA.PT5161LRS(CHIPS)':
 'PWR_2A_15': CDS_PINID='PWR_2A_15';
NODE_NAME     U6011 EG20
 '@T6G_MB_LIB.T6G(SCH_1):PAGE409_I5@PURE_QUANTA.PT5161LRS(CHIPS)':
 'PWR_2A_16': CDS_PINID='PWR_2A_16';
NODE_NAME     U6011 EP17
 '@T6G_MB_LIB.T6G(SCH_1):PAGE409_I5@PURE_QUANTA.PT5161LRS(CHIPS)':
 'PWR_2A_17': CDS_PINID='PWR_2A_17';
NODE_NAME     U6011 EP20
 '@T6G_MB_LIB.T6G(SCH_1):PAGE409_I5@PURE_QUANTA.PT5161LRS(CHIPS)':
 'PWR_2A_18': CDS_PINID='PWR_2A_18';
NODE_NAME     U6011 T17
 '@T6G_MB_LIB.T6G(SCH_1):PAGE409_I5@PURE_QUANTA.PT5161LRS(CHIPS)':
 'PWR_2A_19': CDS_PINID='PWR_2A_19';
NODE_NAME     U6011 T20
 '@T6G_MB_LIB.T6G(SCH_1):PAGE409_I5@PURE_QUANTA.PT5161LRS(CHIPS)':
 'PWR_2A_20': CDS_PINID='PWR_2A_20';
NODE_NAME     R1011 2
 '@T6G_MB_LIB.T6G(SCH_1):PAGE411_I36@PURE_QUANTA.Q_RES(CHIPS)':
 'B': CDS_PINID='B';
NODE_NAME     C662 1
 '@T6G_MB_LIB.T6G(SCH_1):PAGE411_I37@PURE_QUANTA.Q_CAP(CHIPS)':
 'A': CDS_PINID='A';
NODE_NAME     C609 1
 '@T6G_MB_LIB.T6G(SCH_1):PAGE411_I38@PURE_QUANTA.Q_CAP(CHIPS)':
 'A': CDS_PINID='A';
NODE_NAME     C618 1
 '@T6G_MB_LIB.T6G(SCH_1):PAGE411_I39@PURE_QUANTA.Q_CAP(CHIPS)':
 'A': CDS_PINID='A';
NODE_NAME     C626 1
 '@T6G_MB_LIB.T6G(SCH_1):PAGE411_I40@PURE_QUANTA.Q_CAP(CHIPS)':
 'A': CDS_PINID='A';
NODE_NAME     C645 1
 '@T6G_MB_LIB.T6G(SCH_1):PAGE411_I41@PURE_QUANTA.Q_CAP(CHIPS)':
 'A': CDS_PINID='A';
NODE_NAME     C616 1
 '@T6G_MB_LIB.T6G(SCH_1):PAGE411_I42@PURE_QUANTA.Q_CAP(CHIPS)':
 'A': CDS_PINID='A';
NODE_NAME     C657 1
 '@T6G_MB_LIB.T6G(SCH_1):PAGE411_I43@PURE_QUANTA.Q_CAP(CHIPS)':
 'A': CDS_PINID='A';
NODE_NAME     C607 1
 '@T6G_MB_LIB.T6G(SCH_1):PAGE411_I44@PURE_QUANTA.Q_CAP(CHIPS)':
 'A': CDS_PINID='A';
NODE_NAME     C643 1
 '@T6G_MB_LIB.T6G(SCH_1):PAGE411_I45@PURE_QUANTA.Q_CAP(CHIPS)':
 'A': CDS_PINID='A';
NODE_NAME     C635 1
 '@T6G_MB_LIB.T6G(SCH_1):PAGE411_I46@PURE_QUANTA.Q_CAP(CHIPS)':
 'A': CDS_PINID='A';
NODE_NAME     C627 1
 '@T6G_MB_LIB.T6G(SCH_1):PAGE411_I47@PURE_QUANTA.Q_CAP(CHIPS)':
 'A': CDS_PINID='A';
NODE_NAME     C647 1
 '@T6G_MB_LIB.T6G(SCH_1):PAGE411_I48@PURE_QUANTA.Q_CAP(CHIPS)':
 'A': CDS_PINID='A';
NODE_NAME     C654 1
 '@T6G_MB_LIB.T6G(SCH_1):PAGE411_I49@PURE_QUANTA.Q_CAP(CHIPS)':
 'A': CDS_PINID='A';
NODE_NAME     C644 1
 '@T6G_MB_LIB.T6G(SCH_1):PAGE411_I50@PURE_QUANTA.Q_CAP(CHIPS)':
 'A': CDS_PINID='A';
NODE_NAME     C638 1
 '@T6G_MB_LIB.T6G(SCH_1):PAGE411_I51@PURE_QUANTA.Q_CAP(CHIPS)':
 'A': CDS_PINID='A';
NODE_NAME     C649 1
 '@T6G_MB_LIB.T6G(SCH_1):PAGE411_I52@PURE_QUANTA.Q_CAP(CHIPS)':
 'A': CDS_PINID='A';
NODE_NAME     C653 1
 '@T6G_MB_LIB.T6G(SCH_1):PAGE411_I53@PURE_QUANTA.Q_CAP(CHIPS)':
 'A': CDS_PINID='A';
NODE_NAME     C631 1
 '@T6G_MB_LIB.T6G(SCH_1):PAGE411_I55@PURE_QUANTA.Q_CAP(CHIPS)':
 'A': CDS_PINID='A';
NODE_NAME     C650 1
 '@T6G_MB_LIB.T6G(SCH_1):PAGE411_I58@PURE_QUANTA.Q_CAP(CHIPS)':
 'A': CDS_PINID='A';
NODE_NAME     C620 1
 '@T6G_MB_LIB.T6G(SCH_1):PAGE411_I59@PURE_QUANTA.Q_CAP(CHIPS)':
 'A': CDS_PINID='A';
NODE_NAME     C613 1
 '@T6G_MB_LIB.T6G(SCH_1):PAGE411_I61@PURE_QUANTA.Q_CAP(CHIPS)':
 'A': CDS_PINID='A';
NODE_NAME     L14 2
 '@T6G_MB_LIB.T6G(SCH_1):PAGE411_I63@PURE_QUANTA.Q_INDUCTOR(CHIPS)':
 '2': CDS_PINID='\2\';
NODE_NAME     C625 1
 '@T6G_MB_LIB.T6G(SCH_1):PAGE411_I64@PURE_QUANTA.Q_CAP(CHIPS)':
 'A': CDS_PINID='A';
NODE_NAME     C628 1
 '@T6G_MB_LIB.T6G(SCH_1):PAGE411_I65@PURE_QUANTA.Q_CAP(CHIPS)':
 'A': CDS_PINID='A';
NODE_NAME     C633 1
 '@T6G_MB_LIB.T6G(SCH_1):PAGE411_I69@PURE_QUANTA.Q_CAP(CHIPS)':
 'A': CDS_PINID='A';
NODE_NAME     C637 1
 '@T6G_MB_LIB.T6G(SCH_1):PAGE411_I70@PURE_QUANTA.Q_CAP(CHIPS)':
 'A': CDS_PINID='A';
NODE_NAME     C634 1
 '@T6G_MB_LIB.T6G(SCH_1):PAGE411_I71@PURE_QUANTA.Q_CAP(CHIPS)':
 'A': CDS_PINID='A';
NODE_NAME     C663 1
 '@T6G_MB_LIB.T6G(SCH_1):PAGE411_I72@PURE_QUANTA.Q_CAP(CHIPS)':
 'A': CDS_PINID='A';
NODE_NAME     C630 1
 '@T6G_MB_LIB.T6G(SCH_1):PAGE411_I73@PURE_QUANTA.Q_CAP(CHIPS)':
 'A': CDS_PINID='A';
NODE_NAME     C656 1
 '@T6G_MB_LIB.T6G(SCH_1):PAGE411_I77@PURE_QUANTA.Q_CAP(CHIPS)':
 'A': CDS_PINID='A';
NODE_NAME     C661 1
 '@T6G_MB_LIB.T6G(SCH_1):PAGE411_I78@PURE_QUANTA.Q_CAP(CHIPS)':
 'A': CDS_PINID='A';
NODE_NAME     C648 1
 '@T6G_MB_LIB.T6G(SCH_1):PAGE411_I79@PURE_QUANTA.Q_CAP(CHIPS)':
 'A': CDS_PINID='A';
NODE_NAME     C614 1
 '@T6G_MB_LIB.T6G(SCH_1):PAGE411_I85@PURE_QUANTA.Q_CAP(CHIPS)':
 'A': CDS_PINID='A';
NODE_NAME     C622 1
 '@T6G_MB_LIB.T6G(SCH_1):PAGE411_I86@PURE_QUANTA.Q_CAP(CHIPS)':
 'A': CDS_PINID='A';
NODE_NAME     C652 1
 '@T6G_MB_LIB.T6G(SCH_1):PAGE411_I87@PURE_QUANTA.Q_CAP(CHIPS)':
 'A': CDS_PINID='A';
NODE_NAME     C658 1
 '@T6G_MB_LIB.T6G(SCH_1):PAGE411_I92@PURE_QUANTA.Q_CAP(CHIPS)':
 'A': CDS_PINID='A';
NODE_NAME     C659 1
 '@T6G_MB_LIB.T6G(SCH_1):PAGE411_I93@PURE_QUANTA.Q_CAP(CHIPS)':
 'A': CDS_PINID='A';
NODE_NAME     C660 1
 '@T6G_MB_LIB.T6G(SCH_1):PAGE411_I94@PURE_QUANTA.Q_CAP(CHIPS)':
 'A': CDS_PINID='A';
NODE_NAME     C7011 1
 '@T6G_MB_LIB.T6G(SCH_1):PAGE411_I95@PURE_QUANTA.Q_CAPP(CHIPS)':
 'A': CDS_PINID='A';
NODE_NAME     C7012 1
 '@T6G_MB_LIB.T6G(SCH_1):PAGE411_I96@PURE_QUANTA.Q_CAPP(CHIPS)':
 'A': CDS_PINID='A';
NODE_NAME     C7013 1
 '@T6G_MB_LIB.T6G(SCH_1):PAGE411_I97@PURE_QUANTA.Q_CAP(CHIPS)':
 'A': CDS_PINID='A';
NET_NAME
'P0V9_CPU0_RT1_2A_2D'
 '@T6G_MB_LIB.T6G(SCH_1):P0V9_CPU0_RT1_2A_2D':
 C_SIGNAL='@t6g_mb_lib.t6g(sch_1):p0v9_cpu0_rt1_2a_2d',
 CDS_GLOBAL_NET='TRUE';
NODE_NAME     U6011 BD17
 '@T6G_MB_LIB.T6G(SCH_1):PAGE409_I5@PURE_QUANTA.PT5161LRS(CHIPS)':
 'PWR_2A_7': CDS_PINID='PWR_2A_7';
NODE_NAME     U6011 BD20
 '@T6G_MB_LIB.T6G(SCH_1):PAGE409_I5@PURE_QUANTA.PT5161LRS(CHIPS)':
 'PWR_2A_8': CDS_PINID='PWR_2A_8';
NODE_NAME     U6011 DF17
 '@T6G_MB_LIB.T6G(SCH_1):PAGE409_I5@PURE_QUANTA.PT5161LRS(CHIPS)':
 'PWR_2A_9': CDS_PINID='PWR_2A_9';
NODE_NAME     U6011 DF20
 '@T6G_MB_LIB.T6G(SCH_1):PAGE409_I5@PURE_QUANTA.PT5161LRS(CHIPS)':
 'PWR_2A_10': CDS_PINID='PWR_2A_10';
NODE_NAME     R1010 2
 '@T6G_MB_LIB.T6G(SCH_1):PAGE411_I10@PURE_QUANTA.Q_RES(CHIPS)':
 'B': CDS_PINID='B';
NODE_NAME     C617 1
 '@T6G_MB_LIB.T6G(SCH_1):PAGE411_I32@PURE_QUANTA.Q_CAP(CHIPS)':
 'A': CDS_PINID='A';
NODE_NAME     C623 1
 '@T6G_MB_LIB.T6G(SCH_1):PAGE411_I34@PURE_QUANTA.Q_CAP(CHIPS)':
 'A': CDS_PINID='A';
NODE_NAME     R1011 1
 '@T6G_MB_LIB.T6G(SCH_1):PAGE411_I36@PURE_QUANTA.Q_RES(CHIPS)':
 'A': CDS_PINID='A';
NODE_NAME     C621 1
 '@T6G_MB_LIB.T6G(SCH_1):PAGE411_I90@PURE_QUANTA.Q_CAP(CHIPS)':
 'A': CDS_PINID='A';
NODE_NAME     C624 1
 '@T6G_MB_LIB.T6G(SCH_1):PAGE411_I91@PURE_QUANTA.Q_CAP(CHIPS)':
 'A': CDS_PINID='A';
NET_NAME
'P0V9_CPU0_RT2_2A'
 '@T6G_MB_LIB.T6G(SCH_1):P0V9_CPU0_RT2_2A':
 C_SIGNAL='@t6g_mb_lib.t6g(sch_1):p0v9_cpu0_rt2_2a',
 CDS_GLOBAL_NET='TRUE';
NODE_NAME     U6012 AC17
 '@T6G_MB_LIB.T6G(SCH_1):PAGE420_I6@PURE_QUANTA.PT5161LRS(CHIPS)':
 'PWR_2A_1': CDS_PINID='PWR_2A_1';
NODE_NAME     U6012 AC20
 '@T6G_MB_LIB.T6G(SCH_1):PAGE420_I6@PURE_QUANTA.PT5161LRS(CHIPS)':
 'PWR_2A_2': CDS_PINID='PWR_2A_2';
NODE_NAME     U6012 AK17
 '@T6G_MB_LIB.T6G(SCH_1):PAGE420_I6@PURE_QUANTA.PT5161LRS(CHIPS)':
 'PWR_2A_3': CDS_PINID='PWR_2A_3';
NODE_NAME     U6012 AK20
 '@T6G_MB_LIB.T6G(SCH_1):PAGE420_I6@PURE_QUANTA.PT5161LRS(CHIPS)':
 'PWR_2A_4': CDS_PINID='PWR_2A_4';
NODE_NAME     U6012 AU17
 '@T6G_MB_LIB.T6G(SCH_1):PAGE420_I6@PURE_QUANTA.PT5161LRS(CHIPS)':
 'PWR_2A_5': CDS_PINID='PWR_2A_5';
NODE_NAME     U6012 AU20
 '@T6G_MB_LIB.T6G(SCH_1):PAGE420_I6@PURE_QUANTA.PT5161LRS(CHIPS)':
 'PWR_2A_6': CDS_PINID='PWR_2A_6';
NODE_NAME     U6012 DN17
 '@T6G_MB_LIB.T6G(SCH_1):PAGE420_I6@PURE_QUANTA.PT5161LRS(CHIPS)':
 'PWR_2A_11': CDS_PINID='PWR_2A_11';
NODE_NAME     U6012 DN20
 '@T6G_MB_LIB.T6G(SCH_1):PAGE420_I6@PURE_QUANTA.PT5161LRS(CHIPS)':
 'PWR_2A_12': CDS_PINID='PWR_2A_12';
NODE_NAME     U6012 DY17
 '@T6G_MB_LIB.T6G(SCH_1):PAGE420_I6@PURE_QUANTA.PT5161LRS(CHIPS)':
 'PWR_2A_13': CDS_PINID='PWR_2A_13';
NODE_NAME     U6012 DY20
 '@T6G_MB_LIB.T6G(SCH_1):PAGE420_I6@PURE_QUANTA.PT5161LRS(CHIPS)':
 'PWR_2A_14': CDS_PINID='PWR_2A_14';
NODE_NAME     U6012 EG17
 '@T6G_MB_LIB.T6G(SCH_1):PAGE420_I6@PURE_QUANTA.PT5161LRS(CHIPS)':
 'PWR_2A_15': CDS_PINID='PWR_2A_15';
NODE_NAME     U6012 EG20
 '@T6G_MB_LIB.T6G(SCH_1):PAGE420_I6@PURE_QUANTA.PT5161LRS(CHIPS)':
 'PWR_2A_16': CDS_PINID='PWR_2A_16';
NODE_NAME     U6012 EP17
 '@T6G_MB_LIB.T6G(SCH_1):PAGE420_I6@PURE_QUANTA.PT5161LRS(CHIPS)':
 'PWR_2A_17': CDS_PINID='PWR_2A_17';
NODE_NAME     U6012 EP20
 '@T6G_MB_LIB.T6G(SCH_1):PAGE420_I6@PURE_QUANTA.PT5161LRS(CHIPS)':
 'PWR_2A_18': CDS_PINID='PWR_2A_18';
NODE_NAME     U6012 T17
 '@T6G_MB_LIB.T6G(SCH_1):PAGE420_I6@PURE_QUANTA.PT5161LRS(CHIPS)':
 'PWR_2A_19': CDS_PINID='PWR_2A_19';
NODE_NAME     U6012 T20
 '@T6G_MB_LIB.T6G(SCH_1):PAGE420_I6@PURE_QUANTA.PT5161LRS(CHIPS)':
 'PWR_2A_20': CDS_PINID='PWR_2A_20';
NODE_NAME     R1053 2
 '@T6G_MB_LIB.T6G(SCH_1):PAGE422_I22@PURE_QUANTA.Q_RES(CHIPS)':
 'B': CDS_PINID='B';
NODE_NAME     L21 2
 '@T6G_MB_LIB.T6G(SCH_1):PAGE422_I30@PURE_QUANTA.Q_INDUCTOR(CHIPS)':
 '2': CDS_PINID='\2\';
NODE_NAME     C982 1
 '@T6G_MB_LIB.T6G(SCH_1):PAGE422_I34@PURE_QUANTA.Q_CAP(CHIPS)':
 'A': CDS_PINID='A';
NODE_NAME     C984 1
 '@T6G_MB_LIB.T6G(SCH_1):PAGE422_I35@PURE_QUANTA.Q_CAP(CHIPS)':
 'A': CDS_PINID='A';
NODE_NAME     C790 1
 '@T6G_MB_LIB.T6G(SCH_1):PAGE422_I40@PURE_QUANTA.Q_CAP(CHIPS)':
 'A': CDS_PINID='A';
NODE_NAME     C987 1
 '@T6G_MB_LIB.T6G(SCH_1):PAGE422_I41@PURE_QUANTA.Q_CAP(CHIPS)':
 'A': CDS_PINID='A';
NODE_NAME     C800 1
 '@T6G_MB_LIB.T6G(SCH_1):PAGE422_I42@PURE_QUANTA.Q_CAP(CHIPS)':
 'A': CDS_PINID='A';
NODE_NAME     C784 1
 '@T6G_MB_LIB.T6G(SCH_1):PAGE422_I43@PURE_QUANTA.Q_CAP(CHIPS)':
 'A': CDS_PINID='A';
NODE_NAME     C797 1
 '@T6G_MB_LIB.T6G(SCH_1):PAGE422_I44@PURE_QUANTA.Q_CAP(CHIPS)':
 'A': CDS_PINID='A';
NODE_NAME     C781 1
 '@T6G_MB_LIB.T6G(SCH_1):PAGE422_I45@PURE_QUANTA.Q_CAP(CHIPS)':
 'A': CDS_PINID='A';
NODE_NAME     C788 1
 '@T6G_MB_LIB.T6G(SCH_1):PAGE422_I46@PURE_QUANTA.Q_CAP(CHIPS)':
 'A': CDS_PINID='A';
NODE_NAME     C796 1
 '@T6G_MB_LIB.T6G(SCH_1):PAGE422_I47@PURE_QUANTA.Q_CAP(CHIPS)':
 'A': CDS_PINID='A';
NODE_NAME     C795 1
 '@T6G_MB_LIB.T6G(SCH_1):PAGE422_I48@PURE_QUANTA.Q_CAP(CHIPS)':
 'A': CDS_PINID='A';
NODE_NAME     C981 1
 '@T6G_MB_LIB.T6G(SCH_1):PAGE422_I49@PURE_QUANTA.Q_CAP(CHIPS)':
 'A': CDS_PINID='A';
NODE_NAME     C798 1
 '@T6G_MB_LIB.T6G(SCH_1):PAGE422_I50@PURE_QUANTA.Q_CAP(CHIPS)':
 'A': CDS_PINID='A';
NODE_NAME     C802 1
 '@T6G_MB_LIB.T6G(SCH_1):PAGE422_I51@PURE_QUANTA.Q_CAP(CHIPS)':
 'A': CDS_PINID='A';
NODE_NAME     C792 1
 '@T6G_MB_LIB.T6G(SCH_1):PAGE422_I52@PURE_QUANTA.Q_CAP(CHIPS)':
 'A': CDS_PINID='A';
NODE_NAME     C975 1
 '@T6G_MB_LIB.T6G(SCH_1):PAGE422_I54@PURE_QUANTA.Q_CAP(CHIPS)':
 'A': CDS_PINID='A';
NODE_NAME     C979 1
 '@T6G_MB_LIB.T6G(SCH_1):PAGE422_I55@PURE_QUANTA.Q_CAP(CHIPS)':
 'A': CDS_PINID='A';
NODE_NAME     C967 1
 '@T6G_MB_LIB.T6G(SCH_1):PAGE422_I56@PURE_QUANTA.Q_CAP(CHIPS)':
 'A': CDS_PINID='A';
NODE_NAME     C970 1
 '@T6G_MB_LIB.T6G(SCH_1):PAGE422_I57@PURE_QUANTA.Q_CAP(CHIPS)':
 'A': CDS_PINID='A';
NODE_NAME     C966 1
 '@T6G_MB_LIB.T6G(SCH_1):PAGE422_I58@PURE_QUANTA.Q_CAP(CHIPS)':
 'A': CDS_PINID='A';
NODE_NAME     C969 1
 '@T6G_MB_LIB.T6G(SCH_1):PAGE422_I59@PURE_QUANTA.Q_CAP(CHIPS)':
 'A': CDS_PINID='A';
NODE_NAME     C977 1
 '@T6G_MB_LIB.T6G(SCH_1):PAGE422_I60@PURE_QUANTA.Q_CAP(CHIPS)':
 'A': CDS_PINID='A';
NODE_NAME     C978 1
 '@T6G_MB_LIB.T6G(SCH_1):PAGE422_I61@PURE_QUANTA.Q_CAP(CHIPS)':
 'A': CDS_PINID='A';
NODE_NAME     C783 1
 '@T6G_MB_LIB.T6G(SCH_1):PAGE422_I62@PURE_QUANTA.Q_CAP(CHIPS)':
 'A': CDS_PINID='A';
NODE_NAME     C988 1
 '@T6G_MB_LIB.T6G(SCH_1):PAGE422_I63@PURE_QUANTA.Q_CAP(CHIPS)':
 'A': CDS_PINID='A';
NODE_NAME     C974 1
 '@T6G_MB_LIB.T6G(SCH_1):PAGE422_I64@PURE_QUANTA.Q_CAP(CHIPS)':
 'A': CDS_PINID='A';
NODE_NAME     C799 1
 '@T6G_MB_LIB.T6G(SCH_1):PAGE422_I65@PURE_QUANTA.Q_CAP(CHIPS)':
 'A': CDS_PINID='A';
NODE_NAME     C983 1
 '@T6G_MB_LIB.T6G(SCH_1):PAGE422_I66@PURE_QUANTA.Q_CAP(CHIPS)':
 'A': CDS_PINID='A';
NODE_NAME     C804 1
 '@T6G_MB_LIB.T6G(SCH_1):PAGE422_I68@PURE_QUANTA.Q_CAP(CHIPS)':
 'A': CDS_PINID='A';
NODE_NAME     C968 1
 '@T6G_MB_LIB.T6G(SCH_1):PAGE422_I69@PURE_QUANTA.Q_CAP(CHIPS)':
 'A': CDS_PINID='A';
NODE_NAME     C786 1
 '@T6G_MB_LIB.T6G(SCH_1):PAGE422_I72@PURE_QUANTA.Q_CAP(CHIPS)':
 'A': CDS_PINID='A';
NODE_NAME     C779 1
 '@T6G_MB_LIB.T6G(SCH_1):PAGE422_I73@PURE_QUANTA.Q_CAP(CHIPS)':
 'A': CDS_PINID='A';
NODE_NAME     C986 1
 '@T6G_MB_LIB.T6G(SCH_1):PAGE422_I74@PURE_QUANTA.Q_CAP(CHIPS)':
 'A': CDS_PINID='A';
NODE_NAME     C973 1
 '@T6G_MB_LIB.T6G(SCH_1):PAGE422_I75@PURE_QUANTA.Q_CAP(CHIPS)':
 'A': CDS_PINID='A';
NODE_NAME     C803 1
 '@T6G_MB_LIB.T6G(SCH_1):PAGE422_I87@PURE_QUANTA.Q_CAP(CHIPS)':
 'A': CDS_PINID='A';
NODE_NAME     C972 1
 '@T6G_MB_LIB.T6G(SCH_1):PAGE422_I92@PURE_QUANTA.Q_CAP(CHIPS)':
 'A': CDS_PINID='A';
NODE_NAME     C985 1
 '@T6G_MB_LIB.T6G(SCH_1):PAGE422_I93@PURE_QUANTA.Q_CAP(CHIPS)':
 'A': CDS_PINID='A';
NODE_NAME     C7014 1
 '@T6G_MB_LIB.T6G(SCH_1):PAGE422_I94@PURE_QUANTA.Q_CAPP(CHIPS)':
 'A': CDS_PINID='A';
NODE_NAME     C7015 1
 '@T6G_MB_LIB.T6G(SCH_1):PAGE422_I95@PURE_QUANTA.Q_CAPP(CHIPS)':
 'A': CDS_PINID='A';
NODE_NAME     C7016 1
 '@T6G_MB_LIB.T6G(SCH_1):PAGE422_I96@PURE_QUANTA.Q_CAP(CHIPS)':
 'A': CDS_PINID='A';
NET_NAME
'P0V9_CPU0_RT2_2A_2D'
 '@T6G_MB_LIB.T6G(SCH_1):P0V9_CPU0_RT2_2A_2D':
 C_SIGNAL='@t6g_mb_lib.t6g(sch_1):p0v9_cpu0_rt2_2a_2d',
 CDS_GLOBAL_NET='TRUE';
NODE_NAME     U6012 BD17
 '@T6G_MB_LIB.T6G(SCH_1):PAGE420_I6@PURE_QUANTA.PT5161LRS(CHIPS)':
 'PWR_2A_7': CDS_PINID='PWR_2A_7';
NODE_NAME     U6012 BD20
 '@T6G_MB_LIB.T6G(SCH_1):PAGE420_I6@PURE_QUANTA.PT5161LRS(CHIPS)':
 'PWR_2A_8': CDS_PINID='PWR_2A_8';
NODE_NAME     U6012 DF17
 '@T6G_MB_LIB.T6G(SCH_1):PAGE420_I6@PURE_QUANTA.PT5161LRS(CHIPS)':
 'PWR_2A_9': CDS_PINID='PWR_2A_9';
NODE_NAME     U6012 DF20
 '@T6G_MB_LIB.T6G(SCH_1):PAGE420_I6@PURE_QUANTA.PT5161LRS(CHIPS)':
 'PWR_2A_10': CDS_PINID='PWR_2A_10';
NODE_NAME     R1051 2
 '@T6G_MB_LIB.T6G(SCH_1):PAGE422_I21@PURE_QUANTA.Q_RES(CHIPS)':
 'B': CDS_PINID='B';
NODE_NAME     R1053 1
 '@T6G_MB_LIB.T6G(SCH_1):PAGE422_I22@PURE_QUANTA.Q_RES(CHIPS)':
 'A': CDS_PINID='A';
NODE_NAME     C791 1
 '@T6G_MB_LIB.T6G(SCH_1):PAGE422_I36@PURE_QUANTA.Q_CAP(CHIPS)':
 'A': CDS_PINID='A';
NODE_NAME     C794 1
 '@T6G_MB_LIB.T6G(SCH_1):PAGE422_I39@PURE_QUANTA.Q_CAP(CHIPS)':
 'A': CDS_PINID='A';
NODE_NAME     C787 1
 '@T6G_MB_LIB.T6G(SCH_1):PAGE422_I90@PURE_QUANTA.Q_CAP(CHIPS)':
 'A': CDS_PINID='A';
NODE_NAME     C793 1
 '@T6G_MB_LIB.T6G(SCH_1):PAGE422_I91@PURE_QUANTA.Q_CAP(CHIPS)':
 'A': CDS_PINID='A';
NET_NAME
'P0V9_CPU0_RT3_2A'
 '@T6G_MB_LIB.T6G(SCH_1):P0V9_CPU0_RT3_2A':
 C_SIGNAL='@t6g_mb_lib.t6g(sch_1):p0v9_cpu0_rt3_2a',
 CDS_GLOBAL_NET='TRUE';
NODE_NAME     U6013 AC17
 '@T6G_MB_LIB.T6G(SCH_1):PAGE431_I6@PURE_QUANTA.PT5161LRS(CHIPS)':
 'PWR_2A_1': CDS_PINID='PWR_2A_1';
NODE_NAME     U6013 AC20
 '@T6G_MB_LIB.T6G(SCH_1):PAGE431_I6@PURE_QUANTA.PT5161LRS(CHIPS)':
 'PWR_2A_2': CDS_PINID='PWR_2A_2';
NODE_NAME     U6013 AK17
 '@T6G_MB_LIB.T6G(SCH_1):PAGE431_I6@PURE_QUANTA.PT5161LRS(CHIPS)':
 'PWR_2A_3': CDS_PINID='PWR_2A_3';
NODE_NAME     U6013 AK20
 '@T6G_MB_LIB.T6G(SCH_1):PAGE431_I6@PURE_QUANTA.PT5161LRS(CHIPS)':
 'PWR_2A_4': CDS_PINID='PWR_2A_4';
NODE_NAME     U6013 AU17
 '@T6G_MB_LIB.T6G(SCH_1):PAGE431_I6@PURE_QUANTA.PT5161LRS(CHIPS)':
 'PWR_2A_5': CDS_PINID='PWR_2A_5';
NODE_NAME     U6013 AU20
 '@T6G_MB_LIB.T6G(SCH_1):PAGE431_I6@PURE_QUANTA.PT5161LRS(CHIPS)':
 'PWR_2A_6': CDS_PINID='PWR_2A_6';
NODE_NAME     U6013 DN17
 '@T6G_MB_LIB.T6G(SCH_1):PAGE431_I6@PURE_QUANTA.PT5161LRS(CHIPS)':
 'PWR_2A_11': CDS_PINID='PWR_2A_11';
NODE_NAME     U6013 DN20
 '@T6G_MB_LIB.T6G(SCH_1):PAGE431_I6@PURE_QUANTA.PT5161LRS(CHIPS)':
 'PWR_2A_12': CDS_PINID='PWR_2A_12';
NODE_NAME     U6013 DY17
 '@T6G_MB_LIB.T6G(SCH_1):PAGE431_I6@PURE_QUANTA.PT5161LRS(CHIPS)':
 'PWR_2A_13': CDS_PINID='PWR_2A_13';
NODE_NAME     U6013 DY20
 '@T6G_MB_LIB.T6G(SCH_1):PAGE431_I6@PURE_QUANTA.PT5161LRS(CHIPS)':
 'PWR_2A_14': CDS_PINID='PWR_2A_14';
NODE_NAME     U6013 EG17
 '@T6G_MB_LIB.T6G(SCH_1):PAGE431_I6@PURE_QUANTA.PT5161LRS(CHIPS)':
 'PWR_2A_15': CDS_PINID='PWR_2A_15';
NODE_NAME     U6013 EG20
 '@T6G_MB_LIB.T6G(SCH_1):PAGE431_I6@PURE_QUANTA.PT5161LRS(CHIPS)':
 'PWR_2A_16': CDS_PINID='PWR_2A_16';
NODE_NAME     U6013 EP17
 '@T6G_MB_LIB.T6G(SCH_1):PAGE431_I6@PURE_QUANTA.PT5161LRS(CHIPS)':
 'PWR_2A_17': CDS_PINID='PWR_2A_17';
NODE_NAME     U6013 EP20
 '@T6G_MB_LIB.T6G(SCH_1):PAGE431_I6@PURE_QUANTA.PT5161LRS(CHIPS)':
 'PWR_2A_18': CDS_PINID='PWR_2A_18';
NODE_NAME     U6013 T17
 '@T6G_MB_LIB.T6G(SCH_1):PAGE431_I6@PURE_QUANTA.PT5161LRS(CHIPS)':
 'PWR_2A_19': CDS_PINID='PWR_2A_19';
NODE_NAME     U6013 T20
 '@T6G_MB_LIB.T6G(SCH_1):PAGE431_I6@PURE_QUANTA.PT5161LRS(CHIPS)':
 'PWR_2A_20': CDS_PINID='PWR_2A_20';
NODE_NAME     R1095 2
 '@T6G_MB_LIB.T6G(SCH_1):PAGE433_I36@PURE_QUANTA.Q_RES(CHIPS)':
 'B': CDS_PINID='B';
NODE_NAME     C1024 1
 '@T6G_MB_LIB.T6G(SCH_1):PAGE433_I37@PURE_QUANTA.Q_CAP(CHIPS)':
 'A': CDS_PINID='A';
NODE_NAME     C1027 1
 '@T6G_MB_LIB.T6G(SCH_1):PAGE433_I38@PURE_QUANTA.Q_CAP(CHIPS)':
 'A': CDS_PINID='A';
NODE_NAME     C1023 1
 '@T6G_MB_LIB.T6G(SCH_1):PAGE433_I39@PURE_QUANTA.Q_CAP(CHIPS)':
 'A': CDS_PINID='A';
NODE_NAME     C1036 1
 '@T6G_MB_LIB.T6G(SCH_1):PAGE433_I40@PURE_QUANTA.Q_CAP(CHIPS)':
 'A': CDS_PINID='A';
NODE_NAME     C1010 1
 '@T6G_MB_LIB.T6G(SCH_1):PAGE433_I41@PURE_QUANTA.Q_CAP(CHIPS)':
 'A': CDS_PINID='A';
NODE_NAME     C1052 1
 '@T6G_MB_LIB.T6G(SCH_1):PAGE433_I42@PURE_QUANTA.Q_CAP(CHIPS)':
 'A': CDS_PINID='A';
NODE_NAME     C1055 1
 '@T6G_MB_LIB.T6G(SCH_1):PAGE433_I43@PURE_QUANTA.Q_CAP(CHIPS)':
 'A': CDS_PINID='A';
NODE_NAME     C1035 1
 '@T6G_MB_LIB.T6G(SCH_1):PAGE433_I44@PURE_QUANTA.Q_CAP(CHIPS)':
 'A': CDS_PINID='A';
NODE_NAME     C1031 1
 '@T6G_MB_LIB.T6G(SCH_1):PAGE433_I45@PURE_QUANTA.Q_CAP(CHIPS)':
 'A': CDS_PINID='A';
NODE_NAME     C1006 1
 '@T6G_MB_LIB.T6G(SCH_1):PAGE433_I46@PURE_QUANTA.Q_CAP(CHIPS)':
 'A': CDS_PINID='A';
NODE_NAME     C1034 1
 '@T6G_MB_LIB.T6G(SCH_1):PAGE433_I47@PURE_QUANTA.Q_CAP(CHIPS)':
 'A': CDS_PINID='A';
NODE_NAME     C1039 1
 '@T6G_MB_LIB.T6G(SCH_1):PAGE433_I48@PURE_QUANTA.Q_CAP(CHIPS)':
 'A': CDS_PINID='A';
NODE_NAME     C1015 1
 '@T6G_MB_LIB.T6G(SCH_1):PAGE433_I49@PURE_QUANTA.Q_CAP(CHIPS)':
 'A': CDS_PINID='A';
NODE_NAME     C1054 1
 '@T6G_MB_LIB.T6G(SCH_1):PAGE433_I50@PURE_QUANTA.Q_CAP(CHIPS)':
 'A': CDS_PINID='A';
NODE_NAME     C1056 1
 '@T6G_MB_LIB.T6G(SCH_1):PAGE433_I51@PURE_QUANTA.Q_CAP(CHIPS)':
 'A': CDS_PINID='A';
NODE_NAME     C1008 1
 '@T6G_MB_LIB.T6G(SCH_1):PAGE433_I52@PURE_QUANTA.Q_CAP(CHIPS)':
 'A': CDS_PINID='A';
NODE_NAME     C1011 1
 '@T6G_MB_LIB.T6G(SCH_1):PAGE433_I53@PURE_QUANTA.Q_CAP(CHIPS)':
 'A': CDS_PINID='A';
NODE_NAME     C1043 1
 '@T6G_MB_LIB.T6G(SCH_1):PAGE433_I54@PURE_QUANTA.Q_CAP(CHIPS)':
 'A': CDS_PINID='A';
NODE_NAME     C1047 1
 '@T6G_MB_LIB.T6G(SCH_1):PAGE433_I56@PURE_QUANTA.Q_CAP(CHIPS)':
 'A': CDS_PINID='A';
NODE_NAME     C1019 1
 '@T6G_MB_LIB.T6G(SCH_1):PAGE433_I57@PURE_QUANTA.Q_CAP(CHIPS)':
 'A': CDS_PINID='A';
NODE_NAME     C1046 1
 '@T6G_MB_LIB.T6G(SCH_1):PAGE433_I59@PURE_QUANTA.Q_CAP(CHIPS)':
 'A': CDS_PINID='A';
NODE_NAME     C1050 1
 '@T6G_MB_LIB.T6G(SCH_1):PAGE433_I60@PURE_QUANTA.Q_CAP(CHIPS)':
 'A': CDS_PINID='A';
NODE_NAME     C1013 1
 '@T6G_MB_LIB.T6G(SCH_1):PAGE433_I62@PURE_QUANTA.Q_CAP(CHIPS)':
 'A': CDS_PINID='A';
NODE_NAME     C1017 1
 '@T6G_MB_LIB.T6G(SCH_1):PAGE433_I63@PURE_QUANTA.Q_CAP(CHIPS)':
 'A': CDS_PINID='A';
NODE_NAME     L23 2
 '@T6G_MB_LIB.T6G(SCH_1):PAGE433_I65@PURE_QUANTA.Q_INDUCTOR(CHIPS)':
 '2': CDS_PINID='\2\';
NODE_NAME     C1022 1
 '@T6G_MB_LIB.T6G(SCH_1):PAGE433_I66@PURE_QUANTA.Q_CAP(CHIPS)':
 'A': CDS_PINID='A';
NODE_NAME     C1025 1
 '@T6G_MB_LIB.T6G(SCH_1):PAGE433_I67@PURE_QUANTA.Q_CAP(CHIPS)':
 'A': CDS_PINID='A';
NODE_NAME     C1029 1
 '@T6G_MB_LIB.T6G(SCH_1):PAGE433_I70@PURE_QUANTA.Q_CAP(CHIPS)':
 'A': CDS_PINID='A';
NODE_NAME     C1033 1
 '@T6G_MB_LIB.T6G(SCH_1):PAGE433_I71@PURE_QUANTA.Q_CAP(CHIPS)':
 'A': CDS_PINID='A';
NODE_NAME     C1026 1
 '@T6G_MB_LIB.T6G(SCH_1):PAGE433_I72@PURE_QUANTA.Q_CAP(CHIPS)':
 'A': CDS_PINID='A';
NODE_NAME     C1030 1
 '@T6G_MB_LIB.T6G(SCH_1):PAGE433_I77@PURE_QUANTA.Q_CAP(CHIPS)':
 'A': CDS_PINID='A';
NODE_NAME     C1041 1
 '@T6G_MB_LIB.T6G(SCH_1):PAGE433_I78@PURE_QUANTA.Q_CAP(CHIPS)':
 'A': CDS_PINID='A';
NODE_NAME     C1037 1
 '@T6G_MB_LIB.T6G(SCH_1):PAGE433_I79@PURE_QUANTA.Q_CAP(CHIPS)':
 'A': CDS_PINID='A';
NODE_NAME     C1049 1
 '@T6G_MB_LIB.T6G(SCH_1):PAGE433_I80@PURE_QUANTA.Q_CAP(CHIPS)':
 'A': CDS_PINID='A';
NODE_NAME     C1040 1
 '@T6G_MB_LIB.T6G(SCH_1):PAGE433_I86@PURE_QUANTA.Q_CAP(CHIPS)':
 'A': CDS_PINID='A';
NODE_NAME     C1045 1
 '@T6G_MB_LIB.T6G(SCH_1):PAGE433_I87@PURE_QUANTA.Q_CAP(CHIPS)':
 'A': CDS_PINID='A';
NODE_NAME     C1051 1
 '@T6G_MB_LIB.T6G(SCH_1):PAGE433_I92@PURE_QUANTA.Q_CAP(CHIPS)':
 'A': CDS_PINID='A';
NODE_NAME     C1053 1
 '@T6G_MB_LIB.T6G(SCH_1):PAGE433_I93@PURE_QUANTA.Q_CAP(CHIPS)':
 'A': CDS_PINID='A';
NODE_NAME     C7017 1
 '@T6G_MB_LIB.T6G(SCH_1):PAGE433_I94@PURE_QUANTA.Q_CAPP(CHIPS)':
 'A': CDS_PINID='A';
NODE_NAME     C7018 1
 '@T6G_MB_LIB.T6G(SCH_1):PAGE433_I95@PURE_QUANTA.Q_CAPP(CHIPS)':
 'A': CDS_PINID='A';
NODE_NAME     C7019 1
 '@T6G_MB_LIB.T6G(SCH_1):PAGE433_I96@PURE_QUANTA.Q_CAP(CHIPS)':
 'A': CDS_PINID='A';
NET_NAME
'P0V9_CPU0_RT3_2A_2D'
 '@T6G_MB_LIB.T6G(SCH_1):P0V9_CPU0_RT3_2A_2D':
 C_SIGNAL='@t6g_mb_lib.t6g(sch_1):p0v9_cpu0_rt3_2a_2d',
 CDS_GLOBAL_NET='TRUE';
NODE_NAME     U6013 BD17
 '@T6G_MB_LIB.T6G(SCH_1):PAGE431_I6@PURE_QUANTA.PT5161LRS(CHIPS)':
 'PWR_2A_7': CDS_PINID='PWR_2A_7';
NODE_NAME     U6013 BD20
 '@T6G_MB_LIB.T6G(SCH_1):PAGE431_I6@PURE_QUANTA.PT5161LRS(CHIPS)':
 'PWR_2A_8': CDS_PINID='PWR_2A_8';
NODE_NAME     U6013 DF17
 '@T6G_MB_LIB.T6G(SCH_1):PAGE431_I6@PURE_QUANTA.PT5161LRS(CHIPS)':
 'PWR_2A_9': CDS_PINID='PWR_2A_9';
NODE_NAME     U6013 DF20
 '@T6G_MB_LIB.T6G(SCH_1):PAGE431_I6@PURE_QUANTA.PT5161LRS(CHIPS)':
 'PWR_2A_10': CDS_PINID='PWR_2A_10';
NODE_NAME     R1094 2
 '@T6G_MB_LIB.T6G(SCH_1):PAGE433_I7@PURE_QUANTA.Q_RES(CHIPS)':
 'B': CDS_PINID='B';
NODE_NAME     C1014 1
 '@T6G_MB_LIB.T6G(SCH_1):PAGE433_I30@PURE_QUANTA.Q_CAP(CHIPS)':
 'A': CDS_PINID='A';
NODE_NAME     C1021 1
 '@T6G_MB_LIB.T6G(SCH_1):PAGE433_I35@PURE_QUANTA.Q_CAP(CHIPS)':
 'A': CDS_PINID='A';
NODE_NAME     R1095 1
 '@T6G_MB_LIB.T6G(SCH_1):PAGE433_I36@PURE_QUANTA.Q_RES(CHIPS)':
 'A': CDS_PINID='A';
NODE_NAME     C1018 1
 '@T6G_MB_LIB.T6G(SCH_1):PAGE433_I90@PURE_QUANTA.Q_CAP(CHIPS)':
 'A': CDS_PINID='A';
NODE_NAME     C1020 1
 '@T6G_MB_LIB.T6G(SCH_1):PAGE433_I91@PURE_QUANTA.Q_CAP(CHIPS)':
 'A': CDS_PINID='A';
NET_NAME
'P0V9_CPU0_RT_2D'
 '@T6G_MB_LIB.T6G(SCH_1):P0V9_CPU0_RT_2D':
 C_SIGNAL='@t6g_mb_lib.t6g(sch_1):p0v9_cpu0_rt_2d',
 CDS_GLOBAL_NET='TRUE';
NODE_NAME     PR6530 2
 '@T6G_MB_LIB.T6G(SCH_1):PAGE475_I34@PURE_QUANTA.Q_RES(CHIPS)':
 'B': CDS_PINID='B';
NODE_NAME     PC6565 1
 '@T6G_MB_LIB.T6G(SCH_1):PAGE476_I33@PURE_QUANTA.Q_CAP(CHIPS)':
 'A': CDS_PINID='A';
NODE_NAME     PL6505 2
 '@T6G_MB_LIB.T6G(SCH_1):PAGE476_I34@PURE_QUANTA.Q_INDUCTOR(CHIPS)':
 '2': CDS_PINID='\2\';
NODE_NAME     PR6556 2
 '@T6G_MB_LIB.T6G(SCH_1):PAGE476_I42@PURE_QUANTA.Q_RES(CHIPS)':
 'B': CDS_PINID='B';
NODE_NAME     PR6557 1
 '@T6G_MB_LIB.T6G(SCH_1):PAGE476_I187@PURE_QUANTA.Q_RES(CHIPS)':
 'A': CDS_PINID='A';
NODE_NAME     PC6566_1 1
 '@T6G_MB_LIB.T6G(SCH_1):PAGE476_I202@PURE_QUANTA.Q_CAP(CHIPS)':
 'A': CDS_PINID='A';
NODE_NAME     PC6572 1
 '@T6G_MB_LIB.T6G(SCH_1):PAGE476_I222@PURE_QUANTA.Q_CAPP(CHIPS)':
 'A': CDS_PINID='A';
NODE_NAME     PC6567_1 1
 '@T6G_MB_LIB.T6G(SCH_1):PAGE476_I223@PURE_QUANTA.Q_CAP(CHIPS)':
 'A': CDS_PINID='A';
NODE_NAME     PC6568 1
 '@T6G_MB_LIB.T6G(SCH_1):PAGE476_I224@PURE_QUANTA.Q_CAPP(CHIPS)':
 'A': CDS_PINID='A';
NODE_NAME     PC6569 1
 '@T6G_MB_LIB.T6G(SCH_1):PAGE476_I225@PURE_QUANTA.Q_CAPP(CHIPS)':
 'A': CDS_PINID='A';
NODE_NAME     PC6570 1
 '@T6G_MB_LIB.T6G(SCH_1):PAGE476_I226@PURE_QUANTA.Q_CAPP(CHIPS)':
 'A': CDS_PINID='A';
NODE_NAME     PC6571 1
 '@T6G_MB_LIB.T6G(SCH_1):PAGE476_I227@PURE_QUANTA.Q_CAPP(CHIPS)':
 'A': CDS_PINID='A';
NODE_NAME     PC6574 1
 '@T6G_MB_LIB.T6G(SCH_1):PAGE476_I236@PURE_QUANTA.Q_CAPP(CHIPS)':
 'A': CDS_PINID='A';
NODE_NAME     PC6573 1
 '@T6G_MB_LIB.T6G(SCH_1):PAGE476_I238@PURE_QUANTA.Q_CAPP(CHIPS)':
 'A': CDS_PINID='A';
NODE_NAME     PC534 1
 '@T6G_MB_LIB.T6G(SCH_1):PAGE476_I239@PURE_QUANTA.Q_CAPP(CHIPS)':
 'A': CDS_PINID='A';
NODE_NAME     PC6811 1
 '@T6G_MB_LIB.T6G(SCH_1):PAGE476_I247@PURE_QUANTA.Q_CAPP(CHIPS)':
 'A': CDS_PINID='A';
NODE_NAME     PC6812 1
 '@T6G_MB_LIB.T6G(SCH_1):PAGE476_I248@PURE_QUANTA.Q_CAPP(CHIPS)':
 'A': CDS_PINID='A';
NODE_NAME     PC6587_2 1
 '@T6G_MB_LIB.T6G(SCH_1):PAGE476_I250@PURE_QUANTA.Q_CAP(CHIPS)':
 'A': CDS_PINID='A';
NODE_NAME     PC6586_2 1
 '@T6G_MB_LIB.T6G(SCH_1):PAGE476_I251@PURE_QUANTA.Q_CAP(CHIPS)':
 'A': CDS_PINID='A';
NODE_NAME     PC6806 1
 '@T6G_MB_LIB.T6G(SCH_1):PAGE476_I255@PURE_QUANTA.Q_CAP(CHIPS)':
 'A': CDS_PINID='A';
NODE_NAME     PL6506 2
 '@T6G_MB_LIB.T6G(SCH_1):PAGE476_I257@PURE_QUANTA.Q_INDUCTOR(CHIPS)':
 '2': CDS_PINID='\2\';
NODE_NAME     PR6564 2
 '@T6G_MB_LIB.T6G(SCH_1):PAGE476_I263@PURE_QUANTA.Q_RES(CHIPS)':
 'B': CDS_PINID='B';
NODE_NAME     U6010 BL17
 '@T6G_MB_LIB.T6G(SCH_1):PAGE386_I3@PURE_QUANTA.PT5161LRS(CHIPS)':
 'PWR_2D_1': CDS_PINID='PWR_2D_1';
NODE_NAME     U6010 BL20
 '@T6G_MB_LIB.T6G(SCH_1):PAGE386_I3@PURE_QUANTA.PT5161LRS(CHIPS)':
 'PWR_2D_2': CDS_PINID='PWR_2D_2';
NODE_NAME     U6010 CW17
 '@T6G_MB_LIB.T6G(SCH_1):PAGE386_I3@PURE_QUANTA.PT5161LRS(CHIPS)':
 'PWR_2D_3': CDS_PINID='PWR_2D_3';
NODE_NAME     U6010 CW20
 '@T6G_MB_LIB.T6G(SCH_1):PAGE386_I3@PURE_QUANTA.PT5161LRS(CHIPS)':
 'PWR_2D_4': CDS_PINID='PWR_2D_4';
NODE_NAME     R961 1
 '@T6G_MB_LIB.T6G(SCH_1):PAGE388_I10@PURE_QUANTA.Q_RES(CHIPS)':
 'A': CDS_PINID='A';
NODE_NAME     L12 1
 '@T6G_MB_LIB.T6G(SCH_1):PAGE388_I30@PURE_QUANTA.Q_INDUCTOR(CHIPS)':
 '1': CDS_PINID='\1\';
NODE_NAME     C559 1
 '@T6G_MB_LIB.T6G(SCH_1):PAGE388_I72@PURE_QUANTA.Q_CAP(CHIPS)':
 'A': CDS_PINID='A';
NODE_NAME     C574 1
 '@T6G_MB_LIB.T6G(SCH_1):PAGE388_I73@PURE_QUANTA.Q_CAP(CHIPS)':
 'A': CDS_PINID='A';
NODE_NAME     C563 1
 '@T6G_MB_LIB.T6G(SCH_1):PAGE388_I74@PURE_QUANTA.Q_CAP(CHIPS)':
 'A': CDS_PINID='A';
NODE_NAME     C569 1
 '@T6G_MB_LIB.T6G(SCH_1):PAGE388_I79@PURE_QUANTA.Q_CAP(CHIPS)':
 'A': CDS_PINID='A';
NODE_NAME     C528 1
 '@T6G_MB_LIB.T6G(SCH_1):PAGE388_I80@PURE_QUANTA.Q_CAP(CHIPS)':
 'A': CDS_PINID='A';
NODE_NAME     C522 1
 '@T6G_MB_LIB.T6G(SCH_1):PAGE388_I81@PURE_QUANTA.Q_CAP(CHIPS)':
 'A': CDS_PINID='A';
NODE_NAME     C524 1
 '@T6G_MB_LIB.T6G(SCH_1):PAGE388_I84@PURE_QUANTA.Q_CAP(CHIPS)':
 'A': CDS_PINID='A';
NODE_NAME     C578 1
 '@T6G_MB_LIB.T6G(SCH_1):PAGE388_I85@PURE_QUANTA.Q_CAP(CHIPS)':
 'A': CDS_PINID='A';
NODE_NAME     C540 1
 '@T6G_MB_LIB.T6G(SCH_1):PAGE388_I87@PURE_QUANTA.Q_CAP(CHIPS)':
 'A': CDS_PINID='A';
NODE_NAME     U6011 BL17
 '@T6G_MB_LIB.T6G(SCH_1):PAGE409_I5@PURE_QUANTA.PT5161LRS(CHIPS)':
 'PWR_2D_1': CDS_PINID='PWR_2D_1';
NODE_NAME     U6011 BL20
 '@T6G_MB_LIB.T6G(SCH_1):PAGE409_I5@PURE_QUANTA.PT5161LRS(CHIPS)':
 'PWR_2D_2': CDS_PINID='PWR_2D_2';
NODE_NAME     U6011 CW17
 '@T6G_MB_LIB.T6G(SCH_1):PAGE409_I5@PURE_QUANTA.PT5161LRS(CHIPS)':
 'PWR_2D_3': CDS_PINID='PWR_2D_3';
NODE_NAME     U6011 CW20
 '@T6G_MB_LIB.T6G(SCH_1):PAGE409_I5@PURE_QUANTA.PT5161LRS(CHIPS)':
 'PWR_2D_4': CDS_PINID='PWR_2D_4';
NODE_NAME     R1010 1
 '@T6G_MB_LIB.T6G(SCH_1):PAGE411_I10@PURE_QUANTA.Q_RES(CHIPS)':
 'A': CDS_PINID='A';
NODE_NAME     L14 1
 '@T6G_MB_LIB.T6G(SCH_1):PAGE411_I63@PURE_QUANTA.Q_INDUCTOR(CHIPS)':
 '1': CDS_PINID='\1\';
NODE_NAME     C632 1
 '@T6G_MB_LIB.T6G(SCH_1):PAGE411_I67@PURE_QUANTA.Q_CAP(CHIPS)':
 'A': CDS_PINID='A';
NODE_NAME     C636 1
 '@T6G_MB_LIB.T6G(SCH_1):PAGE411_I68@PURE_QUANTA.Q_CAP(CHIPS)':
 'A': CDS_PINID='A';
NODE_NAME     C646 1
 '@T6G_MB_LIB.T6G(SCH_1):PAGE411_I74@PURE_QUANTA.Q_CAP(CHIPS)':
 'A': CDS_PINID='A';
NODE_NAME     C651 1
 '@T6G_MB_LIB.T6G(SCH_1):PAGE411_I75@PURE_QUANTA.Q_CAP(CHIPS)':
 'A': CDS_PINID='A';
NODE_NAME     C655 1
 '@T6G_MB_LIB.T6G(SCH_1):PAGE411_I76@PURE_QUANTA.Q_CAP(CHIPS)':
 'A': CDS_PINID='A';
NODE_NAME     C608 1
 '@T6G_MB_LIB.T6G(SCH_1):PAGE411_I81@PURE_QUANTA.Q_CAP(CHIPS)':
 'A': CDS_PINID='A';
NODE_NAME     C610 1
 '@T6G_MB_LIB.T6G(SCH_1):PAGE411_I82@PURE_QUANTA.Q_CAP(CHIPS)':
 'A': CDS_PINID='A';
NODE_NAME     C615 1
 '@T6G_MB_LIB.T6G(SCH_1):PAGE411_I83@PURE_QUANTA.Q_CAP(CHIPS)':
 'A': CDS_PINID='A';
NODE_NAME     C619 1
 '@T6G_MB_LIB.T6G(SCH_1):PAGE411_I84@PURE_QUANTA.Q_CAP(CHIPS)':
 'A': CDS_PINID='A';
NODE_NAME     U6012 BL17
 '@T6G_MB_LIB.T6G(SCH_1):PAGE420_I6@PURE_QUANTA.PT5161LRS(CHIPS)':
 'PWR_2D_1': CDS_PINID='PWR_2D_1';
NODE_NAME     U6012 BL20
 '@T6G_MB_LIB.T6G(SCH_1):PAGE420_I6@PURE_QUANTA.PT5161LRS(CHIPS)':
 'PWR_2D_2': CDS_PINID='PWR_2D_2';
NODE_NAME     U6012 CW17
 '@T6G_MB_LIB.T6G(SCH_1):PAGE420_I6@PURE_QUANTA.PT5161LRS(CHIPS)':
 'PWR_2D_3': CDS_PINID='PWR_2D_3';
NODE_NAME     U6012 CW20
 '@T6G_MB_LIB.T6G(SCH_1):PAGE420_I6@PURE_QUANTA.PT5161LRS(CHIPS)':
 'PWR_2D_4': CDS_PINID='PWR_2D_4';
NODE_NAME     R1051 1
 '@T6G_MB_LIB.T6G(SCH_1):PAGE422_I21@PURE_QUANTA.Q_RES(CHIPS)':
 'A': CDS_PINID='A';
NODE_NAME     L21 1
 '@T6G_MB_LIB.T6G(SCH_1):PAGE422_I30@PURE_QUANTA.Q_INDUCTOR(CHIPS)':
 '1': CDS_PINID='\1\';
NODE_NAME     C801 1
 '@T6G_MB_LIB.T6G(SCH_1):PAGE422_I77@PURE_QUANTA.Q_CAP(CHIPS)':
 'A': CDS_PINID='A';
NODE_NAME     C805 1
 '@T6G_MB_LIB.T6G(SCH_1):PAGE422_I78@PURE_QUANTA.Q_CAP(CHIPS)':
 'A': CDS_PINID='A';
NODE_NAME     C971 1
 '@T6G_MB_LIB.T6G(SCH_1):PAGE422_I79@PURE_QUANTA.Q_CAP(CHIPS)':
 'A': CDS_PINID='A';
NODE_NAME     C976 1
 '@T6G_MB_LIB.T6G(SCH_1):PAGE422_I80@PURE_QUANTA.Q_CAP(CHIPS)':
 'A': CDS_PINID='A';
NODE_NAME     C980 1
 '@T6G_MB_LIB.T6G(SCH_1):PAGE422_I81@PURE_QUANTA.Q_CAP(CHIPS)':
 'A': CDS_PINID='A';
NODE_NAME     C780 1
 '@T6G_MB_LIB.T6G(SCH_1):PAGE422_I82@PURE_QUANTA.Q_CAP(CHIPS)':
 'A': CDS_PINID='A';
NODE_NAME     C782 1
 '@T6G_MB_LIB.T6G(SCH_1):PAGE422_I83@PURE_QUANTA.Q_CAP(CHIPS)':
 'A': CDS_PINID='A';
NODE_NAME     C785 1
 '@T6G_MB_LIB.T6G(SCH_1):PAGE422_I84@PURE_QUANTA.Q_CAP(CHIPS)':
 'A': CDS_PINID='A';
NODE_NAME     C789 1
 '@T6G_MB_LIB.T6G(SCH_1):PAGE422_I86@PURE_QUANTA.Q_CAP(CHIPS)':
 'A': CDS_PINID='A';
NODE_NAME     U6013 BL17
 '@T6G_MB_LIB.T6G(SCH_1):PAGE431_I6@PURE_QUANTA.PT5161LRS(CHIPS)':
 'PWR_2D_1': CDS_PINID='PWR_2D_1';
NODE_NAME     U6013 BL20
 '@T6G_MB_LIB.T6G(SCH_1):PAGE431_I6@PURE_QUANTA.PT5161LRS(CHIPS)':
 'PWR_2D_2': CDS_PINID='PWR_2D_2';
NODE_NAME     U6013 CW17
 '@T6G_MB_LIB.T6G(SCH_1):PAGE431_I6@PURE_QUANTA.PT5161LRS(CHIPS)':
 'PWR_2D_3': CDS_PINID='PWR_2D_3';
NODE_NAME     U6013 CW20
 '@T6G_MB_LIB.T6G(SCH_1):PAGE431_I6@PURE_QUANTA.PT5161LRS(CHIPS)':
 'PWR_2D_4': CDS_PINID='PWR_2D_4';
NODE_NAME     R1094 1
 '@T6G_MB_LIB.T6G(SCH_1):PAGE433_I7@PURE_QUANTA.Q_RES(CHIPS)':
 'A': CDS_PINID='A';
NODE_NAME     L23 1
 '@T6G_MB_LIB.T6G(SCH_1):PAGE433_I65@PURE_QUANTA.Q_INDUCTOR(CHIPS)':
 '1': CDS_PINID='\1\';
NODE_NAME     C1028 1
 '@T6G_MB_LIB.T6G(SCH_1):PAGE433_I69@PURE_QUANTA.Q_CAP(CHIPS)':
 'A': CDS_PINID='A';
NODE_NAME     C1044 1
 '@T6G_MB_LIB.T6G(SCH_1):PAGE433_I73@PURE_QUANTA.Q_CAP(CHIPS)':
 'A': CDS_PINID='A';
NODE_NAME     C1032 1
 '@T6G_MB_LIB.T6G(SCH_1):PAGE433_I74@PURE_QUANTA.Q_CAP(CHIPS)':
 'A': CDS_PINID='A';
NODE_NAME     C1038 1
 '@T6G_MB_LIB.T6G(SCH_1):PAGE433_I75@PURE_QUANTA.Q_CAP(CHIPS)':
 'A': CDS_PINID='A';
NODE_NAME     C1016 1
 '@T6G_MB_LIB.T6G(SCH_1):PAGE433_I76@PURE_QUANTA.Q_CAP(CHIPS)':
 'A': CDS_PINID='A';
NODE_NAME     C1007 1
 '@T6G_MB_LIB.T6G(SCH_1):PAGE433_I81@PURE_QUANTA.Q_CAP(CHIPS)':
 'A': CDS_PINID='A';
NODE_NAME     C1009 1
 '@T6G_MB_LIB.T6G(SCH_1):PAGE433_I82@PURE_QUANTA.Q_CAP(CHIPS)':
 'A': CDS_PINID='A';
NODE_NAME     C1012 1
 '@T6G_MB_LIB.T6G(SCH_1):PAGE433_I84@PURE_QUANTA.Q_CAP(CHIPS)':
 'A': CDS_PINID='A';
NODE_NAME     C1048 1
 '@T6G_MB_LIB.T6G(SCH_1):PAGE433_I85@PURE_QUANTA.Q_CAP(CHIPS)':
 'A': CDS_PINID='A';
NODE_NAME     PJ09_P0_P 1
 '@T6G_MB_LIB.T6G(SCH_1):PAGE475_I214@PURE_QUANTA.Q_SHORT(CHIPS)':
 '1': CDS_PINID='\1\';
NODE_NAME     C7003 1
 '@T6G_MB_LIB.T6G(SCH_1):PAGE388_I95@PURE_QUANTA.Q_CAP(CHIPS)':
 'A': CDS_PINID='A';
NODE_NAME     C7002 1
 '@T6G_MB_LIB.T6G(SCH_1):PAGE388_I96@PURE_QUANTA.Q_CAP(CHIPS)':
 'A': CDS_PINID='A';
NODE_NAME     C7001 1
 '@T6G_MB_LIB.T6G(SCH_1):PAGE388_I97@PURE_QUANTA.Q_CAPP(CHIPS)':
 'A': CDS_PINID='A';
NODE_NAME     C7000 1
 '@T6G_MB_LIB.T6G(SCH_1):PAGE388_I98@PURE_QUANTA.Q_CAPP(CHIPS)':
 'A': CDS_PINID='A';
NODE_NAME     C7032 1
 '@T6G_MB_LIB.T6G(SCH_1):PAGE388_I102@PURE_QUANTA.Q_CAPP(CHIPS)':
 'A': CDS_PINID='A';
NODE_NAME     C7033 1
 '@T6G_MB_LIB.T6G(SCH_1):PAGE388_I103@PURE_QUANTA.Q_CAP(CHIPS)':
 'A': CDS_PINID='A';
NODE_NAME     C7034 1
 '@T6G_MB_LIB.T6G(SCH_1):PAGE388_I104@PURE_QUANTA.Q_CAP(CHIPS)':
 'A': CDS_PINID='A';
NODE_NAME     C7035 1
 '@T6G_MB_LIB.T6G(SCH_1):PAGE388_I105@PURE_QUANTA.Q_CAP(CHIPS)':
 'A': CDS_PINID='A';
NODE_NAME     C7036 1
 '@T6G_MB_LIB.T6G(SCH_1):PAGE388_I106@PURE_QUANTA.Q_CAP(CHIPS)':
 'A': CDS_PINID='A';
NET_NAME
'P0V9_CPU1_RT0_2A'
 '@T6G_MB_LIB.T6G(SCH_1):P0V9_CPU1_RT0_2A':
 C_SIGNAL='@t6g_mb_lib.t6g(sch_1):p0v9_cpu1_rt0_2a',
 CDS_GLOBAL_NET='TRUE';
NODE_NAME     U6014 AC17
 '@T6G_MB_LIB.T6G(SCH_1):PAGE400_I1@PURE_QUANTA.PT5161LRS(CHIPS)':
 'PWR_2A_1': CDS_PINID='PWR_2A_1';
NODE_NAME     U6014 AC20
 '@T6G_MB_LIB.T6G(SCH_1):PAGE400_I1@PURE_QUANTA.PT5161LRS(CHIPS)':
 'PWR_2A_2': CDS_PINID='PWR_2A_2';
NODE_NAME     U6014 AK17
 '@T6G_MB_LIB.T6G(SCH_1):PAGE400_I1@PURE_QUANTA.PT5161LRS(CHIPS)':
 'PWR_2A_3': CDS_PINID='PWR_2A_3';
NODE_NAME     U6014 AK20
 '@T6G_MB_LIB.T6G(SCH_1):PAGE400_I1@PURE_QUANTA.PT5161LRS(CHIPS)':
 'PWR_2A_4': CDS_PINID='PWR_2A_4';
NODE_NAME     U6014 AU17
 '@T6G_MB_LIB.T6G(SCH_1):PAGE400_I1@PURE_QUANTA.PT5161LRS(CHIPS)':
 'PWR_2A_5': CDS_PINID='PWR_2A_5';
NODE_NAME     U6014 AU20
 '@T6G_MB_LIB.T6G(SCH_1):PAGE400_I1@PURE_QUANTA.PT5161LRS(CHIPS)':
 'PWR_2A_6': CDS_PINID='PWR_2A_6';
NODE_NAME     U6014 DN17
 '@T6G_MB_LIB.T6G(SCH_1):PAGE400_I1@PURE_QUANTA.PT5161LRS(CHIPS)':
 'PWR_2A_11': CDS_PINID='PWR_2A_11';
NODE_NAME     U6014 DN20
 '@T6G_MB_LIB.T6G(SCH_1):PAGE400_I1@PURE_QUANTA.PT5161LRS(CHIPS)':
 'PWR_2A_12': CDS_PINID='PWR_2A_12';
NODE_NAME     U6014 DY17
 '@T6G_MB_LIB.T6G(SCH_1):PAGE400_I1@PURE_QUANTA.PT5161LRS(CHIPS)':
 'PWR_2A_13': CDS_PINID='PWR_2A_13';
NODE_NAME     U6014 DY20
 '@T6G_MB_LIB.T6G(SCH_1):PAGE400_I1@PURE_QUANTA.PT5161LRS(CHIPS)':
 'PWR_2A_14': CDS_PINID='PWR_2A_14';
NODE_NAME     U6014 EG17
 '@T6G_MB_LIB.T6G(SCH_1):PAGE400_I1@PURE_QUANTA.PT5161LRS(CHIPS)':
 'PWR_2A_15': CDS_PINID='PWR_2A_15';
NODE_NAME     U6014 EG20
 '@T6G_MB_LIB.T6G(SCH_1):PAGE400_I1@PURE_QUANTA.PT5161LRS(CHIPS)':
 'PWR_2A_16': CDS_PINID='PWR_2A_16';
NODE_NAME     U6014 EP17
 '@T6G_MB_LIB.T6G(SCH_1):PAGE400_I1@PURE_QUANTA.PT5161LRS(CHIPS)':
 'PWR_2A_17': CDS_PINID='PWR_2A_17';
NODE_NAME     U6014 EP20
 '@T6G_MB_LIB.T6G(SCH_1):PAGE400_I1@PURE_QUANTA.PT5161LRS(CHIPS)':
 'PWR_2A_18': CDS_PINID='PWR_2A_18';
NODE_NAME     U6014 T17
 '@T6G_MB_LIB.T6G(SCH_1):PAGE400_I1@PURE_QUANTA.PT5161LRS(CHIPS)':
 'PWR_2A_19': CDS_PINID='PWR_2A_19';
NODE_NAME     U6014 T20
 '@T6G_MB_LIB.T6G(SCH_1):PAGE400_I1@PURE_QUANTA.PT5161LRS(CHIPS)':
 'PWR_2A_20': CDS_PINID='PWR_2A_20';
NODE_NAME     C222 1
 '@T6G_MB_LIB.T6G(SCH_1):PAGE398_I42@PURE_QUANTA.Q_CAP(CHIPS)':
 'A': CDS_PINID='A';
NODE_NAME     C220 1
 '@T6G_MB_LIB.T6G(SCH_1):PAGE398_I44@PURE_QUANTA.Q_CAP(CHIPS)':
 'A': CDS_PINID='A';
NODE_NAME     C135 1
 '@T6G_MB_LIB.T6G(SCH_1):PAGE398_I46@PURE_QUANTA.Q_CAP(CHIPS)':
 'A': CDS_PINID='A';
NODE_NAME     C243 1
 '@T6G_MB_LIB.T6G(SCH_1):PAGE398_I47@PURE_QUANTA.Q_CAP(CHIPS)':
 'A': CDS_PINID='A';
NODE_NAME     C138 1
 '@T6G_MB_LIB.T6G(SCH_1):PAGE398_I48@PURE_QUANTA.Q_CAP(CHIPS)':
 'A': CDS_PINID='A';
NODE_NAME     C257 1
 '@T6G_MB_LIB.T6G(SCH_1):PAGE398_I49@PURE_QUANTA.Q_CAP(CHIPS)':
 'A': CDS_PINID='A';
NODE_NAME     C221 1
 '@T6G_MB_LIB.T6G(SCH_1):PAGE398_I50@PURE_QUANTA.Q_CAP(CHIPS)':
 'A': CDS_PINID='A';
NODE_NAME     C258 1
 '@T6G_MB_LIB.T6G(SCH_1):PAGE398_I51@PURE_QUANTA.Q_CAP(CHIPS)':
 'A': CDS_PINID='A';
NODE_NAME     C225 1
 '@T6G_MB_LIB.T6G(SCH_1):PAGE398_I52@PURE_QUANTA.Q_CAP(CHIPS)':
 'A': CDS_PINID='A';
NODE_NAME     C240 1
 '@T6G_MB_LIB.T6G(SCH_1):PAGE398_I53@PURE_QUANTA.Q_CAP(CHIPS)':
 'A': CDS_PINID='A';
NODE_NAME     C284 1
 '@T6G_MB_LIB.T6G(SCH_1):PAGE398_I54@PURE_QUANTA.Q_CAP(CHIPS)':
 'A': CDS_PINID='A';
NODE_NAME     C188 1
 '@T6G_MB_LIB.T6G(SCH_1):PAGE398_I55@PURE_QUANTA.Q_CAP(CHIPS)':
 'A': CDS_PINID='A';
NODE_NAME     C265 1
 '@T6G_MB_LIB.T6G(SCH_1):PAGE398_I56@PURE_QUANTA.Q_CAP(CHIPS)':
 'A': CDS_PINID='A';
NODE_NAME     C227 1
 '@T6G_MB_LIB.T6G(SCH_1):PAGE398_I57@PURE_QUANTA.Q_CAP(CHIPS)':
 'A': CDS_PINID='A';
NODE_NAME     C186 1
 '@T6G_MB_LIB.T6G(SCH_1):PAGE398_I58@PURE_QUANTA.Q_CAP(CHIPS)':
 'A': CDS_PINID='A';
NODE_NAME     C280 1
 '@T6G_MB_LIB.T6G(SCH_1):PAGE398_I59@PURE_QUANTA.Q_CAP(CHIPS)':
 'A': CDS_PINID='A';
NODE_NAME     C190 1
 '@T6G_MB_LIB.T6G(SCH_1):PAGE398_I62@PURE_QUANTA.Q_CAP(CHIPS)':
 'A': CDS_PINID='A';
NODE_NAME     C285 1
 '@T6G_MB_LIB.T6G(SCH_1):PAGE398_I63@PURE_QUANTA.Q_CAP(CHIPS)':
 'A': CDS_PINID='A';
NODE_NAME     C255 1
 '@T6G_MB_LIB.T6G(SCH_1):PAGE398_I64@PURE_QUANTA.Q_CAP(CHIPS)':
 'A': CDS_PINID='A';
NODE_NAME     C262 1
 '@T6G_MB_LIB.T6G(SCH_1):PAGE398_I65@PURE_QUANTA.Q_CAP(CHIPS)':
 'A': CDS_PINID='A';
NODE_NAME     C259 1
 '@T6G_MB_LIB.T6G(SCH_1):PAGE398_I66@PURE_QUANTA.Q_CAP(CHIPS)':
 'A': CDS_PINID='A';
NODE_NAME     C254 1
 '@T6G_MB_LIB.T6G(SCH_1):PAGE398_I67@PURE_QUANTA.Q_CAP(CHIPS)':
 'A': CDS_PINID='A';
NODE_NAME     C286 1
 '@T6G_MB_LIB.T6G(SCH_1):PAGE398_I68@PURE_QUANTA.Q_CAP(CHIPS)':
 'A': CDS_PINID='A';
NODE_NAME     C250 1
 '@T6G_MB_LIB.T6G(SCH_1):PAGE398_I70@PURE_QUANTA.Q_CAP(CHIPS)':
 'A': CDS_PINID='A';
NODE_NAME     C269 1
 '@T6G_MB_LIB.T6G(SCH_1):PAGE398_I71@PURE_QUANTA.Q_CAP(CHIPS)':
 'A': CDS_PINID='A';
NODE_NAME     C241 1
 '@T6G_MB_LIB.T6G(SCH_1):PAGE398_I72@PURE_QUANTA.Q_CAP(CHIPS)':
 'A': CDS_PINID='A';
NODE_NAME     C247 1
 '@T6G_MB_LIB.T6G(SCH_1):PAGE398_I73@PURE_QUANTA.Q_CAP(CHIPS)':
 'A': CDS_PINID='A';
NODE_NAME     L4 2
 '@T6G_MB_LIB.T6G(SCH_1):PAGE398_I74@PURE_QUANTA.Q_INDUCTOR(CHIPS)':
 '2': CDS_PINID='\2\';
NODE_NAME     C282 1
 '@T6G_MB_LIB.T6G(SCH_1):PAGE398_I80@PURE_QUANTA.Q_CAP(CHIPS)':
 'A': CDS_PINID='A';
NODE_NAME     C264 1
 '@T6G_MB_LIB.T6G(SCH_1):PAGE398_I81@PURE_QUANTA.Q_CAP(CHIPS)':
 'A': CDS_PINID='A';
NODE_NAME     C141 1
 '@T6G_MB_LIB.T6G(SCH_1):PAGE398_I82@PURE_QUANTA.Q_CAP(CHIPS)':
 'A': CDS_PINID='A';
NODE_NAME     C192 1
 '@T6G_MB_LIB.T6G(SCH_1):PAGE398_I83@PURE_QUANTA.Q_CAP(CHIPS)':
 'A': CDS_PINID='A';
NODE_NAME     C260 1
 '@T6G_MB_LIB.T6G(SCH_1):PAGE398_I84@PURE_QUANTA.Q_CAP(CHIPS)':
 'A': CDS_PINID='A';
NODE_NAME     C184 1
 '@T6G_MB_LIB.T6G(SCH_1):PAGE398_I85@PURE_QUANTA.Q_CAP(CHIPS)':
 'A': CDS_PINID='A';
NODE_NAME     C253 1
 '@T6G_MB_LIB.T6G(SCH_1):PAGE398_I86@PURE_QUANTA.Q_CAP(CHIPS)':
 'A': CDS_PINID='A';
NODE_NAME     C228 1
 '@T6G_MB_LIB.T6G(SCH_1):PAGE398_I87@PURE_QUANTA.Q_CAP(CHIPS)':
 'A': CDS_PINID='A';
NODE_NAME     R6705 2
 '@T6G_MB_LIB.T6G(SCH_1):PAGE398_I95@PURE_QUANTA.Q_RES(CHIPS)':
 'B': CDS_PINID='B';
NODE_NAME     C281 1
 '@T6G_MB_LIB.T6G(SCH_1):PAGE398_I101@PURE_QUANTA.Q_CAP(CHIPS)':
 'A': CDS_PINID='A';
NODE_NAME     C283 1
 '@T6G_MB_LIB.T6G(SCH_1):PAGE398_I102@PURE_QUANTA.Q_CAP(CHIPS)':
 'A': CDS_PINID='A';
NODE_NAME     C7020 1
 '@T6G_MB_LIB.T6G(SCH_1):PAGE398_I103@PURE_QUANTA.Q_CAPP(CHIPS)':
 'A': CDS_PINID='A';
NODE_NAME     C7021 1
 '@T6G_MB_LIB.T6G(SCH_1):PAGE398_I104@PURE_QUANTA.Q_CAPP(CHIPS)':
 'A': CDS_PINID='A';
NODE_NAME     C7022 1
 '@T6G_MB_LIB.T6G(SCH_1):PAGE398_I105@PURE_QUANTA.Q_CAP(CHIPS)':
 'A': CDS_PINID='A';
NET_NAME
'P0V9_CPU1_RT0_2A_2D'
 '@T6G_MB_LIB.T6G(SCH_1):P0V9_CPU1_RT0_2A_2D':
 C_SIGNAL='@t6g_mb_lib.t6g(sch_1):p0v9_cpu1_rt0_2a_2d',
 CDS_GLOBAL_NET='TRUE';
NODE_NAME     U6014 BD17
 '@T6G_MB_LIB.T6G(SCH_1):PAGE400_I1@PURE_QUANTA.PT5161LRS(CHIPS)':
 'PWR_2A_7': CDS_PINID='PWR_2A_7';
NODE_NAME     U6014 BD20
 '@T6G_MB_LIB.T6G(SCH_1):PAGE400_I1@PURE_QUANTA.PT5161LRS(CHIPS)':
 'PWR_2A_8': CDS_PINID='PWR_2A_8';
NODE_NAME     U6014 DF17
 '@T6G_MB_LIB.T6G(SCH_1):PAGE400_I1@PURE_QUANTA.PT5161LRS(CHIPS)':
 'PWR_2A_9': CDS_PINID='PWR_2A_9';
NODE_NAME     U6014 DF20
 '@T6G_MB_LIB.T6G(SCH_1):PAGE400_I1@PURE_QUANTA.PT5161LRS(CHIPS)':
 'PWR_2A_10': CDS_PINID='PWR_2A_10';
NODE_NAME     C198 1
 '@T6G_MB_LIB.T6G(SCH_1):PAGE398_I92@PURE_QUANTA.Q_CAP(CHIPS)':
 'A': CDS_PINID='A';
NODE_NAME     C191 1
 '@T6G_MB_LIB.T6G(SCH_1):PAGE398_I93@PURE_QUANTA.Q_CAP(CHIPS)':
 'A': CDS_PINID='A';
NODE_NAME     R6705 1
 '@T6G_MB_LIB.T6G(SCH_1):PAGE398_I95@PURE_QUANTA.Q_RES(CHIPS)':
 'A': CDS_PINID='A';
NODE_NAME     R6704 2
 '@T6G_MB_LIB.T6G(SCH_1):PAGE398_I96@PURE_QUANTA.Q_RES(CHIPS)':
 'B': CDS_PINID='B';
NODE_NAME     C187 1
 '@T6G_MB_LIB.T6G(SCH_1):PAGE398_I99@PURE_QUANTA.Q_CAP(CHIPS)':
 'A': CDS_PINID='A';
NODE_NAME     C201 1
 '@T6G_MB_LIB.T6G(SCH_1):PAGE398_I100@PURE_QUANTA.Q_CAP(CHIPS)':
 'A': CDS_PINID='A';
NET_NAME
'P0V9_CPU1_RT1_2A'
 '@T6G_MB_LIB.T6G(SCH_1):P0V9_CPU1_RT1_2A':
 C_SIGNAL='@t6g_mb_lib.t6g(sch_1):p0v9_cpu1_rt1_2a',
 CDS_GLOBAL_NET='TRUE';
NODE_NAME     U6015 AC17
 '@T6G_MB_LIB.T6G(SCH_1):PAGE391_I5@PURE_QUANTA.PT5161LRS(CHIPS)':
 'PWR_2A_1': CDS_PINID='PWR_2A_1';
NODE_NAME     U6015 AC20
 '@T6G_MB_LIB.T6G(SCH_1):PAGE391_I5@PURE_QUANTA.PT5161LRS(CHIPS)':
 'PWR_2A_2': CDS_PINID='PWR_2A_2';
NODE_NAME     U6015 AK17
 '@T6G_MB_LIB.T6G(SCH_1):PAGE391_I5@PURE_QUANTA.PT5161LRS(CHIPS)':
 'PWR_2A_3': CDS_PINID='PWR_2A_3';
NODE_NAME     U6015 AK20
 '@T6G_MB_LIB.T6G(SCH_1):PAGE391_I5@PURE_QUANTA.PT5161LRS(CHIPS)':
 'PWR_2A_4': CDS_PINID='PWR_2A_4';
NODE_NAME     U6015 AU17
 '@T6G_MB_LIB.T6G(SCH_1):PAGE391_I5@PURE_QUANTA.PT5161LRS(CHIPS)':
 'PWR_2A_5': CDS_PINID='PWR_2A_5';
NODE_NAME     U6015 AU20
 '@T6G_MB_LIB.T6G(SCH_1):PAGE391_I5@PURE_QUANTA.PT5161LRS(CHIPS)':
 'PWR_2A_6': CDS_PINID='PWR_2A_6';
NODE_NAME     U6015 DN17
 '@T6G_MB_LIB.T6G(SCH_1):PAGE391_I5@PURE_QUANTA.PT5161LRS(CHIPS)':
 'PWR_2A_11': CDS_PINID='PWR_2A_11';
NODE_NAME     U6015 DN20
 '@T6G_MB_LIB.T6G(SCH_1):PAGE391_I5@PURE_QUANTA.PT5161LRS(CHIPS)':
 'PWR_2A_12': CDS_PINID='PWR_2A_12';
NODE_NAME     U6015 DY17
 '@T6G_MB_LIB.T6G(SCH_1):PAGE391_I5@PURE_QUANTA.PT5161LRS(CHIPS)':
 'PWR_2A_13': CDS_PINID='PWR_2A_13';
NODE_NAME     U6015 DY20
 '@T6G_MB_LIB.T6G(SCH_1):PAGE391_I5@PURE_QUANTA.PT5161LRS(CHIPS)':
 'PWR_2A_14': CDS_PINID='PWR_2A_14';
NODE_NAME     U6015 EG17
 '@T6G_MB_LIB.T6G(SCH_1):PAGE391_I5@PURE_QUANTA.PT5161LRS(CHIPS)':
 'PWR_2A_15': CDS_PINID='PWR_2A_15';
NODE_NAME     U6015 EG20
 '@T6G_MB_LIB.T6G(SCH_1):PAGE391_I5@PURE_QUANTA.PT5161LRS(CHIPS)':
 'PWR_2A_16': CDS_PINID='PWR_2A_16';
NODE_NAME     U6015 EP17
 '@T6G_MB_LIB.T6G(SCH_1):PAGE391_I5@PURE_QUANTA.PT5161LRS(CHIPS)':
 'PWR_2A_17': CDS_PINID='PWR_2A_17';
NODE_NAME     U6015 EP20
 '@T6G_MB_LIB.T6G(SCH_1):PAGE391_I5@PURE_QUANTA.PT5161LRS(CHIPS)':
 'PWR_2A_18': CDS_PINID='PWR_2A_18';
NODE_NAME     U6015 T17
 '@T6G_MB_LIB.T6G(SCH_1):PAGE391_I5@PURE_QUANTA.PT5161LRS(CHIPS)':
 'PWR_2A_19': CDS_PINID='PWR_2A_19';
NODE_NAME     U6015 T20
 '@T6G_MB_LIB.T6G(SCH_1):PAGE391_I5@PURE_QUANTA.PT5161LRS(CHIPS)':
 'PWR_2A_20': CDS_PINID='PWR_2A_20';
NODE_NAME     R712 2
 '@T6G_MB_LIB.T6G(SCH_1):PAGE443_I11@PURE_QUANTA.Q_RES(CHIPS)':
 'B': CDS_PINID='B';
NODE_NAME     L6 2
 '@T6G_MB_LIB.T6G(SCH_1):PAGE443_I30@PURE_QUANTA.Q_INDUCTOR(CHIPS)':
 '2': CDS_PINID='\2\';
NODE_NAME     C340 1
 '@T6G_MB_LIB.T6G(SCH_1):PAGE443_I38@PURE_QUANTA.Q_CAP(CHIPS)':
 'A': CDS_PINID='A';
NODE_NAME     C344 1
 '@T6G_MB_LIB.T6G(SCH_1):PAGE443_I39@PURE_QUANTA.Q_CAP(CHIPS)':
 'A': CDS_PINID='A';
NODE_NAME     C294 1
 '@T6G_MB_LIB.T6G(SCH_1):PAGE443_I40@PURE_QUANTA.Q_CAP(CHIPS)':
 'A': CDS_PINID='A';
NODE_NAME     C332 1
 '@T6G_MB_LIB.T6G(SCH_1):PAGE443_I41@PURE_QUANTA.Q_CAP(CHIPS)':
 'A': CDS_PINID='A';
NODE_NAME     C307 1
 '@T6G_MB_LIB.T6G(SCH_1):PAGE443_I42@PURE_QUANTA.Q_CAP(CHIPS)':
 'A': CDS_PINID='A';
NODE_NAME     C326 1
 '@T6G_MB_LIB.T6G(SCH_1):PAGE443_I43@PURE_QUANTA.Q_CAP(CHIPS)':
 'A': CDS_PINID='A';
NODE_NAME     C321 1
 '@T6G_MB_LIB.T6G(SCH_1):PAGE443_I44@PURE_QUANTA.Q_CAP(CHIPS)':
 'A': CDS_PINID='A';
NODE_NAME     C325 1
 '@T6G_MB_LIB.T6G(SCH_1):PAGE443_I45@PURE_QUANTA.Q_CAP(CHIPS)':
 'A': CDS_PINID='A';
NODE_NAME     C331 1
 '@T6G_MB_LIB.T6G(SCH_1):PAGE443_I46@PURE_QUANTA.Q_CAP(CHIPS)':
 'A': CDS_PINID='A';
NODE_NAME     C330 1
 '@T6G_MB_LIB.T6G(SCH_1):PAGE443_I47@PURE_QUANTA.Q_CAP(CHIPS)':
 'A': CDS_PINID='A';
NODE_NAME     C312 1
 '@T6G_MB_LIB.T6G(SCH_1):PAGE443_I48@PURE_QUANTA.Q_CAP(CHIPS)':
 'A': CDS_PINID='A';
NODE_NAME     C349 1
 '@T6G_MB_LIB.T6G(SCH_1):PAGE443_I49@PURE_QUANTA.Q_CAP(CHIPS)':
 'A': CDS_PINID='A';
NODE_NAME     C291 1
 '@T6G_MB_LIB.T6G(SCH_1):PAGE443_I50@PURE_QUANTA.Q_CAP(CHIPS)':
 'A': CDS_PINID='A';
NODE_NAME     C319 1
 '@T6G_MB_LIB.T6G(SCH_1):PAGE443_I51@PURE_QUANTA.Q_CAP(CHIPS)':
 'A': CDS_PINID='A';
NODE_NAME     C314 1
 '@T6G_MB_LIB.T6G(SCH_1):PAGE443_I52@PURE_QUANTA.Q_CAP(CHIPS)':
 'A': CDS_PINID='A';
NODE_NAME     C337 1
 '@T6G_MB_LIB.T6G(SCH_1):PAGE443_I53@PURE_QUANTA.Q_CAP(CHIPS)':
 'A': CDS_PINID='A';
NODE_NAME     C343 1
 '@T6G_MB_LIB.T6G(SCH_1):PAGE443_I54@PURE_QUANTA.Q_CAP(CHIPS)':
 'A': CDS_PINID='A';
NODE_NAME     C336 1
 '@T6G_MB_LIB.T6G(SCH_1):PAGE443_I55@PURE_QUANTA.Q_CAP(CHIPS)':
 'A': CDS_PINID='A';
NODE_NAME     C346 1
 '@T6G_MB_LIB.T6G(SCH_1):PAGE443_I57@PURE_QUANTA.Q_CAP(CHIPS)':
 'A': CDS_PINID='A';
NODE_NAME     C293 1
 '@T6G_MB_LIB.T6G(SCH_1):PAGE443_I58@PURE_QUANTA.Q_CAP(CHIPS)':
 'A': CDS_PINID='A';
NODE_NAME     C301 1
 '@T6G_MB_LIB.T6G(SCH_1):PAGE443_I59@PURE_QUANTA.Q_CAP(CHIPS)':
 'A': CDS_PINID='A';
NODE_NAME     C322 1
 '@T6G_MB_LIB.T6G(SCH_1):PAGE443_I60@PURE_QUANTA.Q_CAP(CHIPS)':
 'A': CDS_PINID='A';
NODE_NAME     C334 1
 '@T6G_MB_LIB.T6G(SCH_1):PAGE443_I62@PURE_QUANTA.Q_CAP(CHIPS)':
 'A': CDS_PINID='A';
NODE_NAME     C289 1
 '@T6G_MB_LIB.T6G(SCH_1):PAGE443_I65@PURE_QUANTA.Q_CAP(CHIPS)':
 'A': CDS_PINID='A';
NODE_NAME     C353 1
 '@T6G_MB_LIB.T6G(SCH_1):PAGE443_I66@PURE_QUANTA.Q_CAP(CHIPS)':
 'A': CDS_PINID='A';
NODE_NAME     C317 1
 '@T6G_MB_LIB.T6G(SCH_1):PAGE443_I67@PURE_QUANTA.Q_CAP(CHIPS)':
 'A': CDS_PINID='A';
NODE_NAME     C320 1
 '@T6G_MB_LIB.T6G(SCH_1):PAGE443_I69@PURE_QUANTA.Q_CAP(CHIPS)':
 'A': CDS_PINID='A';
NODE_NAME     C324 1
 '@T6G_MB_LIB.T6G(SCH_1):PAGE443_I70@PURE_QUANTA.Q_CAP(CHIPS)':
 'A': CDS_PINID='A';
NODE_NAME     C328 1
 '@T6G_MB_LIB.T6G(SCH_1):PAGE443_I71@PURE_QUANTA.Q_CAP(CHIPS)':
 'A': CDS_PINID='A';
NODE_NAME     C329 1
 '@T6G_MB_LIB.T6G(SCH_1):PAGE443_I74@PURE_QUANTA.Q_CAP(CHIPS)':
 'A': CDS_PINID='A';
NODE_NAME     C335 1
 '@T6G_MB_LIB.T6G(SCH_1):PAGE443_I75@PURE_QUANTA.Q_CAP(CHIPS)':
 'A': CDS_PINID='A';
NODE_NAME     C351 1
 '@T6G_MB_LIB.T6G(SCH_1):PAGE443_I76@PURE_QUANTA.Q_CAP(CHIPS)':
 'A': CDS_PINID='A';
NODE_NAME     C318 1
 '@T6G_MB_LIB.T6G(SCH_1):PAGE443_I77@PURE_QUANTA.Q_CAP(CHIPS)':
 'A': CDS_PINID='A';
NODE_NAME     C339 1
 '@T6G_MB_LIB.T6G(SCH_1):PAGE443_I80@PURE_QUANTA.Q_CAP(CHIPS)':
 'A': CDS_PINID='A';
NODE_NAME     C354 1
 '@T6G_MB_LIB.T6G(SCH_1):PAGE443_I81@PURE_QUANTA.Q_CAP(CHIPS)':
 'A': CDS_PINID='A';
NODE_NAME     C341 1
 '@T6G_MB_LIB.T6G(SCH_1):PAGE443_I92@PURE_QUANTA.Q_CAP(CHIPS)':
 'A': CDS_PINID='A';
NODE_NAME     C350 1
 '@T6G_MB_LIB.T6G(SCH_1):PAGE443_I93@PURE_QUANTA.Q_CAP(CHIPS)':
 'A': CDS_PINID='A';
NODE_NAME     C7023 1
 '@T6G_MB_LIB.T6G(SCH_1):PAGE443_I94@PURE_QUANTA.Q_CAPP(CHIPS)':
 'A': CDS_PINID='A';
NODE_NAME     C7024 1
 '@T6G_MB_LIB.T6G(SCH_1):PAGE443_I95@PURE_QUANTA.Q_CAPP(CHIPS)':
 'A': CDS_PINID='A';
NODE_NAME     C7025 1
 '@T6G_MB_LIB.T6G(SCH_1):PAGE443_I96@PURE_QUANTA.Q_CAP(CHIPS)':
 'A': CDS_PINID='A';
NET_NAME
'P0V9_CPU1_RT1_2A_2D'
 '@T6G_MB_LIB.T6G(SCH_1):P0V9_CPU1_RT1_2A_2D':
 C_SIGNAL='@t6g_mb_lib.t6g(sch_1):p0v9_cpu1_rt1_2a_2d',
 CDS_GLOBAL_NET='TRUE';
NODE_NAME     U6015 BD17
 '@T6G_MB_LIB.T6G(SCH_1):PAGE391_I5@PURE_QUANTA.PT5161LRS(CHIPS)':
 'PWR_2A_7': CDS_PINID='PWR_2A_7';
NODE_NAME     U6015 BD20
 '@T6G_MB_LIB.T6G(SCH_1):PAGE391_I5@PURE_QUANTA.PT5161LRS(CHIPS)':
 'PWR_2A_8': CDS_PINID='PWR_2A_8';
NODE_NAME     U6015 DF17
 '@T6G_MB_LIB.T6G(SCH_1):PAGE391_I5@PURE_QUANTA.PT5161LRS(CHIPS)':
 'PWR_2A_9': CDS_PINID='PWR_2A_9';
NODE_NAME     U6015 DF20
 '@T6G_MB_LIB.T6G(SCH_1):PAGE391_I5@PURE_QUANTA.PT5161LRS(CHIPS)':
 'PWR_2A_10': CDS_PINID='PWR_2A_10';
NODE_NAME     R705 2
 '@T6G_MB_LIB.T6G(SCH_1):PAGE443_I10@PURE_QUANTA.Q_RES(CHIPS)':
 'B': CDS_PINID='B';
NODE_NAME     R712 1
 '@T6G_MB_LIB.T6G(SCH_1):PAGE443_I11@PURE_QUANTA.Q_RES(CHIPS)':
 'A': CDS_PINID='A';
NODE_NAME     C313 1
 '@T6G_MB_LIB.T6G(SCH_1):PAGE443_I34@PURE_QUANTA.Q_CAP(CHIPS)':
 'A': CDS_PINID='A';
NODE_NAME     C316 1
 '@T6G_MB_LIB.T6G(SCH_1):PAGE443_I37@PURE_QUANTA.Q_CAP(CHIPS)':
 'A': CDS_PINID='A';
NODE_NAME     C306 1
 '@T6G_MB_LIB.T6G(SCH_1):PAGE443_I90@PURE_QUANTA.Q_CAP(CHIPS)':
 'A': CDS_PINID='A';
NODE_NAME     C315 1
 '@T6G_MB_LIB.T6G(SCH_1):PAGE443_I91@PURE_QUANTA.Q_CAP(CHIPS)':
 'A': CDS_PINID='A';
NET_NAME
'P0V9_CPU1_RT2_2A'
 '@T6G_MB_LIB.T6G(SCH_1):P0V9_CPU1_RT2_2A':
 C_SIGNAL='@t6g_mb_lib.t6g(sch_1):p0v9_cpu1_rt2_2a',
 CDS_GLOBAL_NET='TRUE';
NODE_NAME     U6016 AC17
 '@T6G_MB_LIB.T6G(SCH_1):PAGE452_I7@PURE_QUANTA.PT5161LRS(CHIPS)':
 'PWR_2A_1': CDS_PINID='PWR_2A_1';
NODE_NAME     U6016 AC20
 '@T6G_MB_LIB.T6G(SCH_1):PAGE452_I7@PURE_QUANTA.PT5161LRS(CHIPS)':
 'PWR_2A_2': CDS_PINID='PWR_2A_2';
NODE_NAME     U6016 AK17
 '@T6G_MB_LIB.T6G(SCH_1):PAGE452_I7@PURE_QUANTA.PT5161LRS(CHIPS)':
 'PWR_2A_3': CDS_PINID='PWR_2A_3';
NODE_NAME     U6016 AK20
 '@T6G_MB_LIB.T6G(SCH_1):PAGE452_I7@PURE_QUANTA.PT5161LRS(CHIPS)':
 'PWR_2A_4': CDS_PINID='PWR_2A_4';
NODE_NAME     U6016 AU17
 '@T6G_MB_LIB.T6G(SCH_1):PAGE452_I7@PURE_QUANTA.PT5161LRS(CHIPS)':
 'PWR_2A_5': CDS_PINID='PWR_2A_5';
NODE_NAME     U6016 AU20
 '@T6G_MB_LIB.T6G(SCH_1):PAGE452_I7@PURE_QUANTA.PT5161LRS(CHIPS)':
 'PWR_2A_6': CDS_PINID='PWR_2A_6';
NODE_NAME     U6016 DN17
 '@T6G_MB_LIB.T6G(SCH_1):PAGE452_I7@PURE_QUANTA.PT5161LRS(CHIPS)':
 'PWR_2A_11': CDS_PINID='PWR_2A_11';
NODE_NAME     U6016 DN20
 '@T6G_MB_LIB.T6G(SCH_1):PAGE452_I7@PURE_QUANTA.PT5161LRS(CHIPS)':
 'PWR_2A_12': CDS_PINID='PWR_2A_12';
NODE_NAME     U6016 DY17
 '@T6G_MB_LIB.T6G(SCH_1):PAGE452_I7@PURE_QUANTA.PT5161LRS(CHIPS)':
 'PWR_2A_13': CDS_PINID='PWR_2A_13';
NODE_NAME     U6016 DY20
 '@T6G_MB_LIB.T6G(SCH_1):PAGE452_I7@PURE_QUANTA.PT5161LRS(CHIPS)':
 'PWR_2A_14': CDS_PINID='PWR_2A_14';
NODE_NAME     U6016 EG17
 '@T6G_MB_LIB.T6G(SCH_1):PAGE452_I7@PURE_QUANTA.PT5161LRS(CHIPS)':
 'PWR_2A_15': CDS_PINID='PWR_2A_15';
NODE_NAME     U6016 EG20
 '@T6G_MB_LIB.T6G(SCH_1):PAGE452_I7@PURE_QUANTA.PT5161LRS(CHIPS)':
 'PWR_2A_16': CDS_PINID='PWR_2A_16';
NODE_NAME     U6016 EP17
 '@T6G_MB_LIB.T6G(SCH_1):PAGE452_I7@PURE_QUANTA.PT5161LRS(CHIPS)':
 'PWR_2A_17': CDS_PINID='PWR_2A_17';
NODE_NAME     U6016 EP20
 '@T6G_MB_LIB.T6G(SCH_1):PAGE452_I7@PURE_QUANTA.PT5161LRS(CHIPS)':
 'PWR_2A_18': CDS_PINID='PWR_2A_18';
NODE_NAME     U6016 T17
 '@T6G_MB_LIB.T6G(SCH_1):PAGE452_I7@PURE_QUANTA.PT5161LRS(CHIPS)':
 'PWR_2A_19': CDS_PINID='PWR_2A_19';
NODE_NAME     U6016 T20
 '@T6G_MB_LIB.T6G(SCH_1):PAGE452_I7@PURE_QUANTA.PT5161LRS(CHIPS)':
 'PWR_2A_20': CDS_PINID='PWR_2A_20';
NODE_NAME     C421 1
 '@T6G_MB_LIB.T6G(SCH_1):PAGE454_I31@PURE_QUANTA.Q_CAP(CHIPS)':
 'A': CDS_PINID='A';
NODE_NAME     C427 1
 '@T6G_MB_LIB.T6G(SCH_1):PAGE454_I37@PURE_QUANTA.Q_CAP(CHIPS)':
 'A': CDS_PINID='A';
NODE_NAME     C393 1
 '@T6G_MB_LIB.T6G(SCH_1):PAGE454_I38@PURE_QUANTA.Q_CAP(CHIPS)':
 'A': CDS_PINID='A';
NODE_NAME     C430 1
 '@T6G_MB_LIB.T6G(SCH_1):PAGE454_I39@PURE_QUANTA.Q_CAP(CHIPS)':
 'A': CDS_PINID='A';
NODE_NAME     C400 1
 '@T6G_MB_LIB.T6G(SCH_1):PAGE454_I40@PURE_QUANTA.Q_CAP(CHIPS)':
 'A': CDS_PINID='A';
NODE_NAME     R859 2
 '@T6G_MB_LIB.T6G(SCH_1):PAGE454_I41@PURE_QUANTA.Q_RES(CHIPS)':
 'B': CDS_PINID='B';
NODE_NAME     C384 1
 '@T6G_MB_LIB.T6G(SCH_1):PAGE454_I42@PURE_QUANTA.Q_CAP(CHIPS)':
 'A': CDS_PINID='A';
NODE_NAME     C387 1
 '@T6G_MB_LIB.T6G(SCH_1):PAGE454_I43@PURE_QUANTA.Q_CAP(CHIPS)':
 'A': CDS_PINID='A';
NODE_NAME     C410 1
 '@T6G_MB_LIB.T6G(SCH_1):PAGE454_I44@PURE_QUANTA.Q_CAP(CHIPS)':
 'A': CDS_PINID='A';
NODE_NAME     C420 1
 '@T6G_MB_LIB.T6G(SCH_1):PAGE454_I45@PURE_QUANTA.Q_CAP(CHIPS)':
 'A': CDS_PINID='A';
NODE_NAME     C398 1
 '@T6G_MB_LIB.T6G(SCH_1):PAGE454_I46@PURE_QUANTA.Q_CAP(CHIPS)':
 'A': CDS_PINID='A';
NODE_NAME     C401 1
 '@T6G_MB_LIB.T6G(SCH_1):PAGE454_I47@PURE_QUANTA.Q_CAP(CHIPS)':
 'A': CDS_PINID='A';
NODE_NAME     C406 1
 '@T6G_MB_LIB.T6G(SCH_1):PAGE454_I48@PURE_QUANTA.Q_CAP(CHIPS)':
 'A': CDS_PINID='A';
NODE_NAME     C407 1
 '@T6G_MB_LIB.T6G(SCH_1):PAGE454_I49@PURE_QUANTA.Q_CAP(CHIPS)':
 'A': CDS_PINID='A';
NODE_NAME     C391 1
 '@T6G_MB_LIB.T6G(SCH_1):PAGE454_I50@PURE_QUANTA.Q_CAP(CHIPS)':
 'A': CDS_PINID='A';
NODE_NAME     C415 1
 '@T6G_MB_LIB.T6G(SCH_1):PAGE454_I51@PURE_QUANTA.Q_CAP(CHIPS)':
 'A': CDS_PINID='A';
NODE_NAME     C418 1
 '@T6G_MB_LIB.T6G(SCH_1):PAGE454_I52@PURE_QUANTA.Q_CAP(CHIPS)':
 'A': CDS_PINID='A';
NODE_NAME     C422 1
 '@T6G_MB_LIB.T6G(SCH_1):PAGE454_I53@PURE_QUANTA.Q_CAP(CHIPS)':
 'A': CDS_PINID='A';
NODE_NAME     C416 1
 '@T6G_MB_LIB.T6G(SCH_1):PAGE454_I54@PURE_QUANTA.Q_CAP(CHIPS)':
 'A': CDS_PINID='A';
NODE_NAME     C413 1
 '@T6G_MB_LIB.T6G(SCH_1):PAGE454_I55@PURE_QUANTA.Q_CAP(CHIPS)':
 'A': CDS_PINID='A';
NODE_NAME     C417 1
 '@T6G_MB_LIB.T6G(SCH_1):PAGE454_I56@PURE_QUANTA.Q_CAP(CHIPS)':
 'A': CDS_PINID='A';
NODE_NAME     C412 1
 '@T6G_MB_LIB.T6G(SCH_1):PAGE454_I57@PURE_QUANTA.Q_CAP(CHIPS)':
 'A': CDS_PINID='A';
NODE_NAME     C386 1
 '@T6G_MB_LIB.T6G(SCH_1):PAGE454_I58@PURE_QUANTA.Q_CAP(CHIPS)':
 'A': CDS_PINID='A';
NODE_NAME     C399 1
 '@T6G_MB_LIB.T6G(SCH_1):PAGE454_I59@PURE_QUANTA.Q_CAP(CHIPS)':
 'A': CDS_PINID='A';
NODE_NAME     C402 1
 '@T6G_MB_LIB.T6G(SCH_1):PAGE454_I60@PURE_QUANTA.Q_CAP(CHIPS)':
 'A': CDS_PINID='A';
NODE_NAME     C403 1
 '@T6G_MB_LIB.T6G(SCH_1):PAGE454_I61@PURE_QUANTA.Q_CAP(CHIPS)':
 'A': CDS_PINID='A';
NODE_NAME     C411 1
 '@T6G_MB_LIB.T6G(SCH_1):PAGE454_I62@PURE_QUANTA.Q_CAP(CHIPS)':
 'A': CDS_PINID='A';
NODE_NAME     C395 1
 '@T6G_MB_LIB.T6G(SCH_1):PAGE454_I64@PURE_QUANTA.Q_CAP(CHIPS)':
 'A': CDS_PINID='A';
NODE_NAME     C425 1
 '@T6G_MB_LIB.T6G(SCH_1):PAGE454_I67@PURE_QUANTA.Q_CAP(CHIPS)':
 'A': CDS_PINID='A';
NODE_NAME     C389 1
 '@T6G_MB_LIB.T6G(SCH_1):PAGE454_I68@PURE_QUANTA.Q_CAP(CHIPS)':
 'A': CDS_PINID='A';
NODE_NAME     C424 1
 '@T6G_MB_LIB.T6G(SCH_1):PAGE454_I69@PURE_QUANTA.Q_CAP(CHIPS)':
 'A': CDS_PINID='A';
NODE_NAME     C429 1
 '@T6G_MB_LIB.T6G(SCH_1):PAGE454_I70@PURE_QUANTA.Q_CAP(CHIPS)':
 'A': CDS_PINID='A';
NODE_NAME     C382 1
 '@T6G_MB_LIB.T6G(SCH_1):PAGE454_I71@PURE_QUANTA.Q_CAP(CHIPS)':
 'A': CDS_PINID='A';
NODE_NAME     C431 1
 '@T6G_MB_LIB.T6G(SCH_1):PAGE454_I72@PURE_QUANTA.Q_CAP(CHIPS)':
 'A': CDS_PINID='A';
NODE_NAME     L8 2
 '@T6G_MB_LIB.T6G(SCH_1):PAGE454_I74@PURE_QUANTA.Q_INDUCTOR(CHIPS)':
 '2': CDS_PINID='\2\';
NODE_NAME     C405 1
 '@T6G_MB_LIB.T6G(SCH_1):PAGE454_I86@PURE_QUANTA.Q_CAP(CHIPS)':
 'A': CDS_PINID='A';
NODE_NAME     C409 1
 '@T6G_MB_LIB.T6G(SCH_1):PAGE454_I87@PURE_QUANTA.Q_CAP(CHIPS)':
 'A': CDS_PINID='A';
NODE_NAME     C426 1
 '@T6G_MB_LIB.T6G(SCH_1):PAGE454_I92@PURE_QUANTA.Q_CAP(CHIPS)':
 'A': CDS_PINID='A';
NODE_NAME     C428 1
 '@T6G_MB_LIB.T6G(SCH_1):PAGE454_I93@PURE_QUANTA.Q_CAP(CHIPS)':
 'A': CDS_PINID='A';
NODE_NAME     C7026 1
 '@T6G_MB_LIB.T6G(SCH_1):PAGE454_I98@PURE_QUANTA.Q_CAPP(CHIPS)':
 'A': CDS_PINID='A';
NODE_NAME     C7027 1
 '@T6G_MB_LIB.T6G(SCH_1):PAGE454_I99@PURE_QUANTA.Q_CAPP(CHIPS)':
 'A': CDS_PINID='A';
NODE_NAME     C7028 1
 '@T6G_MB_LIB.T6G(SCH_1):PAGE454_I100@PURE_QUANTA.Q_CAP(CHIPS)':
 'A': CDS_PINID='A';
NET_NAME
'P0V9_CPU1_RT2_2A_2D'
 '@T6G_MB_LIB.T6G(SCH_1):P0V9_CPU1_RT2_2A_2D':
 C_SIGNAL='@t6g_mb_lib.t6g(sch_1):p0v9_cpu1_rt2_2a_2d',
 CDS_GLOBAL_NET='TRUE';
NODE_NAME     U6016 BD17
 '@T6G_MB_LIB.T6G(SCH_1):PAGE452_I7@PURE_QUANTA.PT5161LRS(CHIPS)':
 'PWR_2A_7': CDS_PINID='PWR_2A_7';
NODE_NAME     U6016 BD20
 '@T6G_MB_LIB.T6G(SCH_1):PAGE452_I7@PURE_QUANTA.PT5161LRS(CHIPS)':
 'PWR_2A_8': CDS_PINID='PWR_2A_8';
NODE_NAME     U6016 DF17
 '@T6G_MB_LIB.T6G(SCH_1):PAGE452_I7@PURE_QUANTA.PT5161LRS(CHIPS)':
 'PWR_2A_9': CDS_PINID='PWR_2A_9';
NODE_NAME     U6016 DF20
 '@T6G_MB_LIB.T6G(SCH_1):PAGE452_I7@PURE_QUANTA.PT5161LRS(CHIPS)':
 'PWR_2A_10': CDS_PINID='PWR_2A_10';
NODE_NAME     R858 2
 '@T6G_MB_LIB.T6G(SCH_1):PAGE454_I20@PURE_QUANTA.Q_RES(CHIPS)':
 'B': CDS_PINID='B';
NODE_NAME     C396 1
 '@T6G_MB_LIB.T6G(SCH_1):PAGE454_I35@PURE_QUANTA.Q_CAP(CHIPS)':
 'A': CDS_PINID='A';
NODE_NAME     C397 1
 '@T6G_MB_LIB.T6G(SCH_1):PAGE454_I36@PURE_QUANTA.Q_CAP(CHIPS)':
 'A': CDS_PINID='A';
NODE_NAME     R859 1
 '@T6G_MB_LIB.T6G(SCH_1):PAGE454_I41@PURE_QUANTA.Q_RES(CHIPS)':
 'A': CDS_PINID='A';
NODE_NAME     C390 1
 '@T6G_MB_LIB.T6G(SCH_1):PAGE454_I90@PURE_QUANTA.Q_CAP(CHIPS)':
 'A': CDS_PINID='A';
NODE_NAME     C394 1
 '@T6G_MB_LIB.T6G(SCH_1):PAGE454_I91@PURE_QUANTA.Q_CAP(CHIPS)':
 'A': CDS_PINID='A';
NET_NAME
'P0V9_CPU1_RT3_2A'
 '@T6G_MB_LIB.T6G(SCH_1):P0V9_CPU1_RT3_2A':
 C_SIGNAL='@t6g_mb_lib.t6g(sch_1):p0v9_cpu1_rt3_2a',
 CDS_GLOBAL_NET='TRUE';
NODE_NAME     U6017 AC17
 '@T6G_MB_LIB.T6G(SCH_1):PAGE463_I5@PURE_QUANTA.PT5161LRS(CHIPS)':
 'PWR_2A_1': CDS_PINID='PWR_2A_1';
NODE_NAME     U6017 AC20
 '@T6G_MB_LIB.T6G(SCH_1):PAGE463_I5@PURE_QUANTA.PT5161LRS(CHIPS)':
 'PWR_2A_2': CDS_PINID='PWR_2A_2';
NODE_NAME     U6017 AK17
 '@T6G_MB_LIB.T6G(SCH_1):PAGE463_I5@PURE_QUANTA.PT5161LRS(CHIPS)':
 'PWR_2A_3': CDS_PINID='PWR_2A_3';
NODE_NAME     U6017 AK20
 '@T6G_MB_LIB.T6G(SCH_1):PAGE463_I5@PURE_QUANTA.PT5161LRS(CHIPS)':
 'PWR_2A_4': CDS_PINID='PWR_2A_4';
NODE_NAME     U6017 AU17
 '@T6G_MB_LIB.T6G(SCH_1):PAGE463_I5@PURE_QUANTA.PT5161LRS(CHIPS)':
 'PWR_2A_5': CDS_PINID='PWR_2A_5';
NODE_NAME     U6017 AU20
 '@T6G_MB_LIB.T6G(SCH_1):PAGE463_I5@PURE_QUANTA.PT5161LRS(CHIPS)':
 'PWR_2A_6': CDS_PINID='PWR_2A_6';
NODE_NAME     U6017 DN17
 '@T6G_MB_LIB.T6G(SCH_1):PAGE463_I5@PURE_QUANTA.PT5161LRS(CHIPS)':
 'PWR_2A_11': CDS_PINID='PWR_2A_11';
NODE_NAME     U6017 DN20
 '@T6G_MB_LIB.T6G(SCH_1):PAGE463_I5@PURE_QUANTA.PT5161LRS(CHIPS)':
 'PWR_2A_12': CDS_PINID='PWR_2A_12';
NODE_NAME     U6017 DY17
 '@T6G_MB_LIB.T6G(SCH_1):PAGE463_I5@PURE_QUANTA.PT5161LRS(CHIPS)':
 'PWR_2A_13': CDS_PINID='PWR_2A_13';
NODE_NAME     U6017 DY20
 '@T6G_MB_LIB.T6G(SCH_1):PAGE463_I5@PURE_QUANTA.PT5161LRS(CHIPS)':
 'PWR_2A_14': CDS_PINID='PWR_2A_14';
NODE_NAME     U6017 EG17
 '@T6G_MB_LIB.T6G(SCH_1):PAGE463_I5@PURE_QUANTA.PT5161LRS(CHIPS)':
 'PWR_2A_15': CDS_PINID='PWR_2A_15';
NODE_NAME     U6017 EG20
 '@T6G_MB_LIB.T6G(SCH_1):PAGE463_I5@PURE_QUANTA.PT5161LRS(CHIPS)':
 'PWR_2A_16': CDS_PINID='PWR_2A_16';
NODE_NAME     U6017 EP17
 '@T6G_MB_LIB.T6G(SCH_1):PAGE463_I5@PURE_QUANTA.PT5161LRS(CHIPS)':
 'PWR_2A_17': CDS_PINID='PWR_2A_17';
NODE_NAME     U6017 EP20
 '@T6G_MB_LIB.T6G(SCH_1):PAGE463_I5@PURE_QUANTA.PT5161LRS(CHIPS)':
 'PWR_2A_18': CDS_PINID='PWR_2A_18';
NODE_NAME     U6017 T17
 '@T6G_MB_LIB.T6G(SCH_1):PAGE463_I5@PURE_QUANTA.PT5161LRS(CHIPS)':
 'PWR_2A_19': CDS_PINID='PWR_2A_19';
NODE_NAME     U6017 T20
 '@T6G_MB_LIB.T6G(SCH_1):PAGE463_I5@PURE_QUANTA.PT5161LRS(CHIPS)':
 'PWR_2A_20': CDS_PINID='PWR_2A_20';
NODE_NAME     R900 2
 '@T6G_MB_LIB.T6G(SCH_1):PAGE465_I36@PURE_QUANTA.Q_RES(CHIPS)':
 'B': CDS_PINID='B';
NODE_NAME     C495 1
 '@T6G_MB_LIB.T6G(SCH_1):PAGE465_I37@PURE_QUANTA.Q_CAP(CHIPS)':
 'A': CDS_PINID='A';
NODE_NAME     C470 1
 '@T6G_MB_LIB.T6G(SCH_1):PAGE465_I38@PURE_QUANTA.Q_CAP(CHIPS)':
 'A': CDS_PINID='A';
NODE_NAME     C459 1
 '@T6G_MB_LIB.T6G(SCH_1):PAGE465_I39@PURE_QUANTA.Q_CAP(CHIPS)':
 'A': CDS_PINID='A';
NODE_NAME     C480 1
 '@T6G_MB_LIB.T6G(SCH_1):PAGE465_I40@PURE_QUANTA.Q_CAP(CHIPS)':
 'A': CDS_PINID='A';
NODE_NAME     C490 1
 '@T6G_MB_LIB.T6G(SCH_1):PAGE465_I41@PURE_QUANTA.Q_CAP(CHIPS)':
 'A': CDS_PINID='A';
NODE_NAME     C500 1
 '@T6G_MB_LIB.T6G(SCH_1):PAGE465_I42@PURE_QUANTA.Q_CAP(CHIPS)':
 'A': CDS_PINID='A';
NODE_NAME     C473 1
 '@T6G_MB_LIB.T6G(SCH_1):PAGE465_I43@PURE_QUANTA.Q_CAP(CHIPS)':
 'A': CDS_PINID='A';
NODE_NAME     C448 1
 '@T6G_MB_LIB.T6G(SCH_1):PAGE465_I44@PURE_QUANTA.Q_CAP(CHIPS)':
 'A': CDS_PINID='A';
NODE_NAME     C453 1
 '@T6G_MB_LIB.T6G(SCH_1):PAGE465_I45@PURE_QUANTA.Q_CAP(CHIPS)':
 'A': CDS_PINID='A';
NODE_NAME     C477 1
 '@T6G_MB_LIB.T6G(SCH_1):PAGE465_I46@PURE_QUANTA.Q_CAP(CHIPS)':
 'A': CDS_PINID='A';
NODE_NAME     C450 1
 '@T6G_MB_LIB.T6G(SCH_1):PAGE465_I47@PURE_QUANTA.Q_CAP(CHIPS)':
 'A': CDS_PINID='A';
NODE_NAME     C485 1
 '@T6G_MB_LIB.T6G(SCH_1):PAGE465_I48@PURE_QUANTA.Q_CAP(CHIPS)':
 'A': CDS_PINID='A';
NODE_NAME     C488 1
 '@T6G_MB_LIB.T6G(SCH_1):PAGE465_I49@PURE_QUANTA.Q_CAP(CHIPS)':
 'A': CDS_PINID='A';
NODE_NAME     C472 1
 '@T6G_MB_LIB.T6G(SCH_1):PAGE465_I50@PURE_QUANTA.Q_CAP(CHIPS)':
 'A': CDS_PINID='A';
NODE_NAME     C469 1
 '@T6G_MB_LIB.T6G(SCH_1):PAGE465_I51@PURE_QUANTA.Q_CAP(CHIPS)':
 'A': CDS_PINID='A';
NODE_NAME     C494 1
 '@T6G_MB_LIB.T6G(SCH_1):PAGE465_I52@PURE_QUANTA.Q_CAP(CHIPS)':
 'A': CDS_PINID='A';
NODE_NAME     C491 1
 '@T6G_MB_LIB.T6G(SCH_1):PAGE465_I53@PURE_QUANTA.Q_CAP(CHIPS)':
 'A': CDS_PINID='A';
NODE_NAME     C492 1
 '@T6G_MB_LIB.T6G(SCH_1):PAGE465_I54@PURE_QUANTA.Q_CAP(CHIPS)':
 'A': CDS_PINID='A';
NODE_NAME     C481 1
 '@T6G_MB_LIB.T6G(SCH_1):PAGE465_I56@PURE_QUANTA.Q_CAP(CHIPS)':
 'A': CDS_PINID='A';
NODE_NAME     C457 1
 '@T6G_MB_LIB.T6G(SCH_1):PAGE465_I57@PURE_QUANTA.Q_CAP(CHIPS)':
 'A': CDS_PINID='A';
NODE_NAME     C497 1
 '@T6G_MB_LIB.T6G(SCH_1):PAGE465_I60@PURE_QUANTA.Q_CAP(CHIPS)':
 'A': CDS_PINID='A';
NODE_NAME     C455 1
 '@T6G_MB_LIB.T6G(SCH_1):PAGE465_I61@PURE_QUANTA.Q_CAP(CHIPS)':
 'A': CDS_PINID='A';
NODE_NAME     L10 2
 '@T6G_MB_LIB.T6G(SCH_1):PAGE465_I63@PURE_QUANTA.Q_INDUCTOR(CHIPS)':
 '2': CDS_PINID='\2\';
NODE_NAME     C466 1
 '@T6G_MB_LIB.T6G(SCH_1):PAGE465_I64@PURE_QUANTA.Q_CAP(CHIPS)':
 'A': CDS_PINID='A';
NODE_NAME     C471 1
 '@T6G_MB_LIB.T6G(SCH_1):PAGE465_I65@PURE_QUANTA.Q_CAP(CHIPS)':
 'A': CDS_PINID='A';
NODE_NAME     C475 1
 '@T6G_MB_LIB.T6G(SCH_1):PAGE465_I69@PURE_QUANTA.Q_CAP(CHIPS)':
 'A': CDS_PINID='A';
NODE_NAME     C501 1
 '@T6G_MB_LIB.T6G(SCH_1):PAGE465_I70@PURE_QUANTA.Q_CAP(CHIPS)':
 'A': CDS_PINID='A';
NODE_NAME     C476 1
 '@T6G_MB_LIB.T6G(SCH_1):PAGE465_I71@PURE_QUANTA.Q_CAP(CHIPS)':
 'A': CDS_PINID='A';
NODE_NAME     C487 1
 '@T6G_MB_LIB.T6G(SCH_1):PAGE465_I75@PURE_QUANTA.Q_CAP(CHIPS)':
 'A': CDS_PINID='A';
NODE_NAME     C499 1
 '@T6G_MB_LIB.T6G(SCH_1):PAGE465_I76@PURE_QUANTA.Q_CAP(CHIPS)':
 'A': CDS_PINID='A';
NODE_NAME     C482 1
 '@T6G_MB_LIB.T6G(SCH_1):PAGE465_I77@PURE_QUANTA.Q_CAP(CHIPS)':
 'A': CDS_PINID='A';
NODE_NAME     C462 1
 '@T6G_MB_LIB.T6G(SCH_1):PAGE465_I83@PURE_QUANTA.Q_CAP(CHIPS)':
 'A': CDS_PINID='A';
NODE_NAME     C452 1
 '@T6G_MB_LIB.T6G(SCH_1):PAGE465_I84@PURE_QUANTA.Q_CAP(CHIPS)':
 'A': CDS_PINID='A';
NODE_NAME     C486 1
 '@T6G_MB_LIB.T6G(SCH_1):PAGE465_I85@PURE_QUANTA.Q_CAP(CHIPS)':
 'A': CDS_PINID='A';
NODE_NAME     C483 1
 '@T6G_MB_LIB.T6G(SCH_1):PAGE465_I86@PURE_QUANTA.Q_CAP(CHIPS)':
 'A': CDS_PINID='A';
NODE_NAME     C479 1
 '@T6G_MB_LIB.T6G(SCH_1):PAGE465_I87@PURE_QUANTA.Q_CAP(CHIPS)':
 'A': CDS_PINID='A';
NODE_NAME     C496 1
 '@T6G_MB_LIB.T6G(SCH_1):PAGE465_I92@PURE_QUANTA.Q_CAP(CHIPS)':
 'A': CDS_PINID='A';
NODE_NAME     C498 1
 '@T6G_MB_LIB.T6G(SCH_1):PAGE465_I93@PURE_QUANTA.Q_CAP(CHIPS)':
 'A': CDS_PINID='A';
NODE_NAME     C7029 1
 '@T6G_MB_LIB.T6G(SCH_1):PAGE465_I94@PURE_QUANTA.Q_CAPP(CHIPS)':
 'A': CDS_PINID='A';
NODE_NAME     C7030 1
 '@T6G_MB_LIB.T6G(SCH_1):PAGE465_I95@PURE_QUANTA.Q_CAPP(CHIPS)':
 'A': CDS_PINID='A';
NODE_NAME     C7031 1
 '@T6G_MB_LIB.T6G(SCH_1):PAGE465_I96@PURE_QUANTA.Q_CAP(CHIPS)':
 'A': CDS_PINID='A';
NET_NAME
'P0V9_CPU1_RT3_2A_2D'
 '@T6G_MB_LIB.T6G(SCH_1):P0V9_CPU1_RT3_2A_2D':
 C_SIGNAL='@t6g_mb_lib.t6g(sch_1):p0v9_cpu1_rt3_2a_2d',
 CDS_GLOBAL_NET='TRUE';
NODE_NAME     U6017 BD17
 '@T6G_MB_LIB.T6G(SCH_1):PAGE463_I5@PURE_QUANTA.PT5161LRS(CHIPS)':
 'PWR_2A_7': CDS_PINID='PWR_2A_7';
NODE_NAME     U6017 BD20
 '@T6G_MB_LIB.T6G(SCH_1):PAGE463_I5@PURE_QUANTA.PT5161LRS(CHIPS)':
 'PWR_2A_8': CDS_PINID='PWR_2A_8';
NODE_NAME     U6017 DF17
 '@T6G_MB_LIB.T6G(SCH_1):PAGE463_I5@PURE_QUANTA.PT5161LRS(CHIPS)':
 'PWR_2A_9': CDS_PINID='PWR_2A_9';
NODE_NAME     U6017 DF20
 '@T6G_MB_LIB.T6G(SCH_1):PAGE463_I5@PURE_QUANTA.PT5161LRS(CHIPS)':
 'PWR_2A_10': CDS_PINID='PWR_2A_10';
NODE_NAME     R898 2
 '@T6G_MB_LIB.T6G(SCH_1):PAGE465_I8@PURE_QUANTA.Q_RES(CHIPS)':
 'B': CDS_PINID='B';
NODE_NAME     C463 1
 '@T6G_MB_LIB.T6G(SCH_1):PAGE465_I34@PURE_QUANTA.Q_CAP(CHIPS)':
 'A': CDS_PINID='A';
NODE_NAME     C464 1
 '@T6G_MB_LIB.T6G(SCH_1):PAGE465_I35@PURE_QUANTA.Q_CAP(CHIPS)':
 'A': CDS_PINID='A';
NODE_NAME     R900 1
 '@T6G_MB_LIB.T6G(SCH_1):PAGE465_I36@PURE_QUANTA.Q_RES(CHIPS)':
 'A': CDS_PINID='A';
NODE_NAME     C456 1
 '@T6G_MB_LIB.T6G(SCH_1):PAGE465_I90@PURE_QUANTA.Q_CAP(CHIPS)':
 'A': CDS_PINID='A';
NODE_NAME     C460 1
 '@T6G_MB_LIB.T6G(SCH_1):PAGE465_I91@PURE_QUANTA.Q_CAP(CHIPS)':
 'A': CDS_PINID='A';
NET_NAME
'P0V9_CPU1_RT_2D'
 '@T6G_MB_LIB.T6G(SCH_1):P0V9_CPU1_RT_2D':
 C_SIGNAL='@t6g_mb_lib.t6g(sch_1):p0v9_cpu1_rt_2d',
 CDS_GLOBAL_NET='TRUE';
NODE_NAME     U6014 BL17
 '@T6G_MB_LIB.T6G(SCH_1):PAGE400_I1@PURE_QUANTA.PT5161LRS(CHIPS)':
 'PWR_2D_1': CDS_PINID='PWR_2D_1';
NODE_NAME     U6014 BL20
 '@T6G_MB_LIB.T6G(SCH_1):PAGE400_I1@PURE_QUANTA.PT5161LRS(CHIPS)':
 'PWR_2D_2': CDS_PINID='PWR_2D_2';
NODE_NAME     U6014 CW17
 '@T6G_MB_LIB.T6G(SCH_1):PAGE400_I1@PURE_QUANTA.PT5161LRS(CHIPS)':
 'PWR_2D_3': CDS_PINID='PWR_2D_3';
NODE_NAME     U6014 CW20
 '@T6G_MB_LIB.T6G(SCH_1):PAGE400_I1@PURE_QUANTA.PT5161LRS(CHIPS)':
 'PWR_2D_4': CDS_PINID='PWR_2D_4';
NODE_NAME     PR6600 2
 '@T6G_MB_LIB.T6G(SCH_1):PAGE477_I23@PURE_QUANTA.Q_RES(CHIPS)':
 'B': CDS_PINID='B';
NODE_NAME     PR6631 2
 '@T6G_MB_LIB.T6G(SCH_1):PAGE478_I16@PURE_QUANTA.Q_RES(CHIPS)':
 'B': CDS_PINID='B';
NODE_NAME     PL6512 2
 '@T6G_MB_LIB.T6G(SCH_1):PAGE478_I22@PURE_QUANTA.Q_INDUCTOR(CHIPS)':
 '2': CDS_PINID='\2\';
NODE_NAME     PC6807 1
 '@T6G_MB_LIB.T6G(SCH_1):PAGE478_I23@PURE_QUANTA.Q_CAP(CHIPS)':
 'A': CDS_PINID='A';
NODE_NAME     PC6642_2 1
 '@T6G_MB_LIB.T6G(SCH_1):PAGE478_I29@PURE_QUANTA.Q_CAP(CHIPS)':
 'A': CDS_PINID='A';
NODE_NAME     PC6643_2 1
 '@T6G_MB_LIB.T6G(SCH_1):PAGE478_I30@PURE_QUANTA.Q_CAP(CHIPS)':
 'A': CDS_PINID='A';
NODE_NAME     PC6813 1
 '@T6G_MB_LIB.T6G(SCH_1):PAGE478_I31@PURE_QUANTA.Q_CAPP(CHIPS)':
 'A': CDS_PINID='A';
NODE_NAME     PC6814 1
 '@T6G_MB_LIB.T6G(SCH_1):PAGE478_I32@PURE_QUANTA.Q_CAPP(CHIPS)':
 'A': CDS_PINID='A';
NODE_NAME     PR6626 2
 '@T6G_MB_LIB.T6G(SCH_1):PAGE478_I59@PURE_QUANTA.Q_RES(CHIPS)':
 'B': CDS_PINID='B';
NODE_NAME     PL6511 2
 '@T6G_MB_LIB.T6G(SCH_1):PAGE478_I65@PURE_QUANTA.Q_INDUCTOR(CHIPS)':
 '2': CDS_PINID='\2\';
NODE_NAME     PC6623 1
 '@T6G_MB_LIB.T6G(SCH_1):PAGE478_I66@PURE_QUANTA.Q_CAP(CHIPS)':
 'A': CDS_PINID='A';
NODE_NAME     PC6624_1 1
 '@T6G_MB_LIB.T6G(SCH_1):PAGE478_I67@PURE_QUANTA.Q_CAP(CHIPS)':
 'A': CDS_PINID='A';
NODE_NAME     PC6625_1 1
 '@T6G_MB_LIB.T6G(SCH_1):PAGE478_I68@PURE_QUANTA.Q_CAP(CHIPS)':
 'A': CDS_PINID='A';
NODE_NAME     PC6626 1
 '@T6G_MB_LIB.T6G(SCH_1):PAGE478_I69@PURE_QUANTA.Q_CAPP(CHIPS)':
 'A': CDS_PINID='A';
NODE_NAME     PC6627 1
 '@T6G_MB_LIB.T6G(SCH_1):PAGE478_I70@PURE_QUANTA.Q_CAPP(CHIPS)':
 'A': CDS_PINID='A';
NODE_NAME     PC6815 1
 '@T6G_MB_LIB.T6G(SCH_1):PAGE478_I82@PURE_QUANTA.Q_CAPP(CHIPS)':
 'A': CDS_PINID='A';
NODE_NAME     PC6631 1
 '@T6G_MB_LIB.T6G(SCH_1):PAGE478_I83@PURE_QUANTA.Q_CAPP(CHIPS)':
 'A': CDS_PINID='A';
NODE_NAME     PC6632 1
 '@T6G_MB_LIB.T6G(SCH_1):PAGE478_I84@PURE_QUANTA.Q_CAPP(CHIPS)':
 'A': CDS_PINID='A';
NODE_NAME     PC6628 1
 '@T6G_MB_LIB.T6G(SCH_1):PAGE478_I93@PURE_QUANTA.Q_CAPP(CHIPS)':
 'A': CDS_PINID='A';
NODE_NAME     PC6629 1
 '@T6G_MB_LIB.T6G(SCH_1):PAGE478_I94@PURE_QUANTA.Q_CAPP(CHIPS)':
 'A': CDS_PINID='A';
NODE_NAME     PC6630 1
 '@T6G_MB_LIB.T6G(SCH_1):PAGE478_I95@PURE_QUANTA.Q_CAPP(CHIPS)':
 'A': CDS_PINID='A';
NODE_NAME     PR6625 1
 '@T6G_MB_LIB.T6G(SCH_1):PAGE478_I97@PURE_QUANTA.Q_RES(CHIPS)':
 'A': CDS_PINID='A';
NODE_NAME     C229 1
 '@T6G_MB_LIB.T6G(SCH_1):PAGE398_I34@PURE_QUANTA.Q_CAP(CHIPS)':
 'A': CDS_PINID='A';
NODE_NAME     C244 1
 '@T6G_MB_LIB.T6G(SCH_1):PAGE398_I35@PURE_QUANTA.Q_CAP(CHIPS)':
 'A': CDS_PINID='A';
NODE_NAME     C261 1
 '@T6G_MB_LIB.T6G(SCH_1):PAGE398_I36@PURE_QUANTA.Q_CAP(CHIPS)':
 'A': CDS_PINID='A';
NODE_NAME     C256 1
 '@T6G_MB_LIB.T6G(SCH_1):PAGE398_I39@PURE_QUANTA.Q_CAP(CHIPS)':
 'A': CDS_PINID='A';
NODE_NAME     C185 1
 '@T6G_MB_LIB.T6G(SCH_1):PAGE398_I40@PURE_QUANTA.Q_CAP(CHIPS)':
 'A': CDS_PINID='A';
NODE_NAME     L4 1
 '@T6G_MB_LIB.T6G(SCH_1):PAGE398_I74@PURE_QUANTA.Q_INDUCTOR(CHIPS)':
 '1': CDS_PINID='\1\';
NODE_NAME     C189 1
 '@T6G_MB_LIB.T6G(SCH_1):PAGE398_I75@PURE_QUANTA.Q_CAP(CHIPS)':
 'A': CDS_PINID='A';
NODE_NAME     C266 1
 '@T6G_MB_LIB.T6G(SCH_1):PAGE398_I76@PURE_QUANTA.Q_CAP(CHIPS)':
 'A': CDS_PINID='A';
NODE_NAME     C139 1
 '@T6G_MB_LIB.T6G(SCH_1):PAGE398_I77@PURE_QUANTA.Q_CAP(CHIPS)':
 'A': CDS_PINID='A';
NODE_NAME     C137 1
 '@T6G_MB_LIB.T6G(SCH_1):PAGE398_I78@PURE_QUANTA.Q_CAP(CHIPS)':
 'A': CDS_PINID='A';
NODE_NAME     R6704 1
 '@T6G_MB_LIB.T6G(SCH_1):PAGE398_I96@PURE_QUANTA.Q_RES(CHIPS)':
 'A': CDS_PINID='A';
NODE_NAME     U6015 BL17
 '@T6G_MB_LIB.T6G(SCH_1):PAGE391_I5@PURE_QUANTA.PT5161LRS(CHIPS)':
 'PWR_2D_1': CDS_PINID='PWR_2D_1';
NODE_NAME     U6015 BL20
 '@T6G_MB_LIB.T6G(SCH_1):PAGE391_I5@PURE_QUANTA.PT5161LRS(CHIPS)':
 'PWR_2D_2': CDS_PINID='PWR_2D_2';
NODE_NAME     U6015 CW17
 '@T6G_MB_LIB.T6G(SCH_1):PAGE391_I5@PURE_QUANTA.PT5161LRS(CHIPS)':
 'PWR_2D_3': CDS_PINID='PWR_2D_3';
NODE_NAME     U6015 CW20
 '@T6G_MB_LIB.T6G(SCH_1):PAGE391_I5@PURE_QUANTA.PT5161LRS(CHIPS)':
 'PWR_2D_4': CDS_PINID='PWR_2D_4';
NODE_NAME     R705 1
 '@T6G_MB_LIB.T6G(SCH_1):PAGE443_I10@PURE_QUANTA.Q_RES(CHIPS)':
 'A': CDS_PINID='A';
NODE_NAME     L6 1
 '@T6G_MB_LIB.T6G(SCH_1):PAGE443_I30@PURE_QUANTA.Q_INDUCTOR(CHIPS)':
 '1': CDS_PINID='\1\';
NODE_NAME     C323 1
 '@T6G_MB_LIB.T6G(SCH_1):PAGE443_I72@PURE_QUANTA.Q_CAP(CHIPS)':
 'A': CDS_PINID='A';
NODE_NAME     C327 1
 '@T6G_MB_LIB.T6G(SCH_1):PAGE443_I73@PURE_QUANTA.Q_CAP(CHIPS)':
 'A': CDS_PINID='A';
NODE_NAME     C338 1
 '@T6G_MB_LIB.T6G(SCH_1):PAGE443_I78@PURE_QUANTA.Q_CAP(CHIPS)':
 'A': CDS_PINID='A';
NODE_NAME     C342 1
 '@T6G_MB_LIB.T6G(SCH_1):PAGE443_I79@PURE_QUANTA.Q_CAP(CHIPS)':
 'A': CDS_PINID='A';
NODE_NAME     C300 1
 '@T6G_MB_LIB.T6G(SCH_1):PAGE443_I82@PURE_QUANTA.Q_CAP(CHIPS)':
 'A': CDS_PINID='A';
NODE_NAME     C311 1
 '@T6G_MB_LIB.T6G(SCH_1):PAGE443_I84@PURE_QUANTA.Q_CAP(CHIPS)':
 'A': CDS_PINID='A';
NODE_NAME     C292 1
 '@T6G_MB_LIB.T6G(SCH_1):PAGE443_I85@PURE_QUANTA.Q_CAP(CHIPS)':
 'A': CDS_PINID='A';
NODE_NAME     C290 1
 '@T6G_MB_LIB.T6G(SCH_1):PAGE443_I86@PURE_QUANTA.Q_CAP(CHIPS)':
 'A': CDS_PINID='A';
NODE_NAME     C333 1
 '@T6G_MB_LIB.T6G(SCH_1):PAGE443_I87@PURE_QUANTA.Q_CAP(CHIPS)':
 'A': CDS_PINID='A';
NODE_NAME     U6016 BL17
 '@T6G_MB_LIB.T6G(SCH_1):PAGE452_I7@PURE_QUANTA.PT5161LRS(CHIPS)':
 'PWR_2D_1': CDS_PINID='PWR_2D_1';
NODE_NAME     U6016 BL20
 '@T6G_MB_LIB.T6G(SCH_1):PAGE452_I7@PURE_QUANTA.PT5161LRS(CHIPS)':
 'PWR_2D_2': CDS_PINID='PWR_2D_2';
NODE_NAME     U6016 CW17
 '@T6G_MB_LIB.T6G(SCH_1):PAGE452_I7@PURE_QUANTA.PT5161LRS(CHIPS)':
 'PWR_2D_3': CDS_PINID='PWR_2D_3';
NODE_NAME     U6016 CW20
 '@T6G_MB_LIB.T6G(SCH_1):PAGE452_I7@PURE_QUANTA.PT5161LRS(CHIPS)':
 'PWR_2D_4': CDS_PINID='PWR_2D_4';
NODE_NAME     R858 1
 '@T6G_MB_LIB.T6G(SCH_1):PAGE454_I20@PURE_QUANTA.Q_RES(CHIPS)':
 'A': CDS_PINID='A';
NODE_NAME     L8 1
 '@T6G_MB_LIB.T6G(SCH_1):PAGE454_I74@PURE_QUANTA.Q_INDUCTOR(CHIPS)':
 '1': CDS_PINID='\1\';
NODE_NAME     C404 1
 '@T6G_MB_LIB.T6G(SCH_1):PAGE454_I76@PURE_QUANTA.Q_CAP(CHIPS)':
 'A': CDS_PINID='A';
NODE_NAME     C408 1
 '@T6G_MB_LIB.T6G(SCH_1):PAGE454_I77@PURE_QUANTA.Q_CAP(CHIPS)':
 'A': CDS_PINID='A';
NODE_NAME     C414 1
 '@T6G_MB_LIB.T6G(SCH_1):PAGE454_I78@PURE_QUANTA.Q_CAP(CHIPS)':
 'A': CDS_PINID='A';
NODE_NAME     C419 1
 '@T6G_MB_LIB.T6G(SCH_1):PAGE454_I79@PURE_QUANTA.Q_CAP(CHIPS)':
 'A': CDS_PINID='A';
NODE_NAME     C423 1
 '@T6G_MB_LIB.T6G(SCH_1):PAGE454_I80@PURE_QUANTA.Q_CAP(CHIPS)':
 'A': CDS_PINID='A';
NODE_NAME     C383 1
 '@T6G_MB_LIB.T6G(SCH_1):PAGE454_I82@PURE_QUANTA.Q_CAP(CHIPS)':
 'A': CDS_PINID='A';
NODE_NAME     C385 1
 '@T6G_MB_LIB.T6G(SCH_1):PAGE454_I83@PURE_QUANTA.Q_CAP(CHIPS)':
 'A': CDS_PINID='A';
NODE_NAME     C388 1
 '@T6G_MB_LIB.T6G(SCH_1):PAGE454_I84@PURE_QUANTA.Q_CAP(CHIPS)':
 'A': CDS_PINID='A';
NODE_NAME     C392 1
 '@T6G_MB_LIB.T6G(SCH_1):PAGE454_I85@PURE_QUANTA.Q_CAP(CHIPS)':
 'A': CDS_PINID='A';
NODE_NAME     U6017 BL17
 '@T6G_MB_LIB.T6G(SCH_1):PAGE463_I5@PURE_QUANTA.PT5161LRS(CHIPS)':
 'PWR_2D_1': CDS_PINID='PWR_2D_1';
NODE_NAME     U6017 BL20
 '@T6G_MB_LIB.T6G(SCH_1):PAGE463_I5@PURE_QUANTA.PT5161LRS(CHIPS)':
 'PWR_2D_2': CDS_PINID='PWR_2D_2';
NODE_NAME     U6017 CW17
 '@T6G_MB_LIB.T6G(SCH_1):PAGE463_I5@PURE_QUANTA.PT5161LRS(CHIPS)':
 'PWR_2D_3': CDS_PINID='PWR_2D_3';
NODE_NAME     U6017 CW20
 '@T6G_MB_LIB.T6G(SCH_1):PAGE463_I5@PURE_QUANTA.PT5161LRS(CHIPS)':
 'PWR_2D_4': CDS_PINID='PWR_2D_4';
NODE_NAME     R898 1
 '@T6G_MB_LIB.T6G(SCH_1):PAGE465_I8@PURE_QUANTA.Q_RES(CHIPS)':
 'A': CDS_PINID='A';
NODE_NAME     L10 1
 '@T6G_MB_LIB.T6G(SCH_1):PAGE465_I63@PURE_QUANTA.Q_INDUCTOR(CHIPS)':
 '1': CDS_PINID='\1\';
NODE_NAME     C474 1
 '@T6G_MB_LIB.T6G(SCH_1):PAGE465_I67@PURE_QUANTA.Q_CAP(CHIPS)':
 'A': CDS_PINID='A';
NODE_NAME     C478 1
 '@T6G_MB_LIB.T6G(SCH_1):PAGE465_I68@PURE_QUANTA.Q_CAP(CHIPS)':
 'A': CDS_PINID='A';
NODE_NAME     C489 1
 '@T6G_MB_LIB.T6G(SCH_1):PAGE465_I72@PURE_QUANTA.Q_CAP(CHIPS)':
 'A': CDS_PINID='A';
NODE_NAME     C484 1
 '@T6G_MB_LIB.T6G(SCH_1):PAGE465_I73@PURE_QUANTA.Q_CAP(CHIPS)':
 'A': CDS_PINID='A';
NODE_NAME     C454 1
 '@T6G_MB_LIB.T6G(SCH_1):PAGE465_I74@PURE_QUANTA.Q_CAP(CHIPS)':
 'A': CDS_PINID='A';
NODE_NAME     C449 1
 '@T6G_MB_LIB.T6G(SCH_1):PAGE465_I78@PURE_QUANTA.Q_CAP(CHIPS)':
 'A': CDS_PINID='A';
NODE_NAME     C451 1
 '@T6G_MB_LIB.T6G(SCH_1):PAGE465_I79@PURE_QUANTA.Q_CAP(CHIPS)':
 'A': CDS_PINID='A';
NODE_NAME     C493 1
 '@T6G_MB_LIB.T6G(SCH_1):PAGE465_I80@PURE_QUANTA.Q_CAP(CHIPS)':
 'A': CDS_PINID='A';
NODE_NAME     C458 1
 '@T6G_MB_LIB.T6G(SCH_1):PAGE465_I82@PURE_QUANTA.Q_CAP(CHIPS)':
 'A': CDS_PINID='A';
NODE_NAME     PJ09_P1_P 1
 '@T6G_MB_LIB.T6G(SCH_1):PAGE477_I95@PURE_QUANTA.Q_SHORT(CHIPS)':
 '1': CDS_PINID='\1\';
NODE_NAME     C7004 1
 '@T6G_MB_LIB.T6G(SCH_1):PAGE454_I94@PURE_QUANTA.Q_CAPP(CHIPS)':
 'A': CDS_PINID='A';
NODE_NAME     C7005 1
 '@T6G_MB_LIB.T6G(SCH_1):PAGE454_I95@PURE_QUANTA.Q_CAPP(CHIPS)':
 'A': CDS_PINID='A';
NODE_NAME     C7006 1
 '@T6G_MB_LIB.T6G(SCH_1):PAGE454_I96@PURE_QUANTA.Q_CAP(CHIPS)':
 'A': CDS_PINID='A';
NODE_NAME     C7007 1
 '@T6G_MB_LIB.T6G(SCH_1):PAGE454_I97@PURE_QUANTA.Q_CAP(CHIPS)':
 'A': CDS_PINID='A';
NODE_NAME     C7037 1
 '@T6G_MB_LIB.T6G(SCH_1):PAGE454_I101@PURE_QUANTA.Q_CAPP(CHIPS)':
 'A': CDS_PINID='A';
NODE_NAME     C7038 1
 '@T6G_MB_LIB.T6G(SCH_1):PAGE454_I102@PURE_QUANTA.Q_CAP(CHIPS)':
 'A': CDS_PINID='A';
NODE_NAME     C7039 1
 '@T6G_MB_LIB.T6G(SCH_1):PAGE454_I103@PURE_QUANTA.Q_CAP(CHIPS)':
 'A': CDS_PINID='A';
NODE_NAME     C7040 1
 '@T6G_MB_LIB.T6G(SCH_1):PAGE454_I104@PURE_QUANTA.Q_CAP(CHIPS)':
 'A': CDS_PINID='A';
NODE_NAME     C7041 1
 '@T6G_MB_LIB.T6G(SCH_1):PAGE454_I105@PURE_QUANTA.Q_CAP(CHIPS)':
 'A': CDS_PINID='A';
NET_NAME
'P0V9_RETIMER_CPU0_ADDR'
 '@T6G_MB_LIB.T6G(SCH_1):P0V9_RETIMER_CPU0_ADDR':
 C_SIGNAL='@t6g_mb_lib.t6g(sch_1):p0v9_retimer_cpu0_addr';
NODE_NAME     PU6502 34
 '@T6G_MB_LIB.T6G(SCH_1):PAGE475_I42@PURE_QUANTA.ISL69260IRAZT(CHIPS)':
 'ADDR_CFG': CDS_PINID='ADDR_CFG';
NODE_NAME     PR6603 2
 '@T6G_MB_LIB.T6G(SCH_1):PAGE475_I183@PURE_QUANTA.Q_RES(CHIPS)':
 'B': CDS_PINID='B';
NET_NAME
'P0V9_RETIMER_CPU0_CFP'
 '@T6G_MB_LIB.T6G(SCH_1):P0V9_RETIMER_CPU0_CFP':
 C_SIGNAL='@t6g_mb_lib.t6g(sch_1):p0v9_retimer_cpu0_cfp';
NODE_NAME     PU6502 33
 '@T6G_MB_LIB.T6G(SCH_1):PAGE475_I42@PURE_QUANTA.ISL69260IRAZT(CHIPS)':
 'CFP': CDS_PINID='CFP';
NODE_NAME     R652 2
 '@T6G_MB_LIB.T6G(SCH_1):PAGE475_I128@PURE_QUANTA.Q_RES(CHIPS)':
 'B': CDS_PINID='B';
NET_NAME
'P0V9_RETIMER_CPU0_EN'
 '@T6G_MB_LIB.T6G(SCH_1):P0V9_RETIMER_CPU0_EN':
 C_SIGNAL='@t6g_mb_lib.t6g(sch_1):p0v9_retimer_cpu0_en';
NODE_NAME     R651 1
 '@T6G_MB_LIB.T6G(SCH_1):PAGE475_I120@PURE_QUANTA.Q_RES(CHIPS)':
 'A': CDS_PINID='A';
NODE_NAME     R6854 1
 '@T6G_MB_LIB.T6G(SCH_1):PAGE80_I364@PURE_QUANTA.Q_RES(CHIPS)':
 'A': CDS_PINID='A';
NET_NAME
'P0V9_RETIMER_CPU0_EN0_R'
 '@T6G_MB_LIB.T6G(SCH_1):P0V9_RETIMER_CPU0_EN0_R':
 C_SIGNAL='@t6g_mb_lib.t6g(sch_1):p0v9_retimer_cpu0_en0_r';
NODE_NAME     PU6502 13
 '@T6G_MB_LIB.T6G(SCH_1):PAGE475_I42@PURE_QUANTA.ISL69260IRAZT(CHIPS)':
 'EN0': CDS_PINID='EN0';
NODE_NAME     R651 2
 '@T6G_MB_LIB.T6G(SCH_1):PAGE475_I120@PURE_QUANTA.Q_RES(CHIPS)':
 'B': CDS_PINID='B';
NODE_NAME     R6786 1
 '@T6G_MB_LIB.T6G(SCH_1):PAGE475_I208@PURE_QUANTA.Q_RES(CHIPS)':
 'A': CDS_PINID='A';
NET_NAME
'P0V9_RETIMER_CPU0_EN1_R'
 '@T6G_MB_LIB.T6G(SCH_1):P0V9_RETIMER_CPU0_EN1_R':
 C_SIGNAL='@t6g_mb_lib.t6g(sch_1):p0v9_retimer_cpu0_en1_r';
NODE_NAME     PU6502 20
 '@T6G_MB_LIB.T6G(SCH_1):PAGE475_I42@PURE_QUANTA.ISL69260IRAZT(CHIPS)':
 'EN1': CDS_PINID='EN1';
NODE_NAME     R6801 2
 '@T6G_MB_LIB.T6G(SCH_1):PAGE475_I161@PURE_QUANTA.Q_RES(CHIPS)':
 'B': CDS_PINID='B';
NET_NAME
'P0V9_RETIMER_CPU0_EN_R2'
 '@T6G_MB_LIB.T6G(SCH_1):P0V9_RETIMER_CPU0_EN_R2':
 C_SIGNAL='@t6g_mb_lib.t6g(sch_1):p0v9_retimer_cpu0_en_r2';
NODE_NAME     U18 AA10
 '@T6G_MB_LIB.T6G(SCH_1):PAGE80_I216@PURE_QUANTA.LCMXO3LF9400C5BG484C(CHIPS)':
 'PB22A||PCLKT2_0': CDS_PINID='\pb22a||pclkt2_0\';
NODE_NAME     R6854 2
 '@T6G_MB_LIB.T6G(SCH_1):PAGE80_I364@PURE_QUANTA.Q_RES(CHIPS)':
 'B': CDS_PINID='B';
NET_NAME
'P0V9_RETIMER_CPU0_IMON1'
 '@T6G_MB_LIB.T6G(SCH_1):P0V9_RETIMER_CPU0_IMON1':
 C_SIGNAL='@t6g_mb_lib.t6g(sch_1):p0v9_retimer_cpu0_imon1';
NODE_NAME     PU6502 23
 '@T6G_MB_LIB.T6G(SCH_1):PAGE475_I42@PURE_QUANTA.ISL69260IRAZT(CHIPS)':
 'CS7': CDS_PINID='CS7';
NODE_NAME     PU6503 38
 '@T6G_MB_LIB.T6G(SCH_1):PAGE476_I53@PURE_QUANTA.ISL99390FRZTR5935(CHIPS)':
 'IOUT': CDS_PINID='IOUT';
NET_NAME
'P0V9_RETIMER_CPU0_IMON2'
 '@T6G_MB_LIB.T6G(SCH_1):P0V9_RETIMER_CPU0_IMON2':
 C_SIGNAL='@t6g_mb_lib.t6g(sch_1):p0v9_retimer_cpu0_imon2';
NODE_NAME     PU6502 24
 '@T6G_MB_LIB.T6G(SCH_1):PAGE475_I42@PURE_QUANTA.ISL69260IRAZT(CHIPS)':
 'CS6': CDS_PINID='CS6';
NODE_NAME     PU6504 38
 '@T6G_MB_LIB.T6G(SCH_1):PAGE476_I270@PURE_QUANTA.ISL99390FRZTR5935(CHIPS)':
 'IOUT': CDS_PINID='IOUT';
NET_NAME
'P0V9_RETIMER_CPU0_INALERT'
 '@T6G_MB_LIB.T6G(SCH_1):P0V9_RETIMER_CPU0_INALERT':
 C_SIGNAL='@t6g_mb_lib.t6g(sch_1):p0v9_retimer_cpu0_inalert';
NODE_NAME     PU6502 15
 '@T6G_MB_LIB.T6G(SCH_1):PAGE475_I42@PURE_QUANTA.ISL69260IRAZT(CHIPS)':
 'NPINALERT#||NPSYSCRIT#': CDS_PINID='\npinalert#||npsyscrit#\';
NODE_NAME     R655 2
 '@T6G_MB_LIB.T6G(SCH_1):PAGE475_I127@PURE_QUANTA.Q_RES(CHIPS)':
 'B': CDS_PINID='B';
NET_NAME
'P0V9_RETIMER_CPU0_LSET1'
 '@T6G_MB_LIB.T6G(SCH_1):P0V9_RETIMER_CPU0_LSET1':
 C_SIGNAL='@t6g_mb_lib.t6g(sch_1):p0v9_retimer_cpu0_lset1';
NODE_NAME     PU6503 37
 '@T6G_MB_LIB.T6G(SCH_1):PAGE476_I53@PURE_QUANTA.ISL99390FRZTR5935(CHIPS)':
 'LSET': CDS_PINID='LSET';
NODE_NAME     PR6553 1
 '@T6G_MB_LIB.T6G(SCH_1):PAGE476_I220@PURE_QUANTA.Q_RES(CHIPS)':
 'A': CDS_PINID='A';
NET_NAME
'P0V9_RETIMER_CPU0_LSET2'
 '@T6G_MB_LIB.T6G(SCH_1):P0V9_RETIMER_CPU0_LSET2':
 C_SIGNAL='@t6g_mb_lib.t6g(sch_1):p0v9_retimer_cpu0_lset2';
NODE_NAME     PU6504 37
 '@T6G_MB_LIB.T6G(SCH_1):PAGE476_I270@PURE_QUANTA.ISL99390FRZTR5935(CHIPS)':
 'LSET': CDS_PINID='LSET';
NODE_NAME     PR6561 1
 '@T6G_MB_LIB.T6G(SCH_1):PAGE476_I276@PURE_QUANTA.Q_RES(CHIPS)':
 'A': CDS_PINID='A';
NET_NAME
'P0V9_RETIMER_CPU0_PMSCL'
 '@T6G_MB_LIB.T6G(SCH_1):P0V9_RETIMER_CPU0_PMSCL':
 C_SIGNAL='@t6g_mb_lib.t6g(sch_1):p0v9_retimer_cpu0_pmscl';
NODE_NAME     R646 1
 '@T6G_MB_LIB.T6G(SCH_1):PAGE475_I94@PURE_QUANTA.Q_RES(CHIPS)':
 'A': CDS_PINID='A';
NODE_NAME     R6856 2
 '@T6G_MB_LIB.T6G(SCH_1):PAGE349_I226@PURE_QUANTA.Q_RES(CHIPS)':
 'B': CDS_PINID='B';
NET_NAME
'P0V9_RETIMER_CPU0_PMSCL_R'
 '@T6G_MB_LIB.T6G(SCH_1):P0V9_RETIMER_CPU0_PMSCL_R':
 C_SIGNAL='@t6g_mb_lib.t6g(sch_1):p0v9_retimer_cpu0_pmscl_r';
NODE_NAME     PU6502 10
 '@T6G_MB_LIB.T6G(SCH_1):PAGE475_I42@PURE_QUANTA.ISL69260IRAZT(CHIPS)':
 'PMSCL': CDS_PINID='PMSCL';
NODE_NAME     R646 2
 '@T6G_MB_LIB.T6G(SCH_1):PAGE475_I94@PURE_QUANTA.Q_RES(CHIPS)':
 'B': CDS_PINID='B';
NET_NAME
'P0V9_RETIMER_CPU0_PMSDA'
 '@T6G_MB_LIB.T6G(SCH_1):P0V9_RETIMER_CPU0_PMSDA':
 C_SIGNAL='@t6g_mb_lib.t6g(sch_1):p0v9_retimer_cpu0_pmsda';
NODE_NAME     R647 1
 '@T6G_MB_LIB.T6G(SCH_1):PAGE475_I95@PURE_QUANTA.Q_RES(CHIPS)':
 'A': CDS_PINID='A';
NODE_NAME     R6857 2
 '@T6G_MB_LIB.T6G(SCH_1):PAGE349_I227@PURE_QUANTA.Q_RES(CHIPS)':
 'B': CDS_PINID='B';
NET_NAME
'P0V9_RETIMER_CPU0_PMSDA_R'
 '@T6G_MB_LIB.T6G(SCH_1):P0V9_RETIMER_CPU0_PMSDA_R':
 C_SIGNAL='@t6g_mb_lib.t6g(sch_1):p0v9_retimer_cpu0_pmsda_r';
NODE_NAME     PU6502 9
 '@T6G_MB_LIB.T6G(SCH_1):PAGE475_I42@PURE_QUANTA.ISL69260IRAZT(CHIPS)':
 'PMSDA': CDS_PINID='PMSDA';
NODE_NAME     R647 2
 '@T6G_MB_LIB.T6G(SCH_1):PAGE475_I95@PURE_QUANTA.Q_RES(CHIPS)':
 'B': CDS_PINID='B';
NET_NAME
'P0V9_RETIMER_CPU0_PVCC'
 '@T6G_MB_LIB.T6G(SCH_1):P0V9_RETIMER_CPU0_PVCC':
 C_SIGNAL='@t6g_mb_lib.t6g(sch_1):p0v9_retimer_cpu0_pvcc',
 CDS_GLOBAL_NET='TRUE';
NODE_NAME     PC6550_09P0_1 1
 '@T6G_MB_LIB.T6G(SCH_1):PAGE476_I47@PURE_QUANTA.Q_CAP(CHIPS)':
 'A': CDS_PINID='A';
NODE_NAME     PU6503 4
 '@T6G_MB_LIB.T6G(SCH_1):PAGE476_I53@PURE_QUANTA.ISL99390FRZTR5935(CHIPS)':
 'PVCC': CDS_PINID='PVCC';
NODE_NAME     PR6552 1
 '@T6G_MB_LIB.T6G(SCH_1):PAGE476_I58@PURE_QUANTA.Q_RES(CHIPS)':
 'A': CDS_PINID='A';
NODE_NAME     PR6550 2
 '@T6G_MB_LIB.T6G(SCH_1):PAGE476_I183@PURE_QUANTA.Q_RES(CHIPS)':
 'B': CDS_PINID='B';
NODE_NAME     PR6551 2
 '@T6G_MB_LIB.T6G(SCH_1):PAGE476_I185@PURE_QUANTA.Q_RES(CHIPS)':
 'B': CDS_PINID='B';
NODE_NAME     PC6551_09P0_2 1
 '@T6G_MB_LIB.T6G(SCH_1):PAGE476_I267@PURE_QUANTA.Q_CAP(CHIPS)':
 'A': CDS_PINID='A';
NODE_NAME     PR6560 1
 '@T6G_MB_LIB.T6G(SCH_1):PAGE476_I269@PURE_QUANTA.Q_RES(CHIPS)':
 'A': CDS_PINID='A';
NODE_NAME     PU6504 4
 '@T6G_MB_LIB.T6G(SCH_1):PAGE476_I270@PURE_QUANTA.ISL99390FRZTR5935(CHIPS)':
 'PVCC': CDS_PINID='PVCC';
NET_NAME
'P0V9_RETIMER_CPU0_PWM1'
 '@T6G_MB_LIB.T6G(SCH_1):P0V9_RETIMER_CPU0_PWM1':
 C_SIGNAL='@t6g_mb_lib.t6g(sch_1):p0v9_retimer_cpu0_pwm1';
NODE_NAME     PU6502 8
 '@T6G_MB_LIB.T6G(SCH_1):PAGE475_I42@PURE_QUANTA.ISL69260IRAZT(CHIPS)':
 'PWM7': CDS_PINID='PWM7';
NODE_NAME     PU6503 34
 '@T6G_MB_LIB.T6G(SCH_1):PAGE476_I53@PURE_QUANTA.ISL99390FRZTR5935(CHIPS)':
 'PWM': CDS_PINID='PWM';
NET_NAME
'P0V9_RETIMER_CPU0_PWM2'
 '@T6G_MB_LIB.T6G(SCH_1):P0V9_RETIMER_CPU0_PWM2':
 C_SIGNAL='@t6g_mb_lib.t6g(sch_1):p0v9_retimer_cpu0_pwm2';
NODE_NAME     PU6502 7
 '@T6G_MB_LIB.T6G(SCH_1):PAGE475_I42@PURE_QUANTA.ISL69260IRAZT(CHIPS)':
 'PWM6': CDS_PINID='PWM6';
NODE_NAME     PU6504 34
 '@T6G_MB_LIB.T6G(SCH_1):PAGE476_I270@PURE_QUANTA.ISL99390FRZTR5935(CHIPS)':
 'PWM': CDS_PINID='PWM';
NET_NAME
'P0V9_RETIMER_CPU0_SENSE_R_P'
 '@T6G_MB_LIB.T6G(SCH_1):P0V9_RETIMER_CPU0_SENSE_R_P':
 C_SIGNAL='@t6g_mb_lib.t6g(sch_1):p0v9_retimer_cpu0_sense_r_p';
NODE_NAME     PU6502 21
 '@T6G_MB_LIB.T6G(SCH_1):PAGE475_I42@PURE_QUANTA.ISL69260IRAZT(CHIPS)':
 'VSEN0': CDS_PINID='VSEN0';
NODE_NAME     PR6531 2
 '@T6G_MB_LIB.T6G(SCH_1):PAGE475_I105@PURE_QUANTA.Q_RES(CHIPS)':
 'B': CDS_PINID='B';
NODE_NAME     PC6540 1
 '@T6G_MB_LIB.T6G(SCH_1):PAGE475_I121@PURE_QUANTA.Q_CAP(CHIPS)':
 'A': CDS_PINID='A';
NET_NAME
'P0V9_RETIMER_CPU0_SENSE_SH_N'
 '@T6G_MB_LIB.T6G(SCH_1):P0V9_RETIMER_CPU0_SENSE_SH_N':
 C_SIGNAL='@t6g_mb_lib.t6g(sch_1):p0v9_retimer_cpu0_sense_sh_n';
NODE_NAME     PR6532 1
 '@T6G_MB_LIB.T6G(SCH_1):PAGE475_I32@PURE_QUANTA.Q_RES(CHIPS)':
 'A': CDS_PINID='A';
NODE_NAME     PU6502 22
 '@T6G_MB_LIB.T6G(SCH_1):PAGE475_I42@PURE_QUANTA.ISL69260IRAZT(CHIPS)':
 'RGND0': CDS_PINID='RGND0';
NODE_NAME     PC6540 2
 '@T6G_MB_LIB.T6G(SCH_1):PAGE475_I121@PURE_QUANTA.Q_CAP(CHIPS)':
 'B': CDS_PINID='B';
NODE_NAME     PJ09_P0_N 2
 '@T6G_MB_LIB.T6G(SCH_1):PAGE475_I215@PURE_QUANTA.Q_SHORT(CHIPS)':
 '2': CDS_PINID='\2\';
NET_NAME
'P0V9_RETIMER_CPU0_SENSE_SH_P'
 '@T6G_MB_LIB.T6G(SCH_1):P0V9_RETIMER_CPU0_SENSE_SH_P':
 C_SIGNAL='@t6g_mb_lib.t6g(sch_1):p0v9_retimer_cpu0_sense_sh_p';
NODE_NAME     PR6530 1
 '@T6G_MB_LIB.T6G(SCH_1):PAGE475_I34@PURE_QUANTA.Q_RES(CHIPS)':
 'A': CDS_PINID='A';
NODE_NAME     PR6531 1
 '@T6G_MB_LIB.T6G(SCH_1):PAGE475_I105@PURE_QUANTA.Q_RES(CHIPS)':
 'A': CDS_PINID='A';
NODE_NAME     PJ09_P0_P 2
 '@T6G_MB_LIB.T6G(SCH_1):PAGE475_I214@PURE_QUANTA.Q_SHORT(CHIPS)':
 '2': CDS_PINID='\2\';
NET_NAME
'P0V9_RETIMER_CPU0_SVID_CLK'
 '@T6G_MB_LIB.T6G(SCH_1):P0V9_RETIMER_CPU0_SVID_CLK':
 C_SIGNAL='@t6g_mb_lib.t6g(sch_1):p0v9_retimer_cpu0_svid_clk';
NODE_NAME     PU6502 17
 '@T6G_MB_LIB.T6G(SCH_1):PAGE475_I42@PURE_QUANTA.ISL69260IRAZT(CHIPS)':
 'SVCLK': CDS_PINID='SVCLK';
NODE_NAME     PR6810 1
 '@T6G_MB_LIB.T6G(SCH_1):PAGE475_I165@PURE_QUANTA.Q_RES(CHIPS)':
 'A': CDS_PINID='A';
NODE_NAME     PR6805 2
 '@T6G_MB_LIB.T6G(SCH_1):PAGE475_I166@PURE_QUANTA.Q_RES(CHIPS)':
 'B': CDS_PINID='B';
NET_NAME
'P0V9_RETIMER_CPU0_SVID_SDA'
 '@T6G_MB_LIB.T6G(SCH_1):P0V9_RETIMER_CPU0_SVID_SDA':
 C_SIGNAL='@t6g_mb_lib.t6g(sch_1):p0v9_retimer_cpu0_svid_sda';
NODE_NAME     PU6502 18
 '@T6G_MB_LIB.T6G(SCH_1):PAGE475_I42@PURE_QUANTA.ISL69260IRAZT(CHIPS)':
 'SVDATA': CDS_PINID='SVDATA';
NODE_NAME     PR6803 2
 '@T6G_MB_LIB.T6G(SCH_1):PAGE475_I167@PURE_QUANTA.Q_RES(CHIPS)':
 'B': CDS_PINID='B';
NODE_NAME     PR6819 1
 '@T6G_MB_LIB.T6G(SCH_1):PAGE475_I168@PURE_QUANTA.Q_RES(CHIPS)':
 'A': CDS_PINID='A';
NET_NAME
'P0V9_RETIMER_CPU0_TEMP0'
 '@T6G_MB_LIB.T6G(SCH_1):P0V9_RETIMER_CPU0_TEMP0':
 C_SIGNAL='@t6g_mb_lib.t6g(sch_1):p0v9_retimer_cpu0_temp0';
NODE_NAME     PU6502 35
 '@T6G_MB_LIB.T6G(SCH_1):PAGE475_I42@PURE_QUANTA.ISL69260IRAZT(CHIPS)':
 'TEMP0': CDS_PINID='TEMP0';
NODE_NAME     PR6814 1
 '@T6G_MB_LIB.T6G(SCH_1):PAGE475_I138@PURE_QUANTA.Q_RES(CHIPS)':
 'A': CDS_PINID='A';
NODE_NAME     PC6607 1
 '@T6G_MB_LIB.T6G(SCH_1):PAGE475_I148@PURE_QUANTA.Q_CAP(CHIPS)':
 'A': CDS_PINID='A';
NODE_NAME     PU6503 36
 '@T6G_MB_LIB.T6G(SCH_1):PAGE476_I53@PURE_QUANTA.ISL99390FRZTR5935(CHIPS)':
 'TOUT_FLT': CDS_PINID='TOUT_FLT';
NODE_NAME     PU6504 36
 '@T6G_MB_LIB.T6G(SCH_1):PAGE476_I270@PURE_QUANTA.ISL99390FRZTR5935(CHIPS)':
 'TOUT_FLT': CDS_PINID='TOUT_FLT';
NET_NAME
'P0V9_RETIMER_CPU0_TEMP1_R'
 '@T6G_MB_LIB.T6G(SCH_1):P0V9_RETIMER_CPU0_TEMP1_R':
 C_SIGNAL='@t6g_mb_lib.t6g(sch_1):p0v9_retimer_cpu0_temp1_r';
NODE_NAME     PU6502 36
 '@T6G_MB_LIB.T6G(SCH_1):PAGE475_I42@PURE_QUANTA.ISL69260IRAZT(CHIPS)':
 'TEMP1||ISYS': CDS_PINID='\temp1||isys\';
NODE_NAME     PR6618 1
 '@T6G_MB_LIB.T6G(SCH_1):PAGE475_I204@PURE_QUANTA.Q_RES(CHIPS)':
 'A': CDS_PINID='A';
NET_NAME
'P0V9_RETIMER_CPU0_VCC'
 '@T6G_MB_LIB.T6G(SCH_1):P0V9_RETIMER_CPU0_VCC':
 C_SIGNAL='@t6g_mb_lib.t6g(sch_1):p0v9_retimer_cpu0_vcc';
NODE_NAME     PU6502 39
 '@T6G_MB_LIB.T6G(SCH_1):PAGE475_I42@PURE_QUANTA.ISL69260IRAZT(CHIPS)':
 'VCC': CDS_PINID='VCC';
NODE_NAME     PR6608 1
 '@T6G_MB_LIB.T6G(SCH_1):PAGE475_I131@PURE_QUANTA.Q_RES(CHIPS)':
 'A': CDS_PINID='A';
NODE_NAME     PC6604 1
 '@T6G_MB_LIB.T6G(SCH_1):PAGE475_I132@PURE_QUANTA.Q_CAP(CHIPS)':
 'A': CDS_PINID='A';
NODE_NAME     PC6603 1
 '@T6G_MB_LIB.T6G(SCH_1):PAGE475_I144@PURE_QUANTA.Q_CAP(CHIPS)':
 'A': CDS_PINID='A';
NET_NAME
'P0V9_RETIMER_CPU0_VCC1'
 '@T6G_MB_LIB.T6G(SCH_1):P0V9_RETIMER_CPU0_VCC1':
 C_SIGNAL='@t6g_mb_lib.t6g(sch_1):p0v9_retimer_cpu0_vcc1';
NODE_NAME     PC6552 1
 '@T6G_MB_LIB.T6G(SCH_1):PAGE476_I48@PURE_QUANTA.Q_CAP(CHIPS)':
 'A': CDS_PINID='A';
NODE_NAME     PU6503 35
 '@T6G_MB_LIB.T6G(SCH_1):PAGE476_I53@PURE_QUANTA.ISL99390FRZTR5935(CHIPS)':
 'EN': CDS_PINID='EN';
NODE_NAME     PU6503 3
 '@T6G_MB_LIB.T6G(SCH_1):PAGE476_I53@PURE_QUANTA.ISL99390FRZTR5935(CHIPS)':
 'VCC': CDS_PINID='VCC';
NODE_NAME     PR6552 2
 '@T6G_MB_LIB.T6G(SCH_1):PAGE476_I58@PURE_QUANTA.Q_RES(CHIPS)':
 'B': CDS_PINID='B';
NET_NAME
'P0V9_RETIMER_CPU0_VCC2'
 '@T6G_MB_LIB.T6G(SCH_1):P0V9_RETIMER_CPU0_VCC2':
 C_SIGNAL='@t6g_mb_lib.t6g(sch_1):p0v9_retimer_cpu0_vcc2';
NODE_NAME     PR6560 2
 '@T6G_MB_LIB.T6G(SCH_1):PAGE476_I269@PURE_QUANTA.Q_RES(CHIPS)':
 'B': CDS_PINID='B';
NODE_NAME     PU6504 35
 '@T6G_MB_LIB.T6G(SCH_1):PAGE476_I270@PURE_QUANTA.ISL99390FRZTR5935(CHIPS)':
 'EN': CDS_PINID='EN';
NODE_NAME     PU6504 3
 '@T6G_MB_LIB.T6G(SCH_1):PAGE476_I270@PURE_QUANTA.ISL99390FRZTR5935(CHIPS)':
 'VCC': CDS_PINID='VCC';
NODE_NAME     PC6575 1
 '@T6G_MB_LIB.T6G(SCH_1):PAGE476_I271@PURE_QUANTA.Q_CAP(CHIPS)':
 'A': CDS_PINID='A';
NET_NAME
'P0V9_RETIMER_CPU0_VINSEN'
 '@T6G_MB_LIB.T6G(SCH_1):P0V9_RETIMER_CPU0_VINSEN':
 C_SIGNAL='@t6g_mb_lib.t6g(sch_1):p0v9_retimer_cpu0_vinsen';
NODE_NAME     PU6502 38
 '@T6G_MB_LIB.T6G(SCH_1):PAGE475_I42@PURE_QUANTA.ISL69260IRAZT(CHIPS)':
 'VINSEN||VSYS': CDS_PINID='\vinsen||vsys\';
NODE_NAME     PC6602 1
 '@T6G_MB_LIB.T6G(SCH_1):PAGE475_I123@PURE_QUANTA.Q_CAP(CHIPS)':
 'A': CDS_PINID='A';
NODE_NAME     PR6607 1
 '@T6G_MB_LIB.T6G(SCH_1):PAGE475_I125@PURE_QUANTA.Q_RES(CHIPS)':
 'A': CDS_PINID='A';
NODE_NAME     PR6606 2
 '@T6G_MB_LIB.T6G(SCH_1):PAGE475_I160@PURE_QUANTA.Q_RES(CHIPS)':
 'B': CDS_PINID='B';
NET_NAME
'P0V9_RETIMER_CPU0_VMON'
 '@T6G_MB_LIB.T6G(SCH_1):P0V9_RETIMER_CPU0_VMON':
 C_SIGNAL='@t6g_mb_lib.t6g(sch_1):p0v9_retimer_cpu0_vmon';
NODE_NAME     PU6502 37
 '@T6G_MB_LIB.T6G(SCH_1):PAGE475_I42@PURE_QUANTA.ISL69260IRAZT(CHIPS)':
 'VMON||IINSEN||VSYS||ISYS': CDS_PINID='\vmon||iinsen||vsys||isys\';
NODE_NAME     PR6605 1
 '@T6G_MB_LIB.T6G(SCH_1):PAGE475_I150@PURE_QUANTA.Q_RES(CHIPS)':
 'A': CDS_PINID='A';
NODE_NAME     PC6601 1
 '@T6G_MB_LIB.T6G(SCH_1):PAGE475_I151@PURE_QUANTA.Q_CAP(CHIPS)':
 'A': CDS_PINID='A';
NODE_NAME     PR6807 2
 '@T6G_MB_LIB.T6G(SCH_1):PAGE475_I158@PURE_QUANTA.Q_RES(CHIPS)':
 'B': CDS_PINID='B';
NODE_NAME     PR6604 2
 '@T6G_MB_LIB.T6G(SCH_1):PAGE475_I178@PURE_QUANTA.Q_RES(CHIPS)':
 'B': CDS_PINID='B';
NET_NAME
'P0V9_RETIMER_CPU0_VOS1'
 '@T6G_MB_LIB.T6G(SCH_1):P0V9_RETIMER_CPU0_VOS1':
 C_SIGNAL='@t6g_mb_lib.t6g(sch_1):p0v9_retimer_cpu0_vos1';
NODE_NAME     PR6556 1
 '@T6G_MB_LIB.T6G(SCH_1):PAGE476_I42@PURE_QUANTA.Q_RES(CHIPS)':
 'A': CDS_PINID='A';
NODE_NAME     PU6503 1
 '@T6G_MB_LIB.T6G(SCH_1):PAGE476_I53@PURE_QUANTA.ISL99390FRZTR5935(CHIPS)':
 'VOS': CDS_PINID='VOS';
NET_NAME
'P0V9_RETIMER_CPU0_VOS2'
 '@T6G_MB_LIB.T6G(SCH_1):P0V9_RETIMER_CPU0_VOS2':
 C_SIGNAL='@t6g_mb_lib.t6g(sch_1):p0v9_retimer_cpu0_vos2';
NODE_NAME     PR6564 1
 '@T6G_MB_LIB.T6G(SCH_1):PAGE476_I263@PURE_QUANTA.Q_RES(CHIPS)':
 'A': CDS_PINID='A';
NODE_NAME     PU6504 1
 '@T6G_MB_LIB.T6G(SCH_1):PAGE476_I270@PURE_QUANTA.ISL99390FRZTR5935(CHIPS)':
 'VOS': CDS_PINID='VOS';
NET_NAME
'P0V9_RETIMER_CPU0_VRHOT'
 '@T6G_MB_LIB.T6G(SCH_1):P0V9_RETIMER_CPU0_VRHOT':
 C_SIGNAL='@t6g_mb_lib.t6g(sch_1):p0v9_retimer_cpu0_vrhot';
NODE_NAME     PU6502 14
 '@T6G_MB_LIB.T6G(SCH_1):PAGE475_I42@PURE_QUANTA.ISL69260IRAZT(CHIPS)':
 'NVRHOT#': CDS_PINID='\nvrhot#\';
NODE_NAME     PR6616 1
 '@T6G_MB_LIB.T6G(SCH_1):PAGE475_I136@PURE_QUANTA.Q_RES(CHIPS)':
 'A': CDS_PINID='A';
NET_NAME
'P0V9_RETIMER_CPU1_ADDR'
 '@T6G_MB_LIB.T6G(SCH_1):P0V9_RETIMER_CPU1_ADDR':
 C_SIGNAL='@t6g_mb_lib.t6g(sch_1):p0v9_retimer_cpu1_addr';
NODE_NAME     PR6533 2
 '@T6G_MB_LIB.T6G(SCH_1):PAGE477_I13@PURE_QUANTA.Q_RES(CHIPS)':
 'B': CDS_PINID='B';
NODE_NAME     PU6510 34
 '@T6G_MB_LIB.T6G(SCH_1):PAGE477_I88@PURE_QUANTA.ISL69260IRAZT(CHIPS)':
 'ADDR_CFG': CDS_PINID='ADDR_CFG';
NET_NAME
'P0V9_RETIMER_CPU1_CFP'
 '@T6G_MB_LIB.T6G(SCH_1):P0V9_RETIMER_CPU1_CFP':
 C_SIGNAL='@t6g_mb_lib.t6g(sch_1):p0v9_retimer_cpu1_cfp';
NODE_NAME     R663 2
 '@T6G_MB_LIB.T6G(SCH_1):PAGE477_I15@PURE_QUANTA.Q_RES(CHIPS)':
 'B': CDS_PINID='B';
NODE_NAME     PU6510 33
 '@T6G_MB_LIB.T6G(SCH_1):PAGE477_I88@PURE_QUANTA.ISL69260IRAZT(CHIPS)':
 'CFP': CDS_PINID='CFP';
NET_NAME
'P0V9_RETIMER_CPU1_EN'
 '@T6G_MB_LIB.T6G(SCH_1):P0V9_RETIMER_CPU1_EN':
 C_SIGNAL='@t6g_mb_lib.t6g(sch_1):p0v9_retimer_cpu1_en';
NODE_NAME     R662 1
 '@T6G_MB_LIB.T6G(SCH_1):PAGE477_I38@PURE_QUANTA.Q_RES(CHIPS)':
 'A': CDS_PINID='A';
NODE_NAME     R6855 2
 '@T6G_MB_LIB.T6G(SCH_1):PAGE80_I366@PURE_QUANTA.Q_RES(CHIPS)':
 'B': CDS_PINID='B';
NET_NAME
'P0V9_RETIMER_CPU1_EN0_R'
 '@T6G_MB_LIB.T6G(SCH_1):P0V9_RETIMER_CPU1_EN0_R':
 C_SIGNAL='@t6g_mb_lib.t6g(sch_1):p0v9_retimer_cpu1_en0_r';
NODE_NAME     R662 2
 '@T6G_MB_LIB.T6G(SCH_1):PAGE477_I38@PURE_QUANTA.Q_RES(CHIPS)':
 'B': CDS_PINID='B';
NODE_NAME     PU6510 13
 '@T6G_MB_LIB.T6G(SCH_1):PAGE477_I88@PURE_QUANTA.ISL69260IRAZT(CHIPS)':
 'EN0': CDS_PINID='EN0';
NODE_NAME     R6787 1
 '@T6G_MB_LIB.T6G(SCH_1):PAGE477_I90@PURE_QUANTA.Q_RES(CHIPS)':
 'A': CDS_PINID='A';
NET_NAME
'P0V9_RETIMER_CPU1_EN1_R'
 '@T6G_MB_LIB.T6G(SCH_1):P0V9_RETIMER_CPU1_EN1_R':
 C_SIGNAL='@t6g_mb_lib.t6g(sch_1):p0v9_retimer_cpu1_en1_r';
NODE_NAME     R6800 2
 '@T6G_MB_LIB.T6G(SCH_1):PAGE477_I2@PURE_QUANTA.Q_RES(CHIPS)':
 'B': CDS_PINID='B';
NODE_NAME     PU6510 20
 '@T6G_MB_LIB.T6G(SCH_1):PAGE477_I88@PURE_QUANTA.ISL69260IRAZT(CHIPS)':
 'EN1': CDS_PINID='EN1';
NET_NAME
'P0V9_RETIMER_CPU1_EN_R2'
 '@T6G_MB_LIB.T6G(SCH_1):P0V9_RETIMER_CPU1_EN_R2':
 C_SIGNAL='@t6g_mb_lib.t6g(sch_1):p0v9_retimer_cpu1_en_r2';
NODE_NAME     U18 AA21
 '@T6G_MB_LIB.T6G(SCH_1):PAGE80_I216@PURE_QUANTA.LCMXO3LF9400C5BG484C(CHIPS)':
 'PB46B||SI||SISPI': CDS_PINID='\pb46b||si||sispi\';
NODE_NAME     R6855 1
 '@T6G_MB_LIB.T6G(SCH_1):PAGE80_I366@PURE_QUANTA.Q_RES(CHIPS)':
 'A': CDS_PINID='A';
NET_NAME
'P0V9_RETIMER_CPU1_IMON1'
 '@T6G_MB_LIB.T6G(SCH_1):P0V9_RETIMER_CPU1_IMON1':
 C_SIGNAL='@t6g_mb_lib.t6g(sch_1):p0v9_retimer_cpu1_imon1';
NODE_NAME     PU6510 23
 '@T6G_MB_LIB.T6G(SCH_1):PAGE477_I88@PURE_QUANTA.ISL69260IRAZT(CHIPS)':
 'CS7': CDS_PINID='CS7';
NODE_NAME     PU6511 38
 '@T6G_MB_LIB.T6G(SCH_1):PAGE478_I51@PURE_QUANTA.ISL99390FRZTR5935(CHIPS)':
 'IOUT': CDS_PINID='IOUT';
NET_NAME
'P0V9_RETIMER_CPU1_IMON2'
 '@T6G_MB_LIB.T6G(SCH_1):P0V9_RETIMER_CPU1_IMON2':
 C_SIGNAL='@t6g_mb_lib.t6g(sch_1):p0v9_retimer_cpu1_imon2';
NODE_NAME     PU6510 24
 '@T6G_MB_LIB.T6G(SCH_1):PAGE477_I88@PURE_QUANTA.ISL69260IRAZT(CHIPS)':
 'CS6': CDS_PINID='CS6';
NODE_NAME     PU6512 38
 '@T6G_MB_LIB.T6G(SCH_1):PAGE478_I12@PURE_QUANTA.ISL99390FRZTR5935(CHIPS)':
 'IOUT': CDS_PINID='IOUT';
NET_NAME
'P0V9_RETIMER_CPU1_INALERT'
 '@T6G_MB_LIB.T6G(SCH_1):P0V9_RETIMER_CPU1_INALERT':
 C_SIGNAL='@t6g_mb_lib.t6g(sch_1):p0v9_retimer_cpu1_inalert';
NODE_NAME     R665 2
 '@T6G_MB_LIB.T6G(SCH_1):PAGE477_I14@PURE_QUANTA.Q_RES(CHIPS)':
 'B': CDS_PINID='B';
NODE_NAME     PU6510 15
 '@T6G_MB_LIB.T6G(SCH_1):PAGE477_I88@PURE_QUANTA.ISL69260IRAZT(CHIPS)':
 'NPINALERT#||NPSYSCRIT#': CDS_PINID='\npinalert#||npsyscrit#\';
NET_NAME
'P0V9_RETIMER_CPU1_LSET1'
 '@T6G_MB_LIB.T6G(SCH_1):P0V9_RETIMER_CPU1_LSET1':
 C_SIGNAL='@t6g_mb_lib.t6g(sch_1):p0v9_retimer_cpu1_lset1';
NODE_NAME     PR6622 1
 '@T6G_MB_LIB.T6G(SCH_1):PAGE478_I46@PURE_QUANTA.Q_RES(CHIPS)':
 'A': CDS_PINID='A';
NODE_NAME     PU6511 37
 '@T6G_MB_LIB.T6G(SCH_1):PAGE478_I51@PURE_QUANTA.ISL99390FRZTR5935(CHIPS)':
 'LSET': CDS_PINID='LSET';
NET_NAME
'P0V9_RETIMER_CPU1_LSET2'
 '@T6G_MB_LIB.T6G(SCH_1):P0V9_RETIMER_CPU1_LSET2':
 C_SIGNAL='@t6g_mb_lib.t6g(sch_1):p0v9_retimer_cpu1_lset2';
NODE_NAME     PR6628 1
 '@T6G_MB_LIB.T6G(SCH_1):PAGE478_I5@PURE_QUANTA.Q_RES(CHIPS)':
 'A': CDS_PINID='A';
NODE_NAME     PU6512 37
 '@T6G_MB_LIB.T6G(SCH_1):PAGE478_I12@PURE_QUANTA.ISL99390FRZTR5935(CHIPS)':
 'LSET': CDS_PINID='LSET';
NET_NAME
'P0V9_RETIMER_CPU1_PMSCL'
 '@T6G_MB_LIB.T6G(SCH_1):P0V9_RETIMER_CPU1_PMSCL':
 C_SIGNAL='@t6g_mb_lib.t6g(sch_1):p0v9_retimer_cpu1_pmscl';
NODE_NAME     R657 1
 '@T6G_MB_LIB.T6G(SCH_1):PAGE477_I33@PURE_QUANTA.Q_RES(CHIPS)':
 'A': CDS_PINID='A';
NODE_NAME     R6858 2
 '@T6G_MB_LIB.T6G(SCH_1):PAGE349_I207@PURE_QUANTA.Q_RES(CHIPS)':
 'B': CDS_PINID='B';
NET_NAME
'P0V9_RETIMER_CPU1_PMSCL_R'
 '@T6G_MB_LIB.T6G(SCH_1):P0V9_RETIMER_CPU1_PMSCL_R':
 C_SIGNAL='@t6g_mb_lib.t6g(sch_1):p0v9_retimer_cpu1_pmscl_r';
NODE_NAME     R657 2
 '@T6G_MB_LIB.T6G(SCH_1):PAGE477_I33@PURE_QUANTA.Q_RES(CHIPS)':
 'B': CDS_PINID='B';
NODE_NAME     PU6510 10
 '@T6G_MB_LIB.T6G(SCH_1):PAGE477_I88@PURE_QUANTA.ISL69260IRAZT(CHIPS)':
 'PMSCL': CDS_PINID='PMSCL';
NET_NAME
'P0V9_RETIMER_CPU1_PMSDA'
 '@T6G_MB_LIB.T6G(SCH_1):P0V9_RETIMER_CPU1_PMSDA':
 C_SIGNAL='@t6g_mb_lib.t6g(sch_1):p0v9_retimer_cpu1_pmsda';
NODE_NAME     R658 1
 '@T6G_MB_LIB.T6G(SCH_1):PAGE477_I31@PURE_QUANTA.Q_RES(CHIPS)':
 'A': CDS_PINID='A';
NODE_NAME     R6859 2
 '@T6G_MB_LIB.T6G(SCH_1):PAGE349_I206@PURE_QUANTA.Q_RES(CHIPS)':
 'B': CDS_PINID='B';
NET_NAME
'P0V9_RETIMER_CPU1_PMSDA_R'
 '@T6G_MB_LIB.T6G(SCH_1):P0V9_RETIMER_CPU1_PMSDA_R':
 C_SIGNAL='@t6g_mb_lib.t6g(sch_1):p0v9_retimer_cpu1_pmsda_r';
NODE_NAME     R658 2
 '@T6G_MB_LIB.T6G(SCH_1):PAGE477_I31@PURE_QUANTA.Q_RES(CHIPS)':
 'B': CDS_PINID='B';
NODE_NAME     PU6510 9
 '@T6G_MB_LIB.T6G(SCH_1):PAGE477_I88@PURE_QUANTA.ISL69260IRAZT(CHIPS)':
 'PMSDA': CDS_PINID='PMSDA';
NET_NAME
'P0V9_RETIMER_CPU1_PVCC'
 '@T6G_MB_LIB.T6G(SCH_1):P0V9_RETIMER_CPU1_PVCC':
 C_SIGNAL='@t6g_mb_lib.t6g(sch_1):p0v9_retimer_cpu1_pvcc',
 CDS_GLOBAL_NET='TRUE';
NODE_NAME     PR6627 1
 '@T6G_MB_LIB.T6G(SCH_1):PAGE478_I11@PURE_QUANTA.Q_RES(CHIPS)':
 'A': CDS_PINID='A';
NODE_NAME     PU6512 4
 '@T6G_MB_LIB.T6G(SCH_1):PAGE478_I12@PURE_QUANTA.ISL99390FRZTR5935(CHIPS)':
 'PVCC': CDS_PINID='PVCC';
NODE_NAME     PC6644_09P1_2 1
 '@T6G_MB_LIB.T6G(SCH_1):PAGE478_I14@PURE_QUANTA.Q_CAP(CHIPS)':
 'A': CDS_PINID='A';
NODE_NAME     PR6619 2
 '@T6G_MB_LIB.T6G(SCH_1):PAGE478_I42@PURE_QUANTA.Q_RES(CHIPS)':
 'B': CDS_PINID='B';
NODE_NAME     PU6511 4
 '@T6G_MB_LIB.T6G(SCH_1):PAGE478_I51@PURE_QUANTA.ISL99390FRZTR5935(CHIPS)':
 'PVCC': CDS_PINID='PVCC';
NODE_NAME     PR6621 1
 '@T6G_MB_LIB.T6G(SCH_1):PAGE478_I53@PURE_QUANTA.Q_RES(CHIPS)':
 'A': CDS_PINID='A';
NODE_NAME     PC6609_09P1_1 1
 '@T6G_MB_LIB.T6G(SCH_1):PAGE478_I55@PURE_QUANTA.Q_CAP(CHIPS)':
 'A': CDS_PINID='A';
NODE_NAME     PR6620 2
 '@T6G_MB_LIB.T6G(SCH_1):PAGE478_I56@PURE_QUANTA.Q_RES(CHIPS)':
 'B': CDS_PINID='B';
NET_NAME
'P0V9_RETIMER_CPU1_PWM1'
 '@T6G_MB_LIB.T6G(SCH_1):P0V9_RETIMER_CPU1_PWM1':
 C_SIGNAL='@t6g_mb_lib.t6g(sch_1):p0v9_retimer_cpu1_pwm1';
NODE_NAME     PU6510 8
 '@T6G_MB_LIB.T6G(SCH_1):PAGE477_I88@PURE_QUANTA.ISL69260IRAZT(CHIPS)':
 'PWM7': CDS_PINID='PWM7';
NODE_NAME     PU6511 34
 '@T6G_MB_LIB.T6G(SCH_1):PAGE478_I51@PURE_QUANTA.ISL99390FRZTR5935(CHIPS)':
 'PWM': CDS_PINID='PWM';
NET_NAME
'P0V9_RETIMER_CPU1_PWM2'
 '@T6G_MB_LIB.T6G(SCH_1):P0V9_RETIMER_CPU1_PWM2':
 C_SIGNAL='@t6g_mb_lib.t6g(sch_1):p0v9_retimer_cpu1_pwm2';
NODE_NAME     PU6510 7
 '@T6G_MB_LIB.T6G(SCH_1):PAGE477_I88@PURE_QUANTA.ISL69260IRAZT(CHIPS)':
 'PWM6': CDS_PINID='PWM6';
NODE_NAME     PU6512 34
 '@T6G_MB_LIB.T6G(SCH_1):PAGE478_I12@PURE_QUANTA.ISL99390FRZTR5935(CHIPS)':
 'PWM': CDS_PINID='PWM';
NET_NAME
'P0V9_RETIMER_CPU1_SENSE_R_P'
 '@T6G_MB_LIB.T6G(SCH_1):P0V9_RETIMER_CPU1_SENSE_R_P':
 C_SIGNAL='@t6g_mb_lib.t6g(sch_1):p0v9_retimer_cpu1_sense_r_p';
NODE_NAME     PR6601 2
 '@T6G_MB_LIB.T6G(SCH_1):PAGE477_I27@PURE_QUANTA.Q_RES(CHIPS)':
 'B': CDS_PINID='B';
NODE_NAME     PC6600 1
 '@T6G_MB_LIB.T6G(SCH_1):PAGE477_I28@PURE_QUANTA.Q_CAP(CHIPS)':
 'A': CDS_PINID='A';
NODE_NAME     PU6510 21
 '@T6G_MB_LIB.T6G(SCH_1):PAGE477_I88@PURE_QUANTA.ISL69260IRAZT(CHIPS)':
 'VSEN0': CDS_PINID='VSEN0';
NET_NAME
'P0V9_RETIMER_CPU1_SENSE_SH_N'
 '@T6G_MB_LIB.T6G(SCH_1):P0V9_RETIMER_CPU1_SENSE_SH_N':
 C_SIGNAL='@t6g_mb_lib.t6g(sch_1):p0v9_retimer_cpu1_sense_sh_n';
NODE_NAME     PR6602 1
 '@T6G_MB_LIB.T6G(SCH_1):PAGE477_I22@PURE_QUANTA.Q_RES(CHIPS)':
 'A': CDS_PINID='A';
NODE_NAME     PC6600 2
 '@T6G_MB_LIB.T6G(SCH_1):PAGE477_I28@PURE_QUANTA.Q_CAP(CHIPS)':
 'B': CDS_PINID='B';
NODE_NAME     PU6510 22
 '@T6G_MB_LIB.T6G(SCH_1):PAGE477_I88@PURE_QUANTA.ISL69260IRAZT(CHIPS)':
 'RGND0': CDS_PINID='RGND0';
NODE_NAME     PJ09_P1_N 2
 '@T6G_MB_LIB.T6G(SCH_1):PAGE477_I96@PURE_QUANTA.Q_SHORT(CHIPS)':
 '2': CDS_PINID='\2\';
NET_NAME
'P0V9_RETIMER_CPU1_SENSE_SH_P'
 '@T6G_MB_LIB.T6G(SCH_1):P0V9_RETIMER_CPU1_SENSE_SH_P':
 C_SIGNAL='@t6g_mb_lib.t6g(sch_1):p0v9_retimer_cpu1_sense_sh_p';
NODE_NAME     PR6600 1
 '@T6G_MB_LIB.T6G(SCH_1):PAGE477_I23@PURE_QUANTA.Q_RES(CHIPS)':
 'A': CDS_PINID='A';
NODE_NAME     PR6601 1
 '@T6G_MB_LIB.T6G(SCH_1):PAGE477_I27@PURE_QUANTA.Q_RES(CHIPS)':
 'A': CDS_PINID='A';
NODE_NAME     PJ09_P1_P 2
 '@T6G_MB_LIB.T6G(SCH_1):PAGE477_I95@PURE_QUANTA.Q_SHORT(CHIPS)':
 '2': CDS_PINID='\2\';
NET_NAME
'P0V9_RETIMER_CPU1_SVID_CLK'
 '@T6G_MB_LIB.T6G(SCH_1):P0V9_RETIMER_CPU1_SVID_CLK':
 C_SIGNAL='@t6g_mb_lib.t6g(sch_1):p0v9_retimer_cpu1_svid_clk';
NODE_NAME     PR6806 2
 '@T6G_MB_LIB.T6G(SCH_1):PAGE477_I37@PURE_QUANTA.Q_RES(CHIPS)':
 'B': CDS_PINID='B';
NODE_NAME     PR6811 1
 '@T6G_MB_LIB.T6G(SCH_1):PAGE477_I42@PURE_QUANTA.Q_RES(CHIPS)':
 'A': CDS_PINID='A';
NODE_NAME     PU6510 17
 '@T6G_MB_LIB.T6G(SCH_1):PAGE477_I88@PURE_QUANTA.ISL69260IRAZT(CHIPS)':
 'SVCLK': CDS_PINID='SVCLK';
NET_NAME
'P0V9_RETIMER_CPU1_SVID_SDA'
 '@T6G_MB_LIB.T6G(SCH_1):P0V9_RETIMER_CPU1_SVID_SDA':
 C_SIGNAL='@t6g_mb_lib.t6g(sch_1):p0v9_retimer_cpu1_svid_sda';
NODE_NAME     PR6804 2
 '@T6G_MB_LIB.T6G(SCH_1):PAGE477_I36@PURE_QUANTA.Q_RES(CHIPS)':
 'B': CDS_PINID='B';
NODE_NAME     PR6820 1
 '@T6G_MB_LIB.T6G(SCH_1):PAGE477_I43@PURE_QUANTA.Q_RES(CHIPS)':
 'A': CDS_PINID='A';
NODE_NAME     PU6510 18
 '@T6G_MB_LIB.T6G(SCH_1):PAGE477_I88@PURE_QUANTA.ISL69260IRAZT(CHIPS)':
 'SVDATA': CDS_PINID='SVDATA';
NET_NAME
'P0V9_RETIMER_CPU1_TEMP0'
 '@T6G_MB_LIB.T6G(SCH_1):P0V9_RETIMER_CPU1_TEMP0':
 C_SIGNAL='@t6g_mb_lib.t6g(sch_1):p0v9_retimer_cpu1_temp0';
NODE_NAME     PC523 1
 '@T6G_MB_LIB.T6G(SCH_1):PAGE477_I51@PURE_QUANTA.Q_CAP(CHIPS)':
 'A': CDS_PINID='A';
NODE_NAME     PR6815 1
 '@T6G_MB_LIB.T6G(SCH_1):PAGE477_I54@PURE_QUANTA.Q_RES(CHIPS)':
 'A': CDS_PINID='A';
NODE_NAME     PU6510 35
 '@T6G_MB_LIB.T6G(SCH_1):PAGE477_I88@PURE_QUANTA.ISL69260IRAZT(CHIPS)':
 'TEMP0': CDS_PINID='TEMP0';
NODE_NAME     PU6512 36
 '@T6G_MB_LIB.T6G(SCH_1):PAGE478_I12@PURE_QUANTA.ISL99390FRZTR5935(CHIPS)':
 'TOUT_FLT': CDS_PINID='TOUT_FLT';
NODE_NAME     PU6511 36
 '@T6G_MB_LIB.T6G(SCH_1):PAGE478_I51@PURE_QUANTA.ISL99390FRZTR5935(CHIPS)':
 'TOUT_FLT': CDS_PINID='TOUT_FLT';
NET_NAME
'P0V9_RETIMER_CPU1_TEMP1_R'
 '@T6G_MB_LIB.T6G(SCH_1):P0V9_RETIMER_CPU1_TEMP1_R':
 C_SIGNAL='@t6g_mb_lib.t6g(sch_1):p0v9_retimer_cpu1_temp1_r';
NODE_NAME     PR6548 1
 '@T6G_MB_LIB.T6G(SCH_1):PAGE477_I52@PURE_QUANTA.Q_RES(CHIPS)':
 'A': CDS_PINID='A';
NODE_NAME     PU6510 36
 '@T6G_MB_LIB.T6G(SCH_1):PAGE477_I88@PURE_QUANTA.ISL69260IRAZT(CHIPS)':
 'TEMP1||ISYS': CDS_PINID='\temp1||isys\';
NET_NAME
'P0V9_RETIMER_CPU1_VCC'
 '@T6G_MB_LIB.T6G(SCH_1):P0V9_RETIMER_CPU1_VCC':
 C_SIGNAL='@t6g_mb_lib.t6g(sch_1):p0v9_retimer_cpu1_vcc';
NODE_NAME     PC6543 1
 '@T6G_MB_LIB.T6G(SCH_1):PAGE477_I74@PURE_QUANTA.Q_CAP(CHIPS)':
 'A': CDS_PINID='A';
NODE_NAME     PC6544 1
 '@T6G_MB_LIB.T6G(SCH_1):PAGE477_I75@PURE_QUANTA.Q_CAP(CHIPS)':
 'A': CDS_PINID='A';
NODE_NAME     PR6538 1
 '@T6G_MB_LIB.T6G(SCH_1):PAGE477_I83@PURE_QUANTA.Q_RES(CHIPS)':
 'A': CDS_PINID='A';
NODE_NAME     PU6510 39
 '@T6G_MB_LIB.T6G(SCH_1):PAGE477_I88@PURE_QUANTA.ISL69260IRAZT(CHIPS)':
 'VCC': CDS_PINID='VCC';
NET_NAME
'P0V9_RETIMER_CPU1_VCC1'
 '@T6G_MB_LIB.T6G(SCH_1):P0V9_RETIMER_CPU1_VCC1':
 C_SIGNAL='@t6g_mb_lib.t6g(sch_1):p0v9_retimer_cpu1_vcc1';
NODE_NAME     PU6511 35
 '@T6G_MB_LIB.T6G(SCH_1):PAGE478_I51@PURE_QUANTA.ISL99390FRZTR5935(CHIPS)':
 'EN': CDS_PINID='EN';
NODE_NAME     PU6511 3
 '@T6G_MB_LIB.T6G(SCH_1):PAGE478_I51@PURE_QUANTA.ISL99390FRZTR5935(CHIPS)':
 'VCC': CDS_PINID='VCC';
NODE_NAME     PC6610 1
 '@T6G_MB_LIB.T6G(SCH_1):PAGE478_I52@PURE_QUANTA.Q_CAP(CHIPS)':
 'A': CDS_PINID='A';
NODE_NAME     PR6621 2
 '@T6G_MB_LIB.T6G(SCH_1):PAGE478_I53@PURE_QUANTA.Q_RES(CHIPS)':
 'B': CDS_PINID='B';
NET_NAME
'P0V9_RETIMER_CPU1_VCC2'
 '@T6G_MB_LIB.T6G(SCH_1):P0V9_RETIMER_CPU1_VCC2':
 C_SIGNAL='@t6g_mb_lib.t6g(sch_1):p0v9_retimer_cpu1_vcc2';
NODE_NAME     PC6645 1
 '@T6G_MB_LIB.T6G(SCH_1):PAGE478_I10@PURE_QUANTA.Q_CAP(CHIPS)':
 'A': CDS_PINID='A';
NODE_NAME     PR6627 2
 '@T6G_MB_LIB.T6G(SCH_1):PAGE478_I11@PURE_QUANTA.Q_RES(CHIPS)':
 'B': CDS_PINID='B';
NODE_NAME     PU6512 35
 '@T6G_MB_LIB.T6G(SCH_1):PAGE478_I12@PURE_QUANTA.ISL99390FRZTR5935(CHIPS)':
 'EN': CDS_PINID='EN';
NODE_NAME     PU6512 3
 '@T6G_MB_LIB.T6G(SCH_1):PAGE478_I12@PURE_QUANTA.ISL99390FRZTR5935(CHIPS)':
 'VCC': CDS_PINID='VCC';
NET_NAME
'P0V9_RETIMER_CPU1_VINSEN'
 '@T6G_MB_LIB.T6G(SCH_1):P0V9_RETIMER_CPU1_VINSEN':
 C_SIGNAL='@t6g_mb_lib.t6g(sch_1):p0v9_retimer_cpu1_vinsen';
NODE_NAME     PR6809 2
 '@T6G_MB_LIB.T6G(SCH_1):PAGE477_I10@PURE_QUANTA.Q_RES(CHIPS)':
 'B': CDS_PINID='B';
NODE_NAME     PR6813 1
 '@T6G_MB_LIB.T6G(SCH_1):PAGE477_I46@PURE_QUANTA.Q_RES(CHIPS)':
 'A': CDS_PINID='A';
NODE_NAME     PC819 1
 '@T6G_MB_LIB.T6G(SCH_1):PAGE477_I48@PURE_QUANTA.Q_CAP(CHIPS)':
 'A': CDS_PINID='A';
NODE_NAME     PU6510 38
 '@T6G_MB_LIB.T6G(SCH_1):PAGE477_I88@PURE_QUANTA.ISL69260IRAZT(CHIPS)':
 'VINSEN||VSYS': CDS_PINID='\vinsen||vsys\';
NET_NAME
'P0V9_RETIMER_CPU1_VMON'
 '@T6G_MB_LIB.T6G(SCH_1):P0V9_RETIMER_CPU1_VMON':
 C_SIGNAL='@t6g_mb_lib.t6g(sch_1):p0v9_retimer_cpu1_vmon';
NODE_NAME     PR6821 1
 '@T6G_MB_LIB.T6G(SCH_1):PAGE477_I3@PURE_QUANTA.Q_RES(CHIPS)':
 'A': CDS_PINID='A';
NODE_NAME     PC514 1
 '@T6G_MB_LIB.T6G(SCH_1):PAGE477_I5@PURE_QUANTA.Q_CAP(CHIPS)':
 'A': CDS_PINID='A';
NODE_NAME     PR885 2
 '@T6G_MB_LIB.T6G(SCH_1):PAGE477_I7@PURE_QUANTA.Q_RES(CHIPS)':
 'B': CDS_PINID='B';
NODE_NAME     PR6808 2
 '@T6G_MB_LIB.T6G(SCH_1):PAGE477_I11@PURE_QUANTA.Q_RES(CHIPS)':
 'B': CDS_PINID='B';
NODE_NAME     PU6510 37
 '@T6G_MB_LIB.T6G(SCH_1):PAGE477_I88@PURE_QUANTA.ISL69260IRAZT(CHIPS)':
 'VMON||IINSEN||VSYS||ISYS': CDS_PINID='\vmon||iinsen||vsys||isys\';
NET_NAME
'P0V9_RETIMER_CPU1_VOS1'
 '@T6G_MB_LIB.T6G(SCH_1):P0V9_RETIMER_CPU1_VOS1':
 C_SIGNAL='@t6g_mb_lib.t6g(sch_1):p0v9_retimer_cpu1_vos1';
NODE_NAME     PU6511 1
 '@T6G_MB_LIB.T6G(SCH_1):PAGE478_I51@PURE_QUANTA.ISL99390FRZTR5935(CHIPS)':
 'VOS': CDS_PINID='VOS';
NODE_NAME     PR6626 1
 '@T6G_MB_LIB.T6G(SCH_1):PAGE478_I59@PURE_QUANTA.Q_RES(CHIPS)':
 'A': CDS_PINID='A';
NET_NAME
'P0V9_RETIMER_CPU1_VOS2'
 '@T6G_MB_LIB.T6G(SCH_1):P0V9_RETIMER_CPU1_VOS2':
 C_SIGNAL='@t6g_mb_lib.t6g(sch_1):p0v9_retimer_cpu1_vos2';
NODE_NAME     PU6512 1
 '@T6G_MB_LIB.T6G(SCH_1):PAGE478_I12@PURE_QUANTA.ISL99390FRZTR5935(CHIPS)':
 'VOS': CDS_PINID='VOS';
NODE_NAME     PR6631 1
 '@T6G_MB_LIB.T6G(SCH_1):PAGE478_I16@PURE_QUANTA.Q_RES(CHIPS)':
 'A': CDS_PINID='A';
NET_NAME
'P0V9_RETIMER_CPU1_VRHOT'
 '@T6G_MB_LIB.T6G(SCH_1):P0V9_RETIMER_CPU1_VRHOT':
 C_SIGNAL='@t6g_mb_lib.t6g(sch_1):p0v9_retimer_cpu1_vrhot';
NODE_NAME     PR6816 1
 '@T6G_MB_LIB.T6G(SCH_1):PAGE477_I56@PURE_QUANTA.Q_RES(CHIPS)':
 'A': CDS_PINID='A';
NODE_NAME     PU6510 14
 '@T6G_MB_LIB.T6G(SCH_1):PAGE477_I88@PURE_QUANTA.ISL69260IRAZT(CHIPS)':
 'NVRHOT#': CDS_PINID='\nvrhot#\';
NET_NAME
'P12V_ALL_PWROK'
 '@T6G_MB_LIB.T6G(SCH_1):P12V_ALL_PWROK':
 C_SIGNAL='@t6g_mb_lib.t6g(sch_1):p12v_all_pwrok';
NODE_NAME     Q12 G
 '@T6G_MB_LIB.T6G(SCH_1):PAGE143_I44@PURE_QUANTA.MOSFET_N_GSD(CHIPS)':
 'GATE': CDS_PINID='GATE';
NODE_NAME     R372 2
 '@T6G_MB_LIB.T6G(SCH_1):PAGE80_I159@PURE_QUANTA.Q_RES(CHIPS)':
 'B': CDS_PINID='B';
NET_NAME
'P12V_ALL_PWROK_N'
 '@T6G_MB_LIB.T6G(SCH_1):P12V_ALL_PWROK_N':
 C_SIGNAL='@t6g_mb_lib.t6g(sch_1):p12v_all_pwrok_n';
NODE_NAME     D46 C
 '@T6G_MB_LIB.T6G(SCH_1):PAGE143_I43@PURE_QUANTA.Q_LED(CHIPS)':
 'C': CDS_PINID='C';
NODE_NAME     Q12 D
 '@T6G_MB_LIB.T6G(SCH_1):PAGE143_I44@PURE_QUANTA.MOSFET_N_GSD(CHIPS)':
 'DRAIN': CDS_PINID='DRAIN';
NET_NAME
'P12V_ALL_PWROK_R'
 '@T6G_MB_LIB.T6G(SCH_1):P12V_ALL_PWROK_R':
 C_SIGNAL='@t6g_mb_lib.t6g(sch_1):p12v_all_pwrok_r';
NODE_NAME     R372 1
 '@T6G_MB_LIB.T6G(SCH_1):PAGE80_I159@PURE_QUANTA.Q_RES(CHIPS)':
 'A': CDS_PINID='A';
NODE_NAME     U18 T18
 '@T6G_MB_LIB.T6G(SCH_1):PAGE80_I217@PURE_QUANTA.LCMXO3LF9400C5BG484C(CHIPS)':
 'PR27B': CDS_PINID='PR27B';
NET_NAME
'P12V_AUX'
 '@T6G_MB_LIB.T6G(SCH_1):P12V_AUX':
 C_SIGNAL='@t6g_mb_lib.t6g(sch_1):p12v_aux',
 CDS_GLOBAL_NET='TRUE';
NODE_NAME     PC6002 1
 '@T6G_MB_LIB.T6G(SCH_1):PAGE201_I3@PURE_QUANTA.Q_CAP(CHIPS)':
 'A': CDS_PINID='A';
NODE_NAME     PL56 2
 '@T6G_MB_LIB.T6G(SCH_1):PAGE200_I84@PURE_QUANTA.Q_INDUCTOR(CHIPS)':
 '2': CDS_PINID='\2\';
NODE_NAME     PC85 1
 '@T6G_MB_LIB.T6G(SCH_1):PAGE176_I87@PURE_QUANTA.Q_CAP(CHIPS)':
 'A': CDS_PINID='A';
NODE_NAME     PC6003 1
 '@T6G_MB_LIB.T6G(SCH_1):PAGE183_I79@PURE_QUANTA.Q_CAP(CHIPS)':
 'A': CDS_PINID='A';
NODE_NAME     PR181 1
 '@T6G_MB_LIB.T6G(SCH_1):PAGE185_I47@PURE_QUANTA.Q_RES(CHIPS)':
 'A': CDS_PINID='A';
NODE_NAME     R3117 1
 '@T6G_MB_LIB.T6G(SCH_1):PAGE245_I4@PURE_QUANTA.Q_RES(CHIPS)':
 'A': CDS_PINID='A';
NODE_NAME     PU9 3
 '@T6G_MB_LIB.T6G(SCH_1):PAGE245_I21@PURE_QUANTA.NCP3284AMNTXG(CHIPS)':
 'VIN': CDS_PINID='VIN';
NODE_NAME     PC1649 1
 '@T6G_MB_LIB.T6G(SCH_1):PAGE245_I23@PURE_QUANTA.Q_CAP(CHIPS)':
 'A': CDS_PINID='A';
NODE_NAME     PU288 1
 '@T6G_MB_LIB.T6G(SCH_1):PAGE301_I16@PURE_QUANTA.MP5991GLUZ(CHIPS)':
 'VOUT1': CDS_PINID='VOUT1';
NODE_NAME     PU288 2
 '@T6G_MB_LIB.T6G(SCH_1):PAGE301_I16@PURE_QUANTA.MP5991GLUZ(CHIPS)':
 'VOUT2': CDS_PINID='VOUT2';
NODE_NAME     PU288 25
 '@T6G_MB_LIB.T6G(SCH_1):PAGE301_I16@PURE_QUANTA.MP5991GLUZ(CHIPS)':
 'VOUT3': CDS_PINID='VOUT3';
NODE_NAME     PU288 26
 '@T6G_MB_LIB.T6G(SCH_1):PAGE301_I16@PURE_QUANTA.MP5991GLUZ(CHIPS)':
 'VOUT4': CDS_PINID='VOUT4';
NODE_NAME     PU288 27
 '@T6G_MB_LIB.T6G(SCH_1):PAGE301_I16@PURE_QUANTA.MP5991GLUZ(CHIPS)':
 'VOUT5': CDS_PINID='VOUT5';
NODE_NAME     PU288 28
 '@T6G_MB_LIB.T6G(SCH_1):PAGE301_I16@PURE_QUANTA.MP5991GLUZ(CHIPS)':
 'VOUT6': CDS_PINID='VOUT6';
NODE_NAME     PU288 29
 '@T6G_MB_LIB.T6G(SCH_1):PAGE301_I16@PURE_QUANTA.MP5991GLUZ(CHIPS)':
 'VOUT7': CDS_PINID='VOUT7';
NODE_NAME     PU288 30
 '@T6G_MB_LIB.T6G(SCH_1):PAGE301_I16@PURE_QUANTA.MP5991GLUZ(CHIPS)':
 'VOUT8': CDS_PINID='VOUT8';
NODE_NAME     PU288 31
 '@T6G_MB_LIB.T6G(SCH_1):PAGE301_I16@PURE_QUANTA.MP5991GLUZ(CHIPS)':
 'VOUT9': CDS_PINID='VOUT9';
NODE_NAME     PU288 32
 '@T6G_MB_LIB.T6G(SCH_1):PAGE301_I16@PURE_QUANTA.MP5991GLUZ(CHIPS)':
 'VOUT10': CDS_PINID='VOUT10';
NODE_NAME     PU287 1
 '@T6G_MB_LIB.T6G(SCH_1):PAGE301_I35@PURE_QUANTA.MP5991GLUZ(CHIPS)':
 'VOUT1': CDS_PINID='VOUT1';
NODE_NAME     PU287 2
 '@T6G_MB_LIB.T6G(SCH_1):PAGE301_I35@PURE_QUANTA.MP5991GLUZ(CHIPS)':
 'VOUT2': CDS_PINID='VOUT2';
NODE_NAME     PU287 25
 '@T6G_MB_LIB.T6G(SCH_1):PAGE301_I35@PURE_QUANTA.MP5991GLUZ(CHIPS)':
 'VOUT3': CDS_PINID='VOUT3';
NODE_NAME     PU287 26
 '@T6G_MB_LIB.T6G(SCH_1):PAGE301_I35@PURE_QUANTA.MP5991GLUZ(CHIPS)':
 'VOUT4': CDS_PINID='VOUT4';
NODE_NAME     PU287 27
 '@T6G_MB_LIB.T6G(SCH_1):PAGE301_I35@PURE_QUANTA.MP5991GLUZ(CHIPS)':
 'VOUT5': CDS_PINID='VOUT5';
NODE_NAME     PU287 28
 '@T6G_MB_LIB.T6G(SCH_1):PAGE301_I35@PURE_QUANTA.MP5991GLUZ(CHIPS)':
 'VOUT6': CDS_PINID='VOUT6';
NODE_NAME     PU287 29
 '@T6G_MB_LIB.T6G(SCH_1):PAGE301_I35@PURE_QUANTA.MP5991GLUZ(CHIPS)':
 'VOUT7': CDS_PINID='VOUT7';
NODE_NAME     PU287 30
 '@T6G_MB_LIB.T6G(SCH_1):PAGE301_I35@PURE_QUANTA.MP5991GLUZ(CHIPS)':
 'VOUT8': CDS_PINID='VOUT8';
NODE_NAME     PU287 31
 '@T6G_MB_LIB.T6G(SCH_1):PAGE301_I35@PURE_QUANTA.MP5991GLUZ(CHIPS)':
 'VOUT9': CDS_PINID='VOUT9';
NODE_NAME     PU287 32
 '@T6G_MB_LIB.T6G(SCH_1):PAGE301_I35@PURE_QUANTA.MP5991GLUZ(CHIPS)':
 'VOUT10': CDS_PINID='VOUT10';
NODE_NAME     PU297 1
 '@T6G_MB_LIB.T6G(SCH_1):PAGE325_I17@PURE_QUANTA.MP5991GLUZ(CHIPS)':
 'VOUT1': CDS_PINID='VOUT1';
NODE_NAME     PU297 2
 '@T6G_MB_LIB.T6G(SCH_1):PAGE325_I17@PURE_QUANTA.MP5991GLUZ(CHIPS)':
 'VOUT2': CDS_PINID='VOUT2';
NODE_NAME     PU297 25
 '@T6G_MB_LIB.T6G(SCH_1):PAGE325_I17@PURE_QUANTA.MP5991GLUZ(CHIPS)':
 'VOUT3': CDS_PINID='VOUT3';
NODE_NAME     PU297 26
 '@T6G_MB_LIB.T6G(SCH_1):PAGE325_I17@PURE_QUANTA.MP5991GLUZ(CHIPS)':
 'VOUT4': CDS_PINID='VOUT4';
NODE_NAME     PU297 27
 '@T6G_MB_LIB.T6G(SCH_1):PAGE325_I17@PURE_QUANTA.MP5991GLUZ(CHIPS)':
 'VOUT5': CDS_PINID='VOUT5';
NODE_NAME     PU297 28
 '@T6G_MB_LIB.T6G(SCH_1):PAGE325_I17@PURE_QUANTA.MP5991GLUZ(CHIPS)':
 'VOUT6': CDS_PINID='VOUT6';
NODE_NAME     PU297 29
 '@T6G_MB_LIB.T6G(SCH_1):PAGE325_I17@PURE_QUANTA.MP5991GLUZ(CHIPS)':
 'VOUT7': CDS_PINID='VOUT7';
NODE_NAME     PU297 30
 '@T6G_MB_LIB.T6G(SCH_1):PAGE325_I17@PURE_QUANTA.MP5991GLUZ(CHIPS)':
 'VOUT8': CDS_PINID='VOUT8';
NODE_NAME     PU297 31
 '@T6G_MB_LIB.T6G(SCH_1):PAGE325_I17@PURE_QUANTA.MP5991GLUZ(CHIPS)':
 'VOUT9': CDS_PINID='VOUT9';
NODE_NAME     PU297 32
 '@T6G_MB_LIB.T6G(SCH_1):PAGE325_I17@PURE_QUANTA.MP5991GLUZ(CHIPS)':
 'VOUT10': CDS_PINID='VOUT10';
NODE_NAME     PU296 1
 '@T6G_MB_LIB.T6G(SCH_1):PAGE325_I35@PURE_QUANTA.MP5991GLUZ(CHIPS)':
 'VOUT1': CDS_PINID='VOUT1';
NODE_NAME     PU296 2
 '@T6G_MB_LIB.T6G(SCH_1):PAGE325_I35@PURE_QUANTA.MP5991GLUZ(CHIPS)':
 'VOUT2': CDS_PINID='VOUT2';
NODE_NAME     PU296 25
 '@T6G_MB_LIB.T6G(SCH_1):PAGE325_I35@PURE_QUANTA.MP5991GLUZ(CHIPS)':
 'VOUT3': CDS_PINID='VOUT3';
NODE_NAME     PU296 26
 '@T6G_MB_LIB.T6G(SCH_1):PAGE325_I35@PURE_QUANTA.MP5991GLUZ(CHIPS)':
 'VOUT4': CDS_PINID='VOUT4';
NODE_NAME     PU296 27
 '@T6G_MB_LIB.T6G(SCH_1):PAGE325_I35@PURE_QUANTA.MP5991GLUZ(CHIPS)':
 'VOUT5': CDS_PINID='VOUT5';
NODE_NAME     PU296 28
 '@T6G_MB_LIB.T6G(SCH_1):PAGE325_I35@PURE_QUANTA.MP5991GLUZ(CHIPS)':
 'VOUT6': CDS_PINID='VOUT6';
NODE_NAME     PU296 29
 '@T6G_MB_LIB.T6G(SCH_1):PAGE325_I35@PURE_QUANTA.MP5991GLUZ(CHIPS)':
 'VOUT7': CDS_PINID='VOUT7';
NODE_NAME     PU296 30
 '@T6G_MB_LIB.T6G(SCH_1):PAGE325_I35@PURE_QUANTA.MP5991GLUZ(CHIPS)':
 'VOUT8': CDS_PINID='VOUT8';
NODE_NAME     PU296 31
 '@T6G_MB_LIB.T6G(SCH_1):PAGE325_I35@PURE_QUANTA.MP5991GLUZ(CHIPS)':
 'VOUT9': CDS_PINID='VOUT9';
NODE_NAME     PU296 32
 '@T6G_MB_LIB.T6G(SCH_1):PAGE325_I35@PURE_QUANTA.MP5991GLUZ(CHIPS)':
 'VOUT10': CDS_PINID='VOUT10';
NODE_NAME     PR3805 1
 '@T6G_MB_LIB.T6G(SCH_1):PAGE343_I36@PURE_QUANTA.Q_RES(CHIPS)':
 'A': CDS_PINID='A';
NODE_NAME     R4067 1
 '@T6G_MB_LIB.T6G(SCH_1):PAGE343_I43@PURE_QUANTA.Q_RES(CHIPS)':
 'A': CDS_PINID='A';
NODE_NAME     PD107 C
 '@T6G_MB_LIB.T6G(SCH_1):PAGE343_I47@PURE_QUANTA.DIODE_TVS(CHIPS)':
 'C':PIN_LENGTH='Short',
 CDS_PINID='C';
NODE_NAME     PC2139 1
 '@T6G_MB_LIB.T6G(SCH_1):PAGE343_I49@PURE_QUANTA.Q_CAP(CHIPS)':
 'A': CDS_PINID='A';
NODE_NAME     PU201 A3
 '@T6G_MB_LIB.T6G(SCH_1):PAGE343_I67@PURE_QUANTA.MAX15090BEWIT(CHIPS)':
 'IN_A3': CDS_PINID='IN_A3';
NODE_NAME     PU201 A5
 '@T6G_MB_LIB.T6G(SCH_1):PAGE343_I67@PURE_QUANTA.MAX15090BEWIT(CHIPS)':
 'IN_A5': CDS_PINID='IN_A5';
NODE_NAME     PU201 B3
 '@T6G_MB_LIB.T6G(SCH_1):PAGE343_I67@PURE_QUANTA.MAX15090BEWIT(CHIPS)':
 'IN_B3': CDS_PINID='IN_B3';
NODE_NAME     PU201 B5
 '@T6G_MB_LIB.T6G(SCH_1):PAGE343_I67@PURE_QUANTA.MAX15090BEWIT(CHIPS)':
 'IN_B5': CDS_PINID='IN_B5';
NODE_NAME     PU201 C3
 '@T6G_MB_LIB.T6G(SCH_1):PAGE343_I67@PURE_QUANTA.MAX15090BEWIT(CHIPS)':
 'IN_C3': CDS_PINID='IN_C3';
NODE_NAME     PU201 C5
 '@T6G_MB_LIB.T6G(SCH_1):PAGE343_I67@PURE_QUANTA.MAX15090BEWIT(CHIPS)':
 'IN_C5': CDS_PINID='IN_C5';
NODE_NAME     PU201 D5
 '@T6G_MB_LIB.T6G(SCH_1):PAGE343_I67@PURE_QUANTA.MAX15090BEWIT(CHIPS)':
 'IN_D5': CDS_PINID='IN_D5';
NODE_NAME     PR3830 1
 '@T6G_MB_LIB.T6G(SCH_1):PAGE343_I84@PURE_QUANTA.Q_RES(CHIPS)':
 'A': CDS_PINID='A';
NODE_NAME     PC2165 1
 '@T6G_MB_LIB.T6G(SCH_1):PAGE344_I13@PURE_QUANTA.Q_CAP(CHIPS)':
 'A': CDS_PINID='A';
NODE_NAME     PR3853 1
 '@T6G_MB_LIB.T6G(SCH_1):PAGE344_I36@PURE_QUANTA.Q_RES(CHIPS)':
 'A': CDS_PINID='A';
NODE_NAME     PR3857 1
 '@T6G_MB_LIB.T6G(SCH_1):PAGE344_I37@PURE_QUANTA.Q_RES(CHIPS)':
 'A': CDS_PINID='A';
NODE_NAME     PC2198 1
 '@T6G_MB_LIB.T6G(SCH_1):PAGE323_I25@PURE_QUANTA.Q_CAP(CHIPS)':
 'A': CDS_PINID='A';
NODE_NAME     PR3953 1
 '@T6G_MB_LIB.T6G(SCH_1):PAGE323_I52@PURE_QUANTA.Q_RES(CHIPS)':
 'A': CDS_PINID='A';
NODE_NAME     PR3957 1
 '@T6G_MB_LIB.T6G(SCH_1):PAGE323_I54@PURE_QUANTA.Q_RES(CHIPS)':
 'A': CDS_PINID='A';
NODE_NAME     R4074 1
 '@T6G_MB_LIB.T6G(SCH_1):PAGE324_I25@PURE_QUANTA.Q_RES(CHIPS)':
 'A': CDS_PINID='A';
NODE_NAME     PD114 C
 '@T6G_MB_LIB.T6G(SCH_1):PAGE324_I33@PURE_QUANTA.DIODE_TVS(CHIPS)':
 'C':PIN_LENGTH='Short',
 CDS_PINID='C';
NODE_NAME     PC2207 1
 '@T6G_MB_LIB.T6G(SCH_1):PAGE324_I36@PURE_QUANTA.Q_CAP(CHIPS)':
 'A': CDS_PINID='A';
NODE_NAME     PR3960 1
 '@T6G_MB_LIB.T6G(SCH_1):PAGE324_I37@PURE_QUANTA.Q_RES(CHIPS)':
 'A': CDS_PINID='A';
NODE_NAME     PR3966 1
 '@T6G_MB_LIB.T6G(SCH_1):PAGE324_I65@PURE_QUANTA.Q_RES(CHIPS)':
 'A': CDS_PINID='A';
NODE_NAME     PU294 A3
 '@T6G_MB_LIB.T6G(SCH_1):PAGE324_I66@PURE_QUANTA.MAX15090BEWIT(CHIPS)':
 'IN_A3': CDS_PINID='IN_A3';
NODE_NAME     PU294 A5
 '@T6G_MB_LIB.T6G(SCH_1):PAGE324_I66@PURE_QUANTA.MAX15090BEWIT(CHIPS)':
 'IN_A5': CDS_PINID='IN_A5';
NODE_NAME     PU294 B3
 '@T6G_MB_LIB.T6G(SCH_1):PAGE324_I66@PURE_QUANTA.MAX15090BEWIT(CHIPS)':
 'IN_B3': CDS_PINID='IN_B3';
NODE_NAME     PU294 B5
 '@T6G_MB_LIB.T6G(SCH_1):PAGE324_I66@PURE_QUANTA.MAX15090BEWIT(CHIPS)':
 'IN_B5': CDS_PINID='IN_B5';
NODE_NAME     PU294 C3
 '@T6G_MB_LIB.T6G(SCH_1):PAGE324_I66@PURE_QUANTA.MAX15090BEWIT(CHIPS)':
 'IN_C3': CDS_PINID='IN_C3';
NODE_NAME     PU294 C5
 '@T6G_MB_LIB.T6G(SCH_1):PAGE324_I66@PURE_QUANTA.MAX15090BEWIT(CHIPS)':
 'IN_C5': CDS_PINID='IN_C5';
NODE_NAME     PU294 D5
 '@T6G_MB_LIB.T6G(SCH_1):PAGE324_I66@PURE_QUANTA.MAX15090BEWIT(CHIPS)':
 'IN_D5': CDS_PINID='IN_D5';
NODE_NAME     R4071 1
 '@T6G_MB_LIB.T6G(SCH_1):PAGE350_I25@PURE_QUANTA.Q_RES(CHIPS)':
 'A': CDS_PINID='A';
NODE_NAME     PC2230 1
 '@T6G_MB_LIB.T6G(SCH_1):PAGE350_I31@PURE_QUANTA.Q_CAP(CHIPS)':
 'A': CDS_PINID='A';
NODE_NAME     PC2231 1
 '@T6G_MB_LIB.T6G(SCH_1):PAGE350_I37@PURE_QUANTA.Q_CAP(CHIPS)':
 'A': CDS_PINID='A';
NODE_NAME     PR4010 1
 '@T6G_MB_LIB.T6G(SCH_1):PAGE350_I51@PURE_QUANTA.Q_RES(CHIPS)':
 'A': CDS_PINID='A';
NODE_NAME     PR4000 1
 '@T6G_MB_LIB.T6G(SCH_1):PAGE350_I65@PURE_QUANTA.Q_RES(CHIPS)':
 'A': CDS_PINID='A';
NODE_NAME     R336 1
 '@T6G_MB_LIB.T6G(SCH_1):PAGE273_I10@PURE_QUANTA.Q_RES(CHIPS)':
 'A': CDS_PINID='A';
NODE_NAME     R2528 1
 '@T6G_MB_LIB.T6G(SCH_1):PAGE365_I8@PURE_QUANTA.Q_RES(CHIPS)':
 'A': CDS_PINID='A';
NODE_NAME     R2530 1
 '@T6G_MB_LIB.T6G(SCH_1):PAGE365_I10@PURE_QUANTA.Q_RES(CHIPS)':
 'A': CDS_PINID='A';
NODE_NAME     R4068 1
 '@T6G_MB_LIB.T6G(SCH_1):PAGE338_I17@PURE_QUANTA.Q_RES(CHIPS)':
 'A': CDS_PINID='A';
NODE_NAME     PR3786 1
 '@T6G_MB_LIB.T6G(SCH_1):PAGE338_I43@PURE_QUANTA.Q_RES(CHIPS)':
 'A': CDS_PINID='A';
NODE_NAME     PC2079 1
 '@T6G_MB_LIB.T6G(SCH_1):PAGE338_I45@PURE_QUANTA.Q_CAP(CHIPS)':
 'A': CDS_PINID='A';
NODE_NAME     PU203 A3
 '@T6G_MB_LIB.T6G(SCH_1):PAGE338_I50@PURE_QUANTA.MAX15090BEWIT(CHIPS)':
 'IN_A3': CDS_PINID='IN_A3';
NODE_NAME     PU203 A5
 '@T6G_MB_LIB.T6G(SCH_1):PAGE338_I50@PURE_QUANTA.MAX15090BEWIT(CHIPS)':
 'IN_A5': CDS_PINID='IN_A5';
NODE_NAME     PU203 B3
 '@T6G_MB_LIB.T6G(SCH_1):PAGE338_I50@PURE_QUANTA.MAX15090BEWIT(CHIPS)':
 'IN_B3': CDS_PINID='IN_B3';
NODE_NAME     PU203 B5
 '@T6G_MB_LIB.T6G(SCH_1):PAGE338_I50@PURE_QUANTA.MAX15090BEWIT(CHIPS)':
 'IN_B5': CDS_PINID='IN_B5';
NODE_NAME     PU203 C3
 '@T6G_MB_LIB.T6G(SCH_1):PAGE338_I50@PURE_QUANTA.MAX15090BEWIT(CHIPS)':
 'IN_C3': CDS_PINID='IN_C3';
NODE_NAME     PU203 C5
 '@T6G_MB_LIB.T6G(SCH_1):PAGE338_I50@PURE_QUANTA.MAX15090BEWIT(CHIPS)':
 'IN_C5': CDS_PINID='IN_C5';
NODE_NAME     PU203 D5
 '@T6G_MB_LIB.T6G(SCH_1):PAGE338_I50@PURE_QUANTA.MAX15090BEWIT(CHIPS)':
 'IN_D5': CDS_PINID='IN_D5';
NODE_NAME     PR3792 1
 '@T6G_MB_LIB.T6G(SCH_1):PAGE338_I56@PURE_QUANTA.Q_RES(CHIPS)':
 'A': CDS_PINID='A';
NODE_NAME     R4070 1
 '@T6G_MB_LIB.T6G(SCH_1):PAGE338_I59@PURE_QUANTA.Q_RES(CHIPS)':
 'A': CDS_PINID='A';
NODE_NAME     PD101 C
 '@T6G_MB_LIB.T6G(SCH_1):PAGE338_I115@PURE_QUANTA.DIODE_TVS(CHIPS)':
 'C':PIN_LENGTH='Short',
 CDS_PINID='C';
NODE_NAME     R4072 1
 '@T6G_MB_LIB.T6G(SCH_1):PAGE324_I8@PURE_QUANTA.Q_RES(CHIPS)':
 'A': CDS_PINID='A';
NODE_NAME     PC2154 1
 '@T6G_MB_LIB.T6G(SCH_1):PAGE339_I68@PURE_QUANTA.Q_CAP(CHIPS)':
 'A': CDS_PINID='A';
NODE_NAME     PR3841 1
 '@T6G_MB_LIB.T6G(SCH_1):PAGE339_I82@PURE_QUANTA.Q_RES(CHIPS)':
 'A': CDS_PINID='A';
NODE_NAME     PR3843 1
 '@T6G_MB_LIB.T6G(SCH_1):PAGE339_I88@PURE_QUANTA.Q_RES(CHIPS)':
 'A': CDS_PINID='A';
NODE_NAME     R335 1
 '@T6G_MB_LIB.T6G(SCH_1):PAGE273_I15@PURE_QUANTA.Q_RES(CHIPS)':
 'A': CDS_PINID='A';
NODE_NAME     PC1648 1
 '@T6G_MB_LIB.T6G(SCH_1):PAGE244_I2@PURE_QUANTA.Q_CAP(CHIPS)':
 'A': CDS_PINID='A';
NODE_NAME     PL8064 1
 '@T6G_MB_LIB.T6G(SCH_1):PAGE244_I5@PURE_QUANTA.Q_INDUCTOR(CHIPS)':
 '1': CDS_PINID='\1\';
NODE_NAME     PL8045 1
 '@T6G_MB_LIB.T6G(SCH_1):PAGE245_I24@PURE_QUANTA.Q_INDUCTOR(CHIPS)':
 '1': CDS_PINID='\1\';
NODE_NAME     PC8008 1
 '@T6G_MB_LIB.T6G(SCH_1):PAGE245_I44@PURE_QUANTA.Q_CAP(CHIPS)':
 'A': CDS_PINID='A';
NODE_NAME     PC6000 1
 '@T6G_MB_LIB.T6G(SCH_1):PAGE167_I8@PURE_QUANTA.Q_CAP(CHIPS)':
 'A': CDS_PINID='A';
NODE_NAME     PL71 1
 '@T6G_MB_LIB.T6G(SCH_1):PAGE167_I10@PURE_QUANTA.Q_INDUCTOR(CHIPS)':
 '1': CDS_PINID='\1\';
NODE_NAME     PR314 1
 '@T6G_MB_LIB.T6G(SCH_1):PAGE168_I48@PURE_QUANTA.Q_RES(CHIPS)':
 'A': CDS_PINID='A';
NODE_NAME     PL53 2
 '@T6G_MB_LIB.T6G(SCH_1):PAGE169_I82@PURE_QUANTA.Q_INDUCTOR(CHIPS)':
 '2': CDS_PINID='\2\';
NODE_NAME     PC479 1
 '@T6G_MB_LIB.T6G(SCH_1):PAGE169_I85@PURE_QUANTA.Q_CAP(CHIPS)':
 'A': CDS_PINID='A';
NODE_NAME     PL65 2
 '@T6G_MB_LIB.T6G(SCH_1):PAGE173_I74@PURE_QUANTA.Q_INDUCTOR(CHIPS)':
 '2': CDS_PINID='\2\';
NODE_NAME     PC583 1
 '@T6G_MB_LIB.T6G(SCH_1):PAGE173_I77@PURE_QUANTA.Q_CAP(CHIPS)':
 'A': CDS_PINID='A';
NODE_NAME     PR74 1
 '@T6G_MB_LIB.T6G(SCH_1):PAGE175_I51@PURE_QUANTA.Q_RES(CHIPS)':
 'A': CDS_PINID='A';
NODE_NAME     PL12 2
 '@T6G_MB_LIB.T6G(SCH_1):PAGE176_I83@PURE_QUANTA.Q_INDUCTOR(CHIPS)':
 '2': CDS_PINID='\2\';
NODE_NAME     PL19 2
 '@T6G_MB_LIB.T6G(SCH_1):PAGE180_I69@PURE_QUANTA.Q_INDUCTOR(CHIPS)':
 '2': CDS_PINID='\2\';
NODE_NAME     PC148 1
 '@T6G_MB_LIB.T6G(SCH_1):PAGE180_I72@PURE_QUANTA.Q_CAP(CHIPS)':
 'A': CDS_PINID='A';
NODE_NAME     PR125 1
 '@T6G_MB_LIB.T6G(SCH_1):PAGE182_I16@PURE_QUANTA.Q_RES(CHIPS)':
 'A': CDS_PINID='A';
NODE_NAME     PL24 2
 '@T6G_MB_LIB.T6G(SCH_1):PAGE183_I78@PURE_QUANTA.Q_INDUCTOR(CHIPS)':
 '2': CDS_PINID='\2\';
NODE_NAME     PC6001 1
 '@T6G_MB_LIB.T6G(SCH_1):PAGE184_I5@PURE_QUANTA.Q_CAP(CHIPS)':
 'A': CDS_PINID='A';
NODE_NAME     PL77 1
 '@T6G_MB_LIB.T6G(SCH_1):PAGE184_I7@PURE_QUANTA.Q_INDUCTOR(CHIPS)':
 '1': CDS_PINID='\1\';
NODE_NAME     PL30 2
 '@T6G_MB_LIB.T6G(SCH_1):PAGE186_I73@PURE_QUANTA.Q_INDUCTOR(CHIPS)':
 '2': CDS_PINID='\2\';
NODE_NAME     PC6004 1
 '@T6G_MB_LIB.T6G(SCH_1):PAGE186_I74@PURE_QUANTA.Q_CAP(CHIPS)':
 'A': CDS_PINID='A';
NODE_NAME     PL37 2
 '@T6G_MB_LIB.T6G(SCH_1):PAGE190_I74@PURE_QUANTA.Q_INDUCTOR(CHIPS)':
 '2': CDS_PINID='\2\';
NODE_NAME     PC6007 1
 '@T6G_MB_LIB.T6G(SCH_1):PAGE190_I77@PURE_QUANTA.Q_CAP(CHIPS)':
 'A': CDS_PINID='A';
NODE_NAME     PR251 1
 '@T6G_MB_LIB.T6G(SCH_1):PAGE192_I49@PURE_QUANTA.Q_RES(CHIPS)':
 'A': CDS_PINID='A';
NODE_NAME     PL42 2
 '@T6G_MB_LIB.T6G(SCH_1):PAGE193_I79@PURE_QUANTA.Q_INDUCTOR(CHIPS)':
 '2': CDS_PINID='\2\';
NODE_NAME     PC375 1
 '@T6G_MB_LIB.T6G(SCH_1):PAGE193_I83@PURE_QUANTA.Q_CAP(CHIPS)':
 'A': CDS_PINID='A';
NODE_NAME     PL49 2
 '@T6G_MB_LIB.T6G(SCH_1):PAGE197_I72@PURE_QUANTA.Q_INDUCTOR(CHIPS)':
 '2': CDS_PINID='\2\';
NODE_NAME     PC438 1
 '@T6G_MB_LIB.T6G(SCH_1):PAGE197_I74@PURE_QUANTA.Q_CAP(CHIPS)':
 'A': CDS_PINID='A';
NODE_NAME     PR388 1
 '@T6G_MB_LIB.T6G(SCH_1):PAGE199_I18@PURE_QUANTA.Q_RES(CHIPS)':
 'A': CDS_PINID='A';
NODE_NAME     PC511 1
 '@T6G_MB_LIB.T6G(SCH_1):PAGE200_I85@PURE_QUANTA.Q_CAP(CHIPS)':
 'A': CDS_PINID='A';
NODE_NAME     PL26 1
 '@T6G_MB_LIB.T6G(SCH_1):PAGE201_I4@PURE_QUANTA.Q_INDUCTOR(CHIPS)':
 '1': CDS_PINID='\1\';
NODE_NAME     PD115 C
 '@T6G_MB_LIB.T6G(SCH_1):PAGE350_I28@PURE_QUANTA.DIODE_TVS(CHIPS)':
 'C':PIN_LENGTH='SHORT',
 CDS_PINID='C';
NODE_NAME     PU300 A3
 '@T6G_MB_LIB.T6G(SCH_1):PAGE350_I86@PURE_QUANTA.MAX15090BEWIT(CHIPS)':
 'IN_A3': CDS_PINID='IN_A3';
NODE_NAME     PU300 A5
 '@T6G_MB_LIB.T6G(SCH_1):PAGE350_I86@PURE_QUANTA.MAX15090BEWIT(CHIPS)':
 'IN_A5': CDS_PINID='IN_A5';
NODE_NAME     PU300 B3
 '@T6G_MB_LIB.T6G(SCH_1):PAGE350_I86@PURE_QUANTA.MAX15090BEWIT(CHIPS)':
 'IN_B3': CDS_PINID='IN_B3';
NODE_NAME     PU300 B5
 '@T6G_MB_LIB.T6G(SCH_1):PAGE350_I86@PURE_QUANTA.MAX15090BEWIT(CHIPS)':
 'IN_B5': CDS_PINID='IN_B5';
NODE_NAME     PU300 C3
 '@T6G_MB_LIB.T6G(SCH_1):PAGE350_I86@PURE_QUANTA.MAX15090BEWIT(CHIPS)':
 'IN_C3': CDS_PINID='IN_C3';
NODE_NAME     PU300 C5
 '@T6G_MB_LIB.T6G(SCH_1):PAGE350_I86@PURE_QUANTA.MAX15090BEWIT(CHIPS)':
 'IN_C5': CDS_PINID='IN_C5';
NODE_NAME     PU300 D5
 '@T6G_MB_LIB.T6G(SCH_1):PAGE350_I86@PURE_QUANTA.MAX15090BEWIT(CHIPS)':
 'IN_D5': CDS_PINID='IN_D5';
NODE_NAME     PR4014 1
 '@T6G_MB_LIB.T6G(SCH_1):PAGE350_I53@PURE_QUANTA.Q_RES(CHIPS)':
 'A': CDS_PINID='A';
NODE_NAME     PR4003 1
 '@T6G_MB_LIB.T6G(SCH_1):PAGE350_I68@PURE_QUANTA.Q_RES(CHIPS)':
 'A': CDS_PINID='A';
NODE_NAME     R4065 1
 '@T6G_MB_LIB.T6G(SCH_1):PAGE343_I17@PURE_QUANTA.Q_RES(CHIPS)':
 'A': CDS_PINID='A';
NODE_NAME     R1799 1
 '@T6G_MB_LIB.T6G(SCH_1):PAGE369_I6@PURE_QUANTA.Q_RES(CHIPS)':
 'A': CDS_PINID='A';
NODE_NAME     PU289 27
 '@T6G_MB_LIB.T6G(SCH_1):PAGE267_I58@PURE_QUANTA.MP5990GMA1111Z(CHIPS)':
 'VOUT1': CDS_PINID='VOUT1';
NODE_NAME     PU289 28
 '@T6G_MB_LIB.T6G(SCH_1):PAGE267_I58@PURE_QUANTA.MP5990GMA1111Z(CHIPS)':
 'VOUT2': CDS_PINID='VOUT2';
NODE_NAME     PU289 29
 '@T6G_MB_LIB.T6G(SCH_1):PAGE267_I58@PURE_QUANTA.MP5990GMA1111Z(CHIPS)':
 'VOUT3': CDS_PINID='VOUT3';
NODE_NAME     PU289 30
 '@T6G_MB_LIB.T6G(SCH_1):PAGE267_I58@PURE_QUANTA.MP5990GMA1111Z(CHIPS)':
 'VOUT4': CDS_PINID='VOUT4';
NODE_NAME     PU289 31
 '@T6G_MB_LIB.T6G(SCH_1):PAGE267_I58@PURE_QUANTA.MP5990GMA1111Z(CHIPS)':
 'VOUT5': CDS_PINID='VOUT5';
NODE_NAME     PU289 32
 '@T6G_MB_LIB.T6G(SCH_1):PAGE267_I58@PURE_QUANTA.MP5990GMA1111Z(CHIPS)':
 'VOUT6': CDS_PINID='VOUT6';
NODE_NAME     PU289 33
 '@T6G_MB_LIB.T6G(SCH_1):PAGE267_I58@PURE_QUANTA.MP5990GMA1111Z(CHIPS)':
 'VOUT7': CDS_PINID='VOUT7';
NODE_NAME     PU289 34
 '@T6G_MB_LIB.T6G(SCH_1):PAGE267_I58@PURE_QUANTA.MP5990GMA1111Z(CHIPS)':
 'VOUT8': CDS_PINID='VOUT8';
NODE_NAME     PU289 35
 '@T6G_MB_LIB.T6G(SCH_1):PAGE267_I58@PURE_QUANTA.MP5990GMA1111Z(CHIPS)':
 'VOUT9': CDS_PINID='VOUT9';
NODE_NAME     PU289 36
 '@T6G_MB_LIB.T6G(SCH_1):PAGE267_I58@PURE_QUANTA.MP5990GMA1111Z(CHIPS)':
 'VOUT10': CDS_PINID='VOUT10';
NODE_NAME     R3933 1
 '@T6G_MB_LIB.T6G(SCH_1):PAGE267_I63@PURE_QUANTA.Q_RES(CHIPS)':
 'A': CDS_PINID='A';
NODE_NAME     PR3931 1
 '@T6G_MB_LIB.T6G(SCH_1):PAGE267_I71@PURE_QUANTA.Q_RES(CHIPS)':
 'A': CDS_PINID='A';
NODE_NAME     PD111 K
 '@T6G_MB_LIB.T6G(SCH_1):PAGE267_I89@PURE_QUANTA.SS15P3SM386A(CHIPS)':
 'CATHODE': CDS_PINID='CATHODE';
NODE_NAME     PPQ5 1
 '@T6G_MB_LIB.T6G(SCH_1):PAGE302_I29@PURE_QUANTA.MOSFET_NCH_1D3S(CHIPS)':
 '1': CDS_PINID='\1\';
NODE_NAME     PPQ5 2
 '@T6G_MB_LIB.T6G(SCH_1):PAGE302_I29@PURE_QUANTA.MOSFET_NCH_1D3S(CHIPS)':
 '2': CDS_PINID='\2\';
NODE_NAME     PPQ5 3
 '@T6G_MB_LIB.T6G(SCH_1):PAGE302_I29@PURE_QUANTA.MOSFET_NCH_1D3S(CHIPS)':
 '3': CDS_PINID='\3\';
NODE_NAME     PPQ6 1
 '@T6G_MB_LIB.T6G(SCH_1):PAGE302_I46@PURE_QUANTA.MOSFET_NCH_1D3S(CHIPS)':
 '1': CDS_PINID='\1\';
NODE_NAME     PPQ6 2
 '@T6G_MB_LIB.T6G(SCH_1):PAGE302_I46@PURE_QUANTA.MOSFET_NCH_1D3S(CHIPS)':
 '2': CDS_PINID='\2\';
NODE_NAME     PPQ6 3
 '@T6G_MB_LIB.T6G(SCH_1):PAGE302_I46@PURE_QUANTA.MOSFET_NCH_1D3S(CHIPS)':
 '3': CDS_PINID='\3\';
NODE_NAME     PPQ1 1
 '@T6G_MB_LIB.T6G(SCH_1):PAGE302_I61@PURE_QUANTA.MOSFET_NCH_1D3S(CHIPS)':
 '1': CDS_PINID='\1\';
NODE_NAME     PPQ1 2
 '@T6G_MB_LIB.T6G(SCH_1):PAGE302_I61@PURE_QUANTA.MOSFET_NCH_1D3S(CHIPS)':
 '2': CDS_PINID='\2\';
NODE_NAME     PPQ1 3
 '@T6G_MB_LIB.T6G(SCH_1):PAGE302_I61@PURE_QUANTA.MOSFET_NCH_1D3S(CHIPS)':
 '3': CDS_PINID='\3\';
NODE_NAME     PC1750 1
 '@T6G_MB_LIB.T6G(SCH_1):PAGE302_I63@PURE_QUANTA.Q_CAP(CHIPS)':
 'A': CDS_PINID='A';
NODE_NAME     PPQ2 1
 '@T6G_MB_LIB.T6G(SCH_1):PAGE302_I64@PURE_QUANTA.MOSFET_NCH_1D3S(CHIPS)':
 '1': CDS_PINID='\1\';
NODE_NAME     PPQ2 2
 '@T6G_MB_LIB.T6G(SCH_1):PAGE302_I64@PURE_QUANTA.MOSFET_NCH_1D3S(CHIPS)':
 '2': CDS_PINID='\2\';
NODE_NAME     PPQ2 3
 '@T6G_MB_LIB.T6G(SCH_1):PAGE302_I64@PURE_QUANTA.MOSFET_NCH_1D3S(CHIPS)':
 '3': CDS_PINID='\3\';
NODE_NAME     PR2537 1
 '@T6G_MB_LIB.T6G(SCH_1):PAGE302_I71@PURE_QUANTA.Q_RES(CHIPS)':
 'A': CDS_PINID='A';
NODE_NAME     PD17 K
 '@T6G_MB_LIB.T6G(SCH_1):PAGE302_I72@PURE_QUANTA.SS15P3SM386A(CHIPS)':
 'CATHODE': CDS_PINID='CATHODE';
NODE_NAME     PPQ9 1
 '@T6G_MB_LIB.T6G(SCH_1):PAGE302_I75@PURE_QUANTA.MOSFET_NCH_1D3S(CHIPS)':
 '1': CDS_PINID='\1\';
NODE_NAME     PPQ9 2
 '@T6G_MB_LIB.T6G(SCH_1):PAGE302_I75@PURE_QUANTA.MOSFET_NCH_1D3S(CHIPS)':
 '2': CDS_PINID='\2\';
NODE_NAME     PPQ9 3
 '@T6G_MB_LIB.T6G(SCH_1):PAGE302_I75@PURE_QUANTA.MOSFET_NCH_1D3S(CHIPS)':
 '3': CDS_PINID='\3\';
NODE_NAME     PPQ8 1
 '@T6G_MB_LIB.T6G(SCH_1):PAGE302_I79@PURE_QUANTA.MOSFET_NCH_1D3S(CHIPS)':
 '1': CDS_PINID='\1\';
NODE_NAME     PPQ8 2
 '@T6G_MB_LIB.T6G(SCH_1):PAGE302_I79@PURE_QUANTA.MOSFET_NCH_1D3S(CHIPS)':
 '2': CDS_PINID='\2\';
NODE_NAME     PPQ8 3
 '@T6G_MB_LIB.T6G(SCH_1):PAGE302_I79@PURE_QUANTA.MOSFET_NCH_1D3S(CHIPS)':
 '3': CDS_PINID='\3\';
NODE_NAME     PPQ7 1
 '@T6G_MB_LIB.T6G(SCH_1):PAGE302_I80@PURE_QUANTA.MOSFET_NCH_1D3S(CHIPS)':
 '1': CDS_PINID='\1\';
NODE_NAME     PPQ7 2
 '@T6G_MB_LIB.T6G(SCH_1):PAGE302_I80@PURE_QUANTA.MOSFET_NCH_1D3S(CHIPS)':
 '2': CDS_PINID='\2\';
NODE_NAME     PPQ7 3
 '@T6G_MB_LIB.T6G(SCH_1):PAGE302_I80@PURE_QUANTA.MOSFET_NCH_1D3S(CHIPS)':
 '3': CDS_PINID='\3\';
NODE_NAME     PC1789 1
 '@T6G_MB_LIB.T6G(SCH_1):PAGE371_I28@PURE_QUANTA.Q_CAP(CHIPS)':
 'A': CDS_PINID='A';
NODE_NAME     PJ38 10
 '@T6G_MB_LIB.T6G(SCH_1):PAGE371_I42@PURE_QUANTA.SCONN21_9193031121LF(CHIPS)':
 '10': CDS_PINID='\10\';
NODE_NAME     PC6020 1
 '@T6G_MB_LIB.T6G(SCH_1):PAGE315_I5@PURE_QUANTA.Q_CAP(CHIPS)':
 'A': CDS_PINID='A';
NODE_NAME     PL6002 1
 '@T6G_MB_LIB.T6G(SCH_1):PAGE315_I7@PURE_QUANTA.Q_INDUCTOR(CHIPS)':
 '1': CDS_PINID='\1\';
NODE_NAME     PL6003 1
 '@T6G_MB_LIB.T6G(SCH_1):PAGE380_I2@PURE_QUANTA.Q_INDUCTOR(CHIPS)':
 '1': CDS_PINID='\1\';
NODE_NAME     PC6023 1
 '@T6G_MB_LIB.T6G(SCH_1):PAGE380_I35@PURE_QUANTA.Q_CAP(CHIPS)':
 'A': CDS_PINID='A';
NODE_NAME     R2219 1
 '@T6G_MB_LIB.T6G(SCH_1):PAGE372_I30@PURE_QUANTA.Q_RES(CHIPS)':
 'A': CDS_PINID='A';
NODE_NAME     R2221 1
 '@T6G_MB_LIB.T6G(SCH_1):PAGE372_I35@PURE_QUANTA.Q_RES(CHIPS)':
 'A': CDS_PINID='A';
NODE_NAME     R554 1
 '@T6G_MB_LIB.T6G(SCH_1):PAGE273_I111@PURE_QUANTA.Q_RES(CHIPS)':
 'A': CDS_PINID='A';
NODE_NAME     R568 1
 '@T6G_MB_LIB.T6G(SCH_1):PAGE273_I114@PURE_QUANTA.Q_RES(CHIPS)':
 'A': CDS_PINID='A';
NODE_NAME     R8024 2
 '@T6G_MB_LIB.T6G(SCH_1):PAGE375_I46@PURE_QUANTA.Q_RES(CHIPS)':
 'B': CDS_PINID='B';
NODE_NAME     C8016 1
 '@T6G_MB_LIB.T6G(SCH_1):PAGE371_I95@PURE_QUANTA.Q_CAP(CHIPS)':
 'A': CDS_PINID='A';
NODE_NAME     U8006 5
 '@T6G_MB_LIB.T6G(SCH_1):PAGE371_I104@PURE_QUANTA.AP331AWG7(CHIPS)':
 'VCC': CDS_PINID='VCC';
NODE_NAME     R8114 1
 '@T6G_MB_LIB.T6G(SCH_1):PAGE372_I56@PURE_QUANTA.Q_RES(CHIPS)':
 'A': CDS_PINID='A';
NODE_NAME     C8019 1
 '@T6G_MB_LIB.T6G(SCH_1):PAGE372_I66@PURE_QUANTA.Q_CAP(CHIPS)':
 'A': CDS_PINID='A';
NODE_NAME     U8008 5
 '@T6G_MB_LIB.T6G(SCH_1):PAGE372_I71@PURE_QUANTA.AP331AWG7(CHIPS)':
 'VCC': CDS_PINID='VCC';
NODE_NAME     R8121 1
 '@T6G_MB_LIB.T6G(SCH_1):PAGE372_I76@PURE_QUANTA.Q_RES(CHIPS)':
 'A': CDS_PINID='A';
NODE_NAME     U8010 5
 '@T6G_MB_LIB.T6G(SCH_1):PAGE372_I80@PURE_QUANTA.AP331AWG7(CHIPS)':
 'VCC': CDS_PINID='VCC';
NODE_NAME     C8022 1
 '@T6G_MB_LIB.T6G(SCH_1):PAGE372_I84@PURE_QUANTA.Q_CAP(CHIPS)':
 'A': CDS_PINID='A';
NODE_NAME     PC6500 1
 '@T6G_MB_LIB.T6G(SCH_1):PAGE469_I4@PURE_QUANTA.Q_CAP(CHIPS)':
 'A': CDS_PINID='A';
NODE_NAME     PL6500 1
 '@T6G_MB_LIB.T6G(SCH_1):PAGE469_I9@PURE_QUANTA.Q_INDUCTOR(CHIPS)':
 '1': CDS_PINID='\1\';
NODE_NAME     PC6519 1
 '@T6G_MB_LIB.T6G(SCH_1):PAGE470_I3@PURE_QUANTA.Q_CAP(CHIPS)':
 'A': CDS_PINID='A';
NODE_NAME     PL6503 1
 '@T6G_MB_LIB.T6G(SCH_1):PAGE470_I9@PURE_QUANTA.Q_INDUCTOR(CHIPS)':
 '1': CDS_PINID='\1\';
NODE_NAME     PR6807 1
 '@T6G_MB_LIB.T6G(SCH_1):PAGE475_I158@PURE_QUANTA.Q_RES(CHIPS)':
 'A': CDS_PINID='A';
NODE_NAME     PR6606 1
 '@T6G_MB_LIB.T6G(SCH_1):PAGE475_I160@PURE_QUANTA.Q_RES(CHIPS)':
 'A': CDS_PINID='A';
NODE_NAME     PL6504 2
 '@T6G_MB_LIB.T6G(SCH_1):PAGE476_I182@PURE_QUANTA.Q_INDUCTOR(CHIPS)':
 '2': CDS_PINID='\2\';
NODE_NAME     PC6562 1
 '@T6G_MB_LIB.T6G(SCH_1):PAGE476_I291@PURE_QUANTA.Q_CAP(CHIPS)':
 'A': CDS_PINID='A';
NODE_NAME     PR6809 1
 '@T6G_MB_LIB.T6G(SCH_1):PAGE477_I10@PURE_QUANTA.Q_RES(CHIPS)':
 'A': CDS_PINID='A';
NODE_NAME     PR6808 1
 '@T6G_MB_LIB.T6G(SCH_1):PAGE477_I11@PURE_QUANTA.Q_RES(CHIPS)':
 'A': CDS_PINID='A';
NODE_NAME     PL6510 2
 '@T6G_MB_LIB.T6G(SCH_1):PAGE478_I104@PURE_QUANTA.Q_INDUCTOR(CHIPS)':
 '2': CDS_PINID='\2\';
NODE_NAME     PC6620 1
 '@T6G_MB_LIB.T6G(SCH_1):PAGE478_I114@PURE_QUANTA.Q_CAP(CHIPS)':
 'A': CDS_PINID='A';
NODE_NAME     R9021 1
 '@T6G_MB_LIB.T6G(SCH_1):PAGE372_I97@PURE_QUANTA.Q_RES(CHIPS)':
 'A': CDS_PINID='A';
NODE_NAME     R1837 1
 '@T6G_MB_LIB.T6G(SCH_1):PAGE264_I54@PURE_QUANTA.Q_RES_4P_12(CHIPS)':
 '1': CDS_PINID='\1\';
NODE_NAME     R1838 1
 '@T6G_MB_LIB.T6G(SCH_1):PAGE264_I58@PURE_QUANTA.Q_RES_4P_12(CHIPS)':
 '1': CDS_PINID='\1\';
NODE_NAME     R700 1
 '@T6G_MB_LIB.T6G(SCH_1):PAGE146_I2@PURE_QUANTA.Q_RES(CHIPS)':
 'A': CDS_PINID='A';
NODE_NAME     R1007 1
 '@T6G_MB_LIB.T6G(SCH_1):PAGE146_I11@PURE_QUANTA.Q_RES(CHIPS)':
 'A': CDS_PINID='A';
NODE_NAME     R1480 1
 '@T6G_MB_LIB.T6G(SCH_1):PAGE146_I19@PURE_QUANTA.Q_RES(CHIPS)':
 'A': CDS_PINID='A';
NODE_NAME     R896 1
 '@T6G_MB_LIB.T6G(SCH_1):PAGE146_I35@PURE_QUANTA.Q_RES(CHIPS)':
 'A': CDS_PINID='A';
NODE_NAME     PU299 21_22
 '@T6G_MB_LIB.T6G(SCH_1):PAGE350_I95@PURE_QUANTA.RS31312R(CHIPS)':
 'VIN_21_22': CDS_PINID='VIN_21_22';
NODE_NAME     PU299 23
 '@T6G_MB_LIB.T6G(SCH_1):PAGE350_I95@PURE_QUANTA.RS31312R(CHIPS)':
 'VIN_23': CDS_PINID='VIN_23';
NODE_NAME     PU299 24
 '@T6G_MB_LIB.T6G(SCH_1):PAGE350_I95@PURE_QUANTA.RS31312R(CHIPS)':
 'VIN_24': CDS_PINID='VIN_24';
NODE_NAME     PU299 25
 '@T6G_MB_LIB.T6G(SCH_1):PAGE350_I95@PURE_QUANTA.RS31312R(CHIPS)':
 'VIN_25': CDS_PINID='VIN_25';
NODE_NAME     PU299 26
 '@T6G_MB_LIB.T6G(SCH_1):PAGE350_I95@PURE_QUANTA.RS31312R(CHIPS)':
 'VIN_26': CDS_PINID='VIN_26';
NODE_NAME     PU204 21_22
 '@T6G_MB_LIB.T6G(SCH_1):PAGE339_I137@PURE_QUANTA.RS31312R(CHIPS)':
 'VIN_21_22': CDS_PINID='VIN_21_22';
NODE_NAME     PU204 23
 '@T6G_MB_LIB.T6G(SCH_1):PAGE339_I137@PURE_QUANTA.RS31312R(CHIPS)':
 'VIN_23': CDS_PINID='VIN_23';
NODE_NAME     PU204 24
 '@T6G_MB_LIB.T6G(SCH_1):PAGE339_I137@PURE_QUANTA.RS31312R(CHIPS)':
 'VIN_24': CDS_PINID='VIN_24';
NODE_NAME     PU204 25
 '@T6G_MB_LIB.T6G(SCH_1):PAGE339_I137@PURE_QUANTA.RS31312R(CHIPS)':
 'VIN_25': CDS_PINID='VIN_25';
NODE_NAME     PU204 26
 '@T6G_MB_LIB.T6G(SCH_1):PAGE339_I137@PURE_QUANTA.RS31312R(CHIPS)':
 'VIN_26': CDS_PINID='VIN_26';
NODE_NAME     PU206 21_22
 '@T6G_MB_LIB.T6G(SCH_1):PAGE344_I82@PURE_QUANTA.RS31312R(CHIPS)':
 'VIN_21_22': CDS_PINID='VIN_21_22';
NODE_NAME     PU206 23
 '@T6G_MB_LIB.T6G(SCH_1):PAGE344_I82@PURE_QUANTA.RS31312R(CHIPS)':
 'VIN_23': CDS_PINID='VIN_23';
NODE_NAME     PU206 24
 '@T6G_MB_LIB.T6G(SCH_1):PAGE344_I82@PURE_QUANTA.RS31312R(CHIPS)':
 'VIN_24': CDS_PINID='VIN_24';
NODE_NAME     PU206 25
 '@T6G_MB_LIB.T6G(SCH_1):PAGE344_I82@PURE_QUANTA.RS31312R(CHIPS)':
 'VIN_25': CDS_PINID='VIN_25';
NODE_NAME     PU206 26
 '@T6G_MB_LIB.T6G(SCH_1):PAGE344_I82@PURE_QUANTA.RS31312R(CHIPS)':
 'VIN_26': CDS_PINID='VIN_26';
NODE_NAME     PU292 21_22
 '@T6G_MB_LIB.T6G(SCH_1):PAGE323_I76@PURE_QUANTA.RS31312R(CHIPS)':
 'VIN_21_22': CDS_PINID='VIN_21_22';
NODE_NAME     PU292 23
 '@T6G_MB_LIB.T6G(SCH_1):PAGE323_I76@PURE_QUANTA.RS31312R(CHIPS)':
 'VIN_23': CDS_PINID='VIN_23';
NODE_NAME     PU292 24
 '@T6G_MB_LIB.T6G(SCH_1):PAGE323_I76@PURE_QUANTA.RS31312R(CHIPS)':
 'VIN_24': CDS_PINID='VIN_24';
NODE_NAME     PU292 25
 '@T6G_MB_LIB.T6G(SCH_1):PAGE323_I76@PURE_QUANTA.RS31312R(CHIPS)':
 'VIN_25': CDS_PINID='VIN_25';
NODE_NAME     PU292 26
 '@T6G_MB_LIB.T6G(SCH_1):PAGE323_I76@PURE_QUANTA.RS31312R(CHIPS)':
 'VIN_26': CDS_PINID='VIN_26';
NET_NAME
'P12V_AUX_ADC'
 '@T6G_MB_LIB.T6G(SCH_1):P12V_AUX_ADC':
 C_SIGNAL='@t6g_mb_lib.t6g(sch_1):p12v_aux_adc';
NODE_NAME     R1799 2
 '@T6G_MB_LIB.T6G(SCH_1):PAGE369_I6@PURE_QUANTA.Q_RES(CHIPS)':
 'B': CDS_PINID='B';
NODE_NAME     R3680 1
 '@T6G_MB_LIB.T6G(SCH_1):PAGE369_I9@PURE_QUANTA.Q_RES(CHIPS)':
 'A': CDS_PINID='A';
NODE_NAME     R3679 1
 '@T6G_MB_LIB.T6G(SCH_1):PAGE369_I10@PURE_QUANTA.Q_RES(CHIPS)':
 'A': CDS_PINID='A';
NODE_NAME     R1800 1
 '@T6G_MB_LIB.T6G(SCH_1):PAGE369_I170@PURE_QUANTA.Q_RES(CHIPS)':
 'A': CDS_PINID='A';
NET_NAME
'P12V_AUX_ADC_MAM'
 '@T6G_MB_LIB.T6G(SCH_1):P12V_AUX_ADC_MAM':
 C_SIGNAL='@t6g_mb_lib.t6g(sch_1):p12v_aux_adc_mam';
NODE_NAME     R3679 2
 '@T6G_MB_LIB.T6G(SCH_1):PAGE369_I10@PURE_QUANTA.Q_RES(CHIPS)':
 'B': CDS_PINID='B';
NODE_NAME     C1344 1
 '@T6G_MB_LIB.T6G(SCH_1):PAGE369_I46@PURE_QUANTA.Q_CAP(CHIPS)':
 'A': CDS_PINID='A';
NODE_NAME     U193 5
 '@T6G_MB_LIB.T6G(SCH_1):PAGE369_I169@PURE_QUANTA.MAX11617EEET(CHIPS)':
 'AIN0': CDS_PINID='AIN0';
NET_NAME
'P12V_AUX_ADC_TIC'
 '@T6G_MB_LIB.T6G(SCH_1):P12V_AUX_ADC_TIC':
 C_SIGNAL='@t6g_mb_lib.t6g(sch_1):p12v_aux_adc_tic';
NODE_NAME     R3680 2
 '@T6G_MB_LIB.T6G(SCH_1):PAGE369_I9@PURE_QUANTA.Q_RES(CHIPS)':
 'B': CDS_PINID='B';
NODE_NAME     C2046 1
 '@T6G_MB_LIB.T6G(SCH_1):PAGE369_I44@PURE_QUANTA.Q_CAP(CHIPS)':
 'A': CDS_PINID='A';
NODE_NAME     U269 16
 '@T6G_MB_LIB.T6G(SCH_1):PAGE369_I142@PURE_QUANTA.ADC128D818CIMTXNOPB(CHIPS)':
 'IN0': CDS_PINID='IN0';
NET_NAME
'P12V_AUX_BLEEDING'
 '@T6G_MB_LIB.T6G(SCH_1):P12V_AUX_BLEEDING':
 C_SIGNAL='@t6g_mb_lib.t6g(sch_1):p12v_aux_bleeding';
NODE_NAME     R2530 2
 '@T6G_MB_LIB.T6G(SCH_1):PAGE365_I10@PURE_QUANTA.Q_RES(CHIPS)':
 'B': CDS_PINID='B';
NODE_NAME     Q54 D
 '@T6G_MB_LIB.T6G(SCH_1):PAGE365_I14@PURE_QUANTA.MOSFET_NCH_GDS_ESD_PROTECTED(CHIPS)':
 'D': CDS_PINID='D';
NET_NAME
'P12V_AUX_DSC'
 '@T6G_MB_LIB.T6G(SCH_1):P12V_AUX_DSC':
 C_SIGNAL='@t6g_mb_lib.t6g(sch_1):p12v_aux_dsc';
NODE_NAME     Q7001 5
 '@T6G_MB_LIB.T6G(SCH_1):PAGE146_I16@PURE_QUANTA.MOSFET_NCH_1D3S(CHIPS)':
 '5': CDS_PINID='\5\';
NODE_NAME     R1480 2
 '@T6G_MB_LIB.T6G(SCH_1):PAGE146_I19@PURE_QUANTA.Q_RES(CHIPS)':
 'B': CDS_PINID='B';
NET_NAME
'P12V_AUX_DSC_G1'
 '@T6G_MB_LIB.T6G(SCH_1):P12V_AUX_DSC_G1':
 C_SIGNAL='@t6g_mb_lib.t6g(sch_1):p12v_aux_dsc_g1';
NODE_NAME     Q7000 G
 '@T6G_MB_LIB.T6G(SCH_1):PAGE146_I10@PURE_QUANTA.MOSFET_PCH_GDS_ESD_PROTECTED(CHIPS)':
 'G': CDS_PINID='G';
NODE_NAME     R1007 2
 '@T6G_MB_LIB.T6G(SCH_1):PAGE146_I11@PURE_QUANTA.Q_RES(CHIPS)':
 'B': CDS_PINID='B';
NODE_NAME     R1049 1
 '@T6G_MB_LIB.T6G(SCH_1):PAGE146_I12@PURE_QUANTA.Q_RES(CHIPS)':
 'A': CDS_PINID='A';
NET_NAME
'P12V_AUX_DSC_G2'
 '@T6G_MB_LIB.T6G(SCH_1):P12V_AUX_DSC_G2':
 C_SIGNAL='@t6g_mb_lib.t6g(sch_1):p12v_aux_dsc_g2';
NODE_NAME     Q7000 D
 '@T6G_MB_LIB.T6G(SCH_1):PAGE146_I10@PURE_QUANTA.MOSFET_PCH_GDS_ESD_PROTECTED(CHIPS)':
 'D': CDS_PINID='D';
NODE_NAME     R1474 1
 '@T6G_MB_LIB.T6G(SCH_1):PAGE146_I14@PURE_QUANTA.Q_RES(CHIPS)':
 'A': CDS_PINID='A';
NODE_NAME     Q7001 4
 '@T6G_MB_LIB.T6G(SCH_1):PAGE146_I16@PURE_QUANTA.MOSFET_NCH_1D3S(CHIPS)':
 '4': CDS_PINID='\4\';
NET_NAME
'P12V_AUX_DSC_S1'
 '@T6G_MB_LIB.T6G(SCH_1):P12V_AUX_DSC_S1':
 C_SIGNAL='@t6g_mb_lib.t6g(sch_1):p12v_aux_dsc_s1';
NODE_NAME     U57 3
 '@T6G_MB_LIB.T6G(SCH_1):PAGE146_I5@PURE_QUANTA.SCHOTTKY_DUAL_12A_3C(CHIPS)':
 'C': CDS_PINID='C';
NODE_NAME     C1113 1
 '@T6G_MB_LIB.T6G(SCH_1):PAGE146_I6@PURE_QUANTA.Q_CAP(CHIPS)':
 'A': CDS_PINID='A';
NODE_NAME     Q7000 S
 '@T6G_MB_LIB.T6G(SCH_1):PAGE146_I10@PURE_QUANTA.MOSFET_PCH_GDS_ESD_PROTECTED(CHIPS)':
 'S': CDS_PINID='S';
NET_NAME
'P12V_AUX_DSC_VOL'
 '@T6G_MB_LIB.T6G(SCH_1):P12V_AUX_DSC_VOL':
 C_SIGNAL='@t6g_mb_lib.t6g(sch_1):p12v_aux_dsc_vol';
NODE_NAME     R700 2
 '@T6G_MB_LIB.T6G(SCH_1):PAGE146_I2@PURE_QUANTA.Q_RES(CHIPS)':
 'B': CDS_PINID='B';
NODE_NAME     R855 1
 '@T6G_MB_LIB.T6G(SCH_1):PAGE146_I3@PURE_QUANTA.Q_RES(CHIPS)':
 'A': CDS_PINID='A';
NODE_NAME     U57 1
 '@T6G_MB_LIB.T6G(SCH_1):PAGE146_I5@PURE_QUANTA.SCHOTTKY_DUAL_12A_3C(CHIPS)':
 'B': CDS_PINID='B';
NET_NAME
'P12V_AUX_UV_ADR_TRIGGER'
 '@T6G_MB_LIB.T6G(SCH_1):P12V_AUX_UV_ADR_TRIGGER':
 C_SIGNAL='@t6g_mb_lib.t6g(sch_1):p12v_aux_uv_adr_trigger';
NODE_NAME     R8115 1
 '@T6G_MB_LIB.T6G(SCH_1):PAGE372_I55@PURE_QUANTA.Q_RES(CHIPS)':
 'A': CDS_PINID='A';
NODE_NAME     R8114 2
 '@T6G_MB_LIB.T6G(SCH_1):PAGE372_I56@PURE_QUANTA.Q_RES(CHIPS)':
 'B': CDS_PINID='B';
NODE_NAME     C8018 1
 '@T6G_MB_LIB.T6G(SCH_1):PAGE372_I61@PURE_QUANTA.Q_CAP(CHIPS)':
 'A': CDS_PINID='A';
NODE_NAME     R8117 1
 '@T6G_MB_LIB.T6G(SCH_1):PAGE372_I63@PURE_QUANTA.Q_RES(CHIPS)':
 'A': CDS_PINID='A';
NODE_NAME     U8008 3
 '@T6G_MB_LIB.T6G(SCH_1):PAGE372_I71@PURE_QUANTA.AP331AWG7(CHIPS)':
 'IN+': CDS_PINID='\in+\';
NET_NAME
'P12V_AUX_UV_TRIGGER'
 '@T6G_MB_LIB.T6G(SCH_1):P12V_AUX_UV_TRIGGER':
 C_SIGNAL='@t6g_mb_lib.t6g(sch_1):p12v_aux_uv_trigger';
NODE_NAME     R8122 1
 '@T6G_MB_LIB.T6G(SCH_1):PAGE372_I75@PURE_QUANTA.Q_RES(CHIPS)':
 'A': CDS_PINID='A';
NODE_NAME     R8121 2
 '@T6G_MB_LIB.T6G(SCH_1):PAGE372_I76@PURE_QUANTA.Q_RES(CHIPS)':
 'B': CDS_PINID='B';
NODE_NAME     U8010 3
 '@T6G_MB_LIB.T6G(SCH_1):PAGE372_I80@PURE_QUANTA.AP331AWG7(CHIPS)':
 'IN+': CDS_PINID='\in+\';
NODE_NAME     R8123 1
 '@T6G_MB_LIB.T6G(SCH_1):PAGE372_I81@PURE_QUANTA.Q_RES(CHIPS)':
 'A': CDS_PINID='A';
NODE_NAME     C8021 1
 '@T6G_MB_LIB.T6G(SCH_1):PAGE372_I92@PURE_QUANTA.Q_CAP(CHIPS)':
 'A': CDS_PINID='A';
NET_NAME
'P12V_E1S_0'
 '@T6G_MB_LIB.T6G(SCH_1):P12V_E1S_0':
 C_SIGNAL='@t6g_mb_lib.t6g(sch_1):p12v_e1s_0',
 CDS_GLOBAL_NET='TRUE';
NODE_NAME     PR3950 1
 '@T6G_MB_LIB.T6G(SCH_1):PAGE323_I42@PURE_QUANTA.Q_RES(CHIPS)':
 'A': CDS_PINID='A';
NODE_NAME     PR3952 1
 '@T6G_MB_LIB.T6G(SCH_1):PAGE323_I45@PURE_QUANTA.Q_RES(CHIPS)':
 'A': CDS_PINID='A';
NODE_NAME     PC2206 1
 '@T6G_MB_LIB.T6G(SCH_1):PAGE323_I56@PURE_QUANTA.Q_CAP(CHIPS)':
 'A': CDS_PINID='A';
NODE_NAME     PU294 A4
 '@T6G_MB_LIB.T6G(SCH_1):PAGE324_I66@PURE_QUANTA.MAX15090BEWIT(CHIPS)':
 'OUT_A4': CDS_PINID='OUT_A4';
NODE_NAME     PU294 B4
 '@T6G_MB_LIB.T6G(SCH_1):PAGE324_I66@PURE_QUANTA.MAX15090BEWIT(CHIPS)':
 'OUT_B4': CDS_PINID='OUT_B4';
NODE_NAME     PU294 B6
 '@T6G_MB_LIB.T6G(SCH_1):PAGE324_I66@PURE_QUANTA.MAX15090BEWIT(CHIPS)':
 'OUT_B6': CDS_PINID='OUT_B6';
NODE_NAME     PU294 C4
 '@T6G_MB_LIB.T6G(SCH_1):PAGE324_I66@PURE_QUANTA.MAX15090BEWIT(CHIPS)':
 'OUT_C4': CDS_PINID='OUT_C4';
NODE_NAME     PU294 C6
 '@T6G_MB_LIB.T6G(SCH_1):PAGE324_I66@PURE_QUANTA.MAX15090BEWIT(CHIPS)':
 'OUT_C6': CDS_PINID='OUT_C6';
NODE_NAME     PU294 D4
 '@T6G_MB_LIB.T6G(SCH_1):PAGE324_I66@PURE_QUANTA.MAX15090BEWIT(CHIPS)':
 'OUT_D4': CDS_PINID='OUT_D4';
NODE_NAME     PU294 D6
 '@T6G_MB_LIB.T6G(SCH_1):PAGE324_I66@PURE_QUANTA.MAX15090BEWIT(CHIPS)':
 'OUT_D6': CDS_PINID='OUT_D6';
NODE_NAME     PC2214 1
 '@T6G_MB_LIB.T6G(SCH_1):PAGE324_I72@PURE_QUANTA.Q_CAP(CHIPS)':
 'A': CDS_PINID='A';
NODE_NAME     PD112 C
 '@T6G_MB_LIB.T6G(SCH_1):PAGE324_I74@PURE_QUANTA.SCHOTTKY_AC(CHIPS)':
 'C': CDS_PINID='C';
NODE_NAME     PC2217 1
 '@T6G_MB_LIB.T6G(SCH_1):PAGE324_I78@PURE_QUANTA.Q_CAP(CHIPS)':
 'A': CDS_PINID='A';
NODE_NAME     PC2280 1
 '@T6G_MB_LIB.T6G(SCH_1):PAGE324_I80@PURE_QUANTA.Q_CAP(CHIPS)':
 'A': CDS_PINID='A';
NODE_NAME     PR4528 1
 '@T6G_MB_LIB.T6G(SCH_1):PAGE324_I73@PURE_QUANTA.Q_RES(CHIPS)':
 'A': CDS_PINID='A';
NODE_NAME     PC2219 1
 '@T6G_MB_LIB.T6G(SCH_1):PAGE324_I79@PURE_QUANTA.Q_CAP(CHIPS)':
 'A': CDS_PINID='A';
NODE_NAME     U52 11
 '@T6G_MB_LIB.T6G(SCH_1):PAGE466_I57@PURE_QUANTA.ISL28022FRZT(CHIPS)':
 'VBUS': CDS_PINID='VBUS';
NODE_NAME     R1283 1
 '@T6G_MB_LIB.T6G(SCH_1):PAGE466_I74@PURE_QUANTA.Q_RES(CHIPS)':
 'A': CDS_PINID='A';
NODE_NAME     C1107 1
 '@T6G_MB_LIB.T6G(SCH_1):PAGE466_I81@PURE_QUANTA.Q_CAP(CHIPS)':
 'A': CDS_PINID='A';
NODE_NAME     R1323 2
 '@T6G_MB_LIB.T6G(SCH_1):PAGE466_I84@PURE_QUANTA.Q_RES(CHIPS)':
 'B': CDS_PINID='B';
NODE_NAME     PU292 13
 '@T6G_MB_LIB.T6G(SCH_1):PAGE323_I76@PURE_QUANTA.RS31312R(CHIPS)':
 'VOUT_13': CDS_PINID='VOUT_13';
NODE_NAME     PU292 14
 '@T6G_MB_LIB.T6G(SCH_1):PAGE323_I76@PURE_QUANTA.RS31312R(CHIPS)':
 'VOUT_14': CDS_PINID='VOUT_14';
NODE_NAME     PU292 15
 '@T6G_MB_LIB.T6G(SCH_1):PAGE323_I76@PURE_QUANTA.RS31312R(CHIPS)':
 'VOUT_15': CDS_PINID='VOUT_15';
NODE_NAME     PU292 16
 '@T6G_MB_LIB.T6G(SCH_1):PAGE323_I76@PURE_QUANTA.RS31312R(CHIPS)':
 'VOUT_16': CDS_PINID='VOUT_16';
NODE_NAME     PU292 17
 '@T6G_MB_LIB.T6G(SCH_1):PAGE323_I76@PURE_QUANTA.RS31312R(CHIPS)':
 'VOUT_17': CDS_PINID='VOUT_17';
NODE_NAME     PU292 18
 '@T6G_MB_LIB.T6G(SCH_1):PAGE323_I76@PURE_QUANTA.RS31312R(CHIPS)':
 'VOUT_18': CDS_PINID='VOUT_18';
NODE_NAME     PU292 19
 '@T6G_MB_LIB.T6G(SCH_1):PAGE323_I76@PURE_QUANTA.RS31312R(CHIPS)':
 'VOUT_19': CDS_PINID='VOUT_19';
NODE_NAME     PU292 20
 '@T6G_MB_LIB.T6G(SCH_1):PAGE323_I76@PURE_QUANTA.RS31312R(CHIPS)':
 'VOUT_20': CDS_PINID='VOUT_20';
NET_NAME
'P12V_E1S_0_ADC_ALERT_R'
 '@T6G_MB_LIB.T6G(SCH_1):P12V_E1S_0_ADC_ALERT_R':
 C_SIGNAL='@t6g_mb_lib.t6g(sch_1):p12v_e1s_0_adc_alert_r';
NODE_NAME     U52 3
 '@T6G_MB_LIB.T6G(SCH_1):PAGE466_I57@PURE_QUANTA.ISL28022FRZT(CHIPS)':
 'EXT_CLK||INT': CDS_PINID='\ext_clk||int\';
NODE_NAME     R1269 1
 '@T6G_MB_LIB.T6G(SCH_1):PAGE466_I62@PURE_QUANTA.Q_RES(CHIPS)':
 'A': CDS_PINID='A';
NET_NAME
'P12V_E1S_0_EN'
 '@T6G_MB_LIB.T6G(SCH_1):P12V_E1S_0_EN':
 C_SIGNAL='@t6g_mb_lib.t6g(sch_1):p12v_e1s_0_en';
NODE_NAME     R199 2
 '@T6G_MB_LIB.T6G(SCH_1):PAGE80_I22@PURE_QUANTA.Q_RES(CHIPS)':
 'B': CDS_PINID='B';
NODE_NAME     U18 AA11
 '@T6G_MB_LIB.T6G(SCH_1):PAGE80_I216@PURE_QUANTA.LCMXO3LF9400C5BG484C(CHIPS)':
 'PB24A': CDS_PINID='PB24A';
NET_NAME
'P12V_E1S_0_EN_G'
 '@T6G_MB_LIB.T6G(SCH_1):P12V_E1S_0_EN_G':
 C_SIGNAL='@t6g_mb_lib.t6g(sch_1):p12v_e1s_0_en_g';
NODE_NAME     R4074 2
 '@T6G_MB_LIB.T6G(SCH_1):PAGE324_I25@PURE_QUANTA.Q_RES(CHIPS)':
 'B': CDS_PINID='B';
NODE_NAME     Q127 5
 '@T6G_MB_LIB.T6G(SCH_1):PAGE324_I27@PURE_QUANTA.MOSFET_NCH_DUAL(CHIPS)':
 'G2': CDS_PINID='G2';
NODE_NAME     Q127 6
 '@T6G_MB_LIB.T6G(SCH_1):PAGE324_I12@PURE_QUANTA.MOSFET_NCH_DUAL(CHIPS)':
 'D1': CDS_PINID='D1';
NET_NAME
'P12V_E1S_0_ISENSE_MAM'
 '@T6G_MB_LIB.T6G(SCH_1):P12V_E1S_0_ISENSE_MAM':
 C_SIGNAL='@t6g_mb_lib.t6g(sch_1):p12v_e1s_0_isense_mam';
NODE_NAME     C35 1
 '@T6G_MB_LIB.T6G(SCH_1):PAGE369_I78@PURE_QUANTA.Q_CAP(CHIPS)':
 'A': CDS_PINID='A';
NODE_NAME     R3940 2
 '@T6G_MB_LIB.T6G(SCH_1):PAGE369_I79@PURE_QUANTA.Q_RES(CHIPS)':
 'B': CDS_PINID='B';
NODE_NAME     R3939 2
 '@T6G_MB_LIB.T6G(SCH_1):PAGE369_I80@PURE_QUANTA.Q_RES(CHIPS)':
 'B': CDS_PINID='B';
NODE_NAME     U193 12
 '@T6G_MB_LIB.T6G(SCH_1):PAGE369_I169@PURE_QUANTA.MAX11617EEET(CHIPS)':
 'AIN7': CDS_PINID='AIN7';
NET_NAME
'P12V_E1S_0_ISENSE_MAM_MAM'
 '@T6G_MB_LIB.T6G(SCH_1):P12V_E1S_0_ISENSE_MAM_MAM':
 C_SIGNAL='@t6g_mb_lib.t6g(sch_1):p12v_e1s_0_isense_mam_mam';
NODE_NAME     R3974 2
 '@T6G_MB_LIB.T6G(SCH_1):PAGE324_I70@PURE_QUANTA.Q_RES(CHIPS)':
 'B': CDS_PINID='B';
NODE_NAME     R3939 1
 '@T6G_MB_LIB.T6G(SCH_1):PAGE369_I80@PURE_QUANTA.Q_RES(CHIPS)':
 'A': CDS_PINID='A';
NET_NAME
'P12V_E1S_0_ISENSE_MAM_TIC'
 '@T6G_MB_LIB.T6G(SCH_1):P12V_E1S_0_ISENSE_MAM_TIC':
 C_SIGNAL='@t6g_mb_lib.t6g(sch_1):p12v_e1s_0_isense_mam_tic';
NODE_NAME     R3975 2
 '@T6G_MB_LIB.T6G(SCH_1):PAGE324_I87@PURE_QUANTA.Q_RES(CHIPS)':
 'B': CDS_PINID='B';
NODE_NAME     R3941 1
 '@T6G_MB_LIB.T6G(SCH_1):PAGE369_I74@PURE_QUANTA.Q_RES(CHIPS)':
 'A': CDS_PINID='A';
NET_NAME
'P12V_E1S_0_ISENSE_MPS_MAM'
 '@T6G_MB_LIB.T6G(SCH_1):P12V_E1S_0_ISENSE_MPS_MAM':
 C_SIGNAL='@t6g_mb_lib.t6g(sch_1):p12v_e1s_0_isense_mps_mam';
NODE_NAME     R3955 2
 '@T6G_MB_LIB.T6G(SCH_1):PAGE323_I48@PURE_QUANTA.Q_RES(CHIPS)':
 'B': CDS_PINID='B';
NODE_NAME     R3940 1
 '@T6G_MB_LIB.T6G(SCH_1):PAGE369_I79@PURE_QUANTA.Q_RES(CHIPS)':
 'A': CDS_PINID='A';
NET_NAME
'P12V_E1S_0_ISENSE_MPS_TIC'
 '@T6G_MB_LIB.T6G(SCH_1):P12V_E1S_0_ISENSE_MPS_TIC':
 C_SIGNAL='@t6g_mb_lib.t6g(sch_1):p12v_e1s_0_isense_mps_tic';
NODE_NAME     R3956 2
 '@T6G_MB_LIB.T6G(SCH_1):PAGE323_I47@PURE_QUANTA.Q_RES(CHIPS)':
 'B': CDS_PINID='B';
NODE_NAME     R3942 1
 '@T6G_MB_LIB.T6G(SCH_1):PAGE369_I73@PURE_QUANTA.Q_RES(CHIPS)':
 'A': CDS_PINID='A';
NET_NAME
'P12V_E1S_0_ISENSE_TIC'
 '@T6G_MB_LIB.T6G(SCH_1):P12V_E1S_0_ISENSE_TIC':
 C_SIGNAL='@t6g_mb_lib.t6g(sch_1):p12v_e1s_0_isense_tic';
NODE_NAME     R3942 2
 '@T6G_MB_LIB.T6G(SCH_1):PAGE369_I73@PURE_QUANTA.Q_RES(CHIPS)':
 'B': CDS_PINID='B';
NODE_NAME     R3941 2
 '@T6G_MB_LIB.T6G(SCH_1):PAGE369_I74@PURE_QUANTA.Q_RES(CHIPS)':
 'B': CDS_PINID='B';
NODE_NAME     C2194 1
 '@T6G_MB_LIB.T6G(SCH_1):PAGE369_I76@PURE_QUANTA.Q_CAP(CHIPS)':
 'A': CDS_PINID='A';
NODE_NAME     U269 9
 '@T6G_MB_LIB.T6G(SCH_1):PAGE369_I142@PURE_QUANTA.ADC128D818CIMTXNOPB(CHIPS)':
 'IN7': CDS_PINID='IN7';
NET_NAME
'P12V_E1S_0_PWRGD'
 '@T6G_MB_LIB.T6G(SCH_1):P12V_E1S_0_PWRGD':
 C_SIGNAL='@t6g_mb_lib.t6g(sch_1):p12v_e1s_0_pwrgd';
NODE_NAME     R6048 2
 '@T6G_MB_LIB.T6G(SCH_1):PAGE80_I28@PURE_QUANTA.Q_RES(CHIPS)':
 'B': CDS_PINID='B';
NODE_NAME     U18 U10
 '@T6G_MB_LIB.T6G(SCH_1):PAGE80_I216@PURE_QUANTA.LCMXO3LF9400C5BG484C(CHIPS)':
 'PB19D': CDS_PINID='PB19D';
NET_NAME
'P12V_E1S_0_R'
 '@T6G_MB_LIB.T6G(SCH_1):P12V_E1S_0_R':
 C_SIGNAL='@t6g_mb_lib.t6g(sch_1):p12v_e1s_0_r',
 CDS_GLOBAL_NET='TRUE';
NODE_NAME     C1276 1
 '@T6G_MB_LIB.T6G(SCH_1):PAGE297_I66@PURE_QUANTA.Q_CAP(CHIPS)':
 'A': CDS_PINID='A';
NODE_NAME     C1277 1
 '@T6G_MB_LIB.T6G(SCH_1):PAGE297_I67@PURE_QUANTA.Q_CAP(CHIPS)':
 'A': CDS_PINID='A';
NODE_NAME     C1278 1
 '@T6G_MB_LIB.T6G(SCH_1):PAGE297_I68@PURE_QUANTA.Q_CAP(CHIPS)':
 'A': CDS_PINID='A';
NODE_NAME     C1279 1
 '@T6G_MB_LIB.T6G(SCH_1):PAGE297_I74@PURE_QUANTA.Q_CAP(CHIPS)':
 'A': CDS_PINID='A';
NODE_NAME     J90 B1
 '@T6G_MB_LIB.T6G(SCH_1):PAGE297_I90@PURE_QUANTA.SCONN56_123276793(CHIPS)':
 'P12V_B1': CDS_PINID='P12V_B1';
NODE_NAME     J90 B2
 '@T6G_MB_LIB.T6G(SCH_1):PAGE297_I90@PURE_QUANTA.SCONN56_123276793(CHIPS)':
 'P12V_B2': CDS_PINID='P12V_B2';
NODE_NAME     J90 B3
 '@T6G_MB_LIB.T6G(SCH_1):PAGE297_I90@PURE_QUANTA.SCONN56_123276793(CHIPS)':
 'P12V_B3': CDS_PINID='P12V_B3';
NODE_NAME     J90 B4
 '@T6G_MB_LIB.T6G(SCH_1):PAGE297_I90@PURE_QUANTA.SCONN56_123276793(CHIPS)':
 'P12V_B4': CDS_PINID='P12V_B4';
NODE_NAME     J90 B5
 '@T6G_MB_LIB.T6G(SCH_1):PAGE297_I90@PURE_QUANTA.SCONN56_123276793(CHIPS)':
 'P12V_B5': CDS_PINID='P12V_B5';
NODE_NAME     J90 B6
 '@T6G_MB_LIB.T6G(SCH_1):PAGE297_I90@PURE_QUANTA.SCONN56_123276793(CHIPS)':
 'P12V_B6': CDS_PINID='P12V_B6';
NODE_NAME     R1292 1
 '@T6G_MB_LIB.T6G(SCH_1):PAGE466_I75@PURE_QUANTA.Q_RES(CHIPS)':
 'A': CDS_PINID='A';
NODE_NAME     R1323 1
 '@T6G_MB_LIB.T6G(SCH_1):PAGE466_I84@PURE_QUANTA.Q_RES(CHIPS)':
 'A': CDS_PINID='A';
NET_NAME
'P12V_E1S_AVIN_PD_0'
 '@T6G_MB_LIB.T6G(SCH_1):P12V_E1S_AVIN_PD_0':
 C_SIGNAL='@t6g_mb_lib.t6g(sch_1):p12v_e1s_avin_pd_0';
NODE_NAME     PR3950 2
 '@T6G_MB_LIB.T6G(SCH_1):PAGE323_I42@PURE_QUANTA.Q_RES(CHIPS)':
 'B': CDS_PINID='B';
NODE_NAME     PC2205 1
 '@T6G_MB_LIB.T6G(SCH_1):PAGE323_I51@PURE_QUANTA.Q_CAP(CHIPS)':
 'A': CDS_PINID='A';
NODE_NAME     PR3957 2
 '@T6G_MB_LIB.T6G(SCH_1):PAGE323_I54@PURE_QUANTA.Q_RES(CHIPS)':
 'B': CDS_PINID='B';
NODE_NAME     PU292 12
 '@T6G_MB_LIB.T6G(SCH_1):PAGE323_I76@PURE_QUANTA.RS31312R(CHIPS)':
 'AVIN': CDS_PINID='AVIN';
NET_NAME
'P12V_E1S_CB_0'
 '@T6G_MB_LIB.T6G(SCH_1):P12V_E1S_CB_0':
 C_SIGNAL='@t6g_mb_lib.t6g(sch_1):p12v_e1s_cb_0';
NODE_NAME     PR3968 1
 '@T6G_MB_LIB.T6G(SCH_1):PAGE324_I63@PURE_QUANTA.Q_RES(CHIPS)':
 'A': CDS_PINID='A';
NODE_NAME     PU294 B1
 '@T6G_MB_LIB.T6G(SCH_1):PAGE324_I66@PURE_QUANTA.MAX15090BEWIT(CHIPS)':
 'CB': CDS_PINID='CB';
NET_NAME
'P12V_E1S_EN_0_R'
 '@T6G_MB_LIB.T6G(SCH_1):P12V_E1S_EN_0_R':
 C_SIGNAL='@t6g_mb_lib.t6g(sch_1):p12v_e1s_en_0_r';
NODE_NAME     R4073 1
 '@T6G_MB_LIB.T6G(SCH_1):PAGE324_I11@PURE_QUANTA.Q_RES(CHIPS)':
 'A': CDS_PINID='A';
NODE_NAME     Q127 2
 '@T6G_MB_LIB.T6G(SCH_1):PAGE324_I12@PURE_QUANTA.MOSFET_NCH_DUAL(CHIPS)':
 'G1': CDS_PINID='G1';
NODE_NAME     R4064 2
 '@T6G_MB_LIB.T6G(SCH_1):PAGE324_I24@PURE_QUANTA.Q_RES(CHIPS)':
 'B': CDS_PINID='B';
NET_NAME
'P12V_E1S_EN_0_R2'
 '@T6G_MB_LIB.T6G(SCH_1):P12V_E1S_EN_0_R2':
 C_SIGNAL='@t6g_mb_lib.t6g(sch_1):p12v_e1s_en_0_r2';
NODE_NAME     R3943 2
 '@T6G_MB_LIB.T6G(SCH_1):PAGE323_I19@PURE_QUANTA.Q_RES(CHIPS)':
 'B': CDS_PINID='B';
NODE_NAME     PU292 1
 '@T6G_MB_LIB.T6G(SCH_1):PAGE323_I76@PURE_QUANTA.RS31312R(CHIPS)':
 'EN': CDS_PINID='EN';
NET_NAME
'P12V_E1S_FAULT_0'
 '@T6G_MB_LIB.T6G(SCH_1):P12V_E1S_FAULT_0':
 C_SIGNAL='@t6g_mb_lib.t6g(sch_1):p12v_e1s_fault_0';
NODE_NAME     PU294 C7
 '@T6G_MB_LIB.T6G(SCH_1):PAGE324_I66@PURE_QUANTA.MAX15090BEWIT(CHIPS)':
 'FAULT#': CDS_PINID='\fault#\';
NODE_NAME     R3976 2
 '@T6G_MB_LIB.T6G(SCH_1):PAGE324_I76@PURE_QUANTA.Q_RES(CHIPS)':
 'B': CDS_PINID='B';
NET_NAME
'P12V_E1S_FLTB_0'
 '@T6G_MB_LIB.T6G(SCH_1):P12V_E1S_FLTB_0':
 C_SIGNAL='@t6g_mb_lib.t6g(sch_1):p12v_e1s_fltb_0';
NODE_NAME     PR3951 1
 '@T6G_MB_LIB.T6G(SCH_1):PAGE323_I40@PURE_QUANTA.Q_RES(CHIPS)':
 'A': CDS_PINID='A';
NODE_NAME     PU292 9
 '@T6G_MB_LIB.T6G(SCH_1):PAGE323_I76@PURE_QUANTA.RS31312R(CHIPS)':
 'FLTB': CDS_PINID='FLTB';
NET_NAME
'P12V_E1S_GATE_0'
 '@T6G_MB_LIB.T6G(SCH_1):P12V_E1S_GATE_0':
 C_SIGNAL='@t6g_mb_lib.t6g(sch_1):p12v_e1s_gate_0';
NODE_NAME     PU294 A6
 '@T6G_MB_LIB.T6G(SCH_1):PAGE324_I66@PURE_QUANTA.MAX15090BEWIT(CHIPS)':
 'GATE': CDS_PINID='GATE';
NODE_NAME     PC2215 1
 '@T6G_MB_LIB.T6G(SCH_1):PAGE324_I69@PURE_QUANTA.Q_CAP(CHIPS)':
 'A': CDS_PINID='A';
NODE_NAME     PC2214 2
 '@T6G_MB_LIB.T6G(SCH_1):PAGE324_I72@PURE_QUANTA.Q_CAP(CHIPS)':
 'B': CDS_PINID='B';
NODE_NAME     PR4528 2
 '@T6G_MB_LIB.T6G(SCH_1):PAGE324_I73@PURE_QUANTA.Q_RES(CHIPS)':
 'B': CDS_PINID='B';
NET_NAME
'P12V_E1S_IMON_0'
 '@T6G_MB_LIB.T6G(SCH_1):P12V_E1S_IMON_0':
 C_SIGNAL='@t6g_mb_lib.t6g(sch_1):p12v_e1s_imon_0';
NODE_NAME     PR3949 1
 '@T6G_MB_LIB.T6G(SCH_1):PAGE323_I36@PURE_QUANTA.Q_RES(CHIPS)':
 'A': CDS_PINID='A';
NODE_NAME     PC2202 1
 '@T6G_MB_LIB.T6G(SCH_1):PAGE323_I39@PURE_QUANTA.Q_CAP(CHIPS)':
 'A': CDS_PINID='A';
NODE_NAME     R3956 1
 '@T6G_MB_LIB.T6G(SCH_1):PAGE323_I47@PURE_QUANTA.Q_RES(CHIPS)':
 'A': CDS_PINID='A';
NODE_NAME     R3955 1
 '@T6G_MB_LIB.T6G(SCH_1):PAGE323_I48@PURE_QUANTA.Q_RES(CHIPS)':
 'A': CDS_PINID='A';
NODE_NAME     PU292 8
 '@T6G_MB_LIB.T6G(SCH_1):PAGE323_I76@PURE_QUANTA.RS31312R(CHIPS)':
 'IMON': CDS_PINID='IMON';
NET_NAME
'P12V_E1S_ISET_0'
 '@T6G_MB_LIB.T6G(SCH_1):P12V_E1S_ISET_0':
 C_SIGNAL='@t6g_mb_lib.t6g(sch_1):p12v_e1s_iset_0';
NODE_NAME     PR3944 1
 '@T6G_MB_LIB.T6G(SCH_1):PAGE323_I15@PURE_QUANTA.Q_RES(CHIPS)':
 'A': CDS_PINID='A';
NODE_NAME     PR4541 1
 '@T6G_MB_LIB.T6G(SCH_1):PAGE323_I18@PURE_QUANTA.Q_RES(CHIPS)':
 'A': CDS_PINID='A';
NODE_NAME     PU292 5
 '@T6G_MB_LIB.T6G(SCH_1):PAGE323_I76@PURE_QUANTA.RS31312R(CHIPS)':
 'ISET': CDS_PINID='ISET';
NET_NAME
'P12V_E1S_ISET_0_R'
 '@T6G_MB_LIB.T6G(SCH_1):P12V_E1S_ISET_0_R':
 C_SIGNAL='@t6g_mb_lib.t6g(sch_1):p12v_e1s_iset_0_r';
NODE_NAME     PC2341 1
 '@T6G_MB_LIB.T6G(SCH_1):PAGE323_I17@PURE_QUANTA.Q_CAP(CHIPS)':
 'A': CDS_PINID='A';
NODE_NAME     PR4541 2
 '@T6G_MB_LIB.T6G(SCH_1):PAGE323_I18@PURE_QUANTA.Q_RES(CHIPS)':
 'B': CDS_PINID='B';
NET_NAME
'P12V_E1S_OV_0'
 '@T6G_MB_LIB.T6G(SCH_1):P12V_E1S_OV_0':
 C_SIGNAL='@t6g_mb_lib.t6g(sch_1):p12v_e1s_ov_0';
NODE_NAME     PR3962 1
 '@T6G_MB_LIB.T6G(SCH_1):PAGE324_I31@PURE_QUANTA.Q_RES(CHIPS)':
 'A': CDS_PINID='A';
NODE_NAME     PU294 D3
 '@T6G_MB_LIB.T6G(SCH_1):PAGE324_I66@PURE_QUANTA.MAX15090BEWIT(CHIPS)':
 'OV': CDS_PINID='OV';
NODE_NAME     PR3961 2
 '@T6G_MB_LIB.T6G(SCH_1):PAGE324_I32@PURE_QUANTA.Q_RES(CHIPS)':
 'B': CDS_PINID='B';
NET_NAME
'P12V_E1S_OV_FB_0'
 '@T6G_MB_LIB.T6G(SCH_1):P12V_E1S_OV_FB_0':
 C_SIGNAL='@t6g_mb_lib.t6g(sch_1):p12v_e1s_ov_fb_0';
NODE_NAME     PR3952 2
 '@T6G_MB_LIB.T6G(SCH_1):PAGE323_I45@PURE_QUANTA.Q_RES(CHIPS)':
 'B': CDS_PINID='B';
NODE_NAME     PR3954 1
 '@T6G_MB_LIB.T6G(SCH_1):PAGE323_I49@PURE_QUANTA.Q_RES(CHIPS)':
 'A': CDS_PINID='A';
NODE_NAME     PR3953 2
 '@T6G_MB_LIB.T6G(SCH_1):PAGE323_I52@PURE_QUANTA.Q_RES(CHIPS)':
 'B': CDS_PINID='B';
NODE_NAME     PU292 11
 '@T6G_MB_LIB.T6G(SCH_1):PAGE323_I76@PURE_QUANTA.RS31312R(CHIPS)':
 'OV': CDS_PINID='OV';
NET_NAME
'P12V_E1S_PWRGD_0'
 '@T6G_MB_LIB.T6G(SCH_1):P12V_E1S_PWRGD_0':
 C_SIGNAL='@t6g_mb_lib.t6g(sch_1):p12v_e1s_pwrgd_0';
NODE_NAME     PU294 D7
 '@T6G_MB_LIB.T6G(SCH_1):PAGE324_I66@PURE_QUANTA.MAX15090BEWIT(CHIPS)':
 'PG': CDS_PINID='PG';
NODE_NAME     R3972 1
 '@T6G_MB_LIB.T6G(SCH_1):PAGE324_I71@PURE_QUANTA.Q_RES(CHIPS)':
 'A': CDS_PINID='A';
NET_NAME
'P12V_E1S_REG_0'
 '@T6G_MB_LIB.T6G(SCH_1):P12V_E1S_REG_0':
 C_SIGNAL='@t6g_mb_lib.t6g(sch_1):p12v_e1s_reg_0';
NODE_NAME     PC2211 2
 '@T6G_MB_LIB.T6G(SCH_1):PAGE324_I61@PURE_QUANTA.Q_CAP(CHIPS)':
 'B': CDS_PINID='B';
NODE_NAME     PU294 D1
 '@T6G_MB_LIB.T6G(SCH_1):PAGE324_I66@PURE_QUANTA.MAX15090BEWIT(CHIPS)':
 'REG': CDS_PINID='REG';
NET_NAME
'P12V_E1S_SENSE_0'
 '@T6G_MB_LIB.T6G(SCH_1):P12V_E1S_SENSE_0':
 C_SIGNAL='@t6g_mb_lib.t6g(sch_1):p12v_e1s_sense_0';
NODE_NAME     PU294 A1
 '@T6G_MB_LIB.T6G(SCH_1):PAGE324_I66@PURE_QUANTA.MAX15090BEWIT(CHIPS)':
 'ISENSE': CDS_PINID='ISENSE';
NODE_NAME     PR3970 1
 '@T6G_MB_LIB.T6G(SCH_1):PAGE324_I68@PURE_QUANTA.Q_RES(CHIPS)':
 'A': CDS_PINID='A';
NODE_NAME     R3974 1
 '@T6G_MB_LIB.T6G(SCH_1):PAGE324_I70@PURE_QUANTA.Q_RES(CHIPS)':
 'A': CDS_PINID='A';
NODE_NAME     R3975 1
 '@T6G_MB_LIB.T6G(SCH_1):PAGE324_I87@PURE_QUANTA.Q_RES(CHIPS)':
 'A': CDS_PINID='A';
NET_NAME
'P12V_E1S_SS_0'
 '@T6G_MB_LIB.T6G(SCH_1):P12V_E1S_SS_0':
 C_SIGNAL='@t6g_mb_lib.t6g(sch_1):p12v_e1s_ss_0';
NODE_NAME     PC2281 1
 '@T6G_MB_LIB.T6G(SCH_1):PAGE323_I22@PURE_QUANTA.Q_CAP(CHIPS)':
 'A': CDS_PINID='A';
NODE_NAME     PU292 6
 '@T6G_MB_LIB.T6G(SCH_1):PAGE323_I76@PURE_QUANTA.RS31312R(CHIPS)':
 'SS': CDS_PINID='SS';
NET_NAME
'P12V_E1S_TIMER_0'
 '@T6G_MB_LIB.T6G(SCH_1):P12V_E1S_TIMER_0':
 C_SIGNAL='@t6g_mb_lib.t6g(sch_1):p12v_e1s_timer_0';
NODE_NAME     PC2196 1
 '@T6G_MB_LIB.T6G(SCH_1):PAGE323_I13@PURE_QUANTA.Q_CAP(CHIPS)':
 'A': CDS_PINID='A';
NODE_NAME     PU292 4
 '@T6G_MB_LIB.T6G(SCH_1):PAGE323_I76@PURE_QUANTA.RS31312R(CHIPS)':
 'TIMER': CDS_PINID='TIMER';
NET_NAME
'P12V_E1S_UV_0'
 '@T6G_MB_LIB.T6G(SCH_1):P12V_E1S_UV_0':
 C_SIGNAL='@t6g_mb_lib.t6g(sch_1):p12v_e1s_uv_0';
NODE_NAME     R3958 2
 '@T6G_MB_LIB.T6G(SCH_1):PAGE324_I29@PURE_QUANTA.Q_RES(CHIPS)':
 'B': CDS_PINID='B';
NODE_NAME     PR3960 2
 '@T6G_MB_LIB.T6G(SCH_1):PAGE324_I37@PURE_QUANTA.Q_RES(CHIPS)':
 'B': CDS_PINID='B';
NODE_NAME     PU294 D2
 '@T6G_MB_LIB.T6G(SCH_1):PAGE324_I66@PURE_QUANTA.MAX15090BEWIT(CHIPS)':
 'UV': CDS_PINID='UV';
NODE_NAME     PR3961 1
 '@T6G_MB_LIB.T6G(SCH_1):PAGE324_I32@PURE_QUANTA.Q_RES(CHIPS)':
 'A': CDS_PINID='A';
NET_NAME
'P12V_E1S_UV_0_R'
 '@T6G_MB_LIB.T6G(SCH_1):P12V_E1S_UV_0_R':
 C_SIGNAL='@t6g_mb_lib.t6g(sch_1):p12v_e1s_uv_0_r';
NODE_NAME     Q127 3
 '@T6G_MB_LIB.T6G(SCH_1):PAGE324_I27@PURE_QUANTA.MOSFET_NCH_DUAL(CHIPS)':
 'D2': CDS_PINID='D2';
NODE_NAME     R3958 1
 '@T6G_MB_LIB.T6G(SCH_1):PAGE324_I29@PURE_QUANTA.Q_RES(CHIPS)':
 'A': CDS_PINID='A';
NET_NAME
'P12V_E1S_VCC_0'
 '@T6G_MB_LIB.T6G(SCH_1):P12V_E1S_VCC_0':
 C_SIGNAL='@t6g_mb_lib.t6g(sch_1):p12v_e1s_vcc_0';
NODE_NAME     PR3966 2
 '@T6G_MB_LIB.T6G(SCH_1):PAGE324_I65@PURE_QUANTA.Q_RES(CHIPS)':
 'B': CDS_PINID='B';
NODE_NAME     PU294 A2
 '@T6G_MB_LIB.T6G(SCH_1):PAGE324_I66@PURE_QUANTA.MAX15090BEWIT(CHIPS)':
 'VCC': CDS_PINID='VCC';
NODE_NAME     PC2209 1
 '@T6G_MB_LIB.T6G(SCH_1):PAGE324_I64@PURE_QUANTA.Q_CAP(CHIPS)':
 'A': CDS_PINID='A';
NET_NAME
'P12V_HSC_ADC_N'
 '@T6G_MB_LIB.T6G(SCH_1):P12V_HSC_ADC_N':
 C_SIGNAL='@t6g_mb_lib.t6g(sch_1):p12v_hsc_adc_n';
NODE_NAME     PJ38 6
 '@T6G_MB_LIB.T6G(SCH_1):PAGE371_I42@PURE_QUANTA.SCONN21_9193031121LF(CHIPS)':
 '6': CDS_PINID='\6\';
NODE_NAME     PR2515 1
 '@T6G_MB_LIB.T6G(SCH_1):PAGE302_I83@PURE_QUANTA.Q_RES(CHIPS)':
 'A': CDS_PINID='A';
NODE_NAME     PR2516 1
 '@T6G_MB_LIB.T6G(SCH_1):PAGE302_I84@PURE_QUANTA.Q_RES(CHIPS)':
 'A': CDS_PINID='A';
NODE_NAME     PR2517 1
 '@T6G_MB_LIB.T6G(SCH_1):PAGE302_I85@PURE_QUANTA.Q_RES(CHIPS)':
 'A': CDS_PINID='A';
NODE_NAME     PR2518 1
 '@T6G_MB_LIB.T6G(SCH_1):PAGE302_I86@PURE_QUANTA.Q_RES(CHIPS)':
 'A': CDS_PINID='A';
NODE_NAME     PR2519 1
 '@T6G_MB_LIB.T6G(SCH_1):PAGE302_I87@PURE_QUANTA.Q_RES(CHIPS)':
 'A': CDS_PINID='A';
NET_NAME
'P12V_HSC_ADC_P'
 '@T6G_MB_LIB.T6G(SCH_1):P12V_HSC_ADC_P':
 C_SIGNAL='@t6g_mb_lib.t6g(sch_1):p12v_hsc_adc_p';
NODE_NAME     PR2513 1
 '@T6G_MB_LIB.T6G(SCH_1):PAGE302_I15@PURE_QUANTA.Q_RES(CHIPS)':
 'A': CDS_PINID='A';
NODE_NAME     PR2512 1
 '@T6G_MB_LIB.T6G(SCH_1):PAGE302_I16@PURE_QUANTA.Q_RES(CHIPS)':
 'A': CDS_PINID='A';
NODE_NAME     PR2511 1
 '@T6G_MB_LIB.T6G(SCH_1):PAGE302_I17@PURE_QUANTA.Q_RES(CHIPS)':
 'A': CDS_PINID='A';
NODE_NAME     PR2510 1
 '@T6G_MB_LIB.T6G(SCH_1):PAGE302_I18@PURE_QUANTA.Q_RES(CHIPS)':
 'A': CDS_PINID='A';
NODE_NAME     PJ38 7
 '@T6G_MB_LIB.T6G(SCH_1):PAGE371_I42@PURE_QUANTA.SCONN21_9193031121LF(CHIPS)':
 '7': CDS_PINID='\7\';
NODE_NAME     PR2514 1
 '@T6G_MB_LIB.T6G(SCH_1):PAGE302_I82@PURE_QUANTA.Q_RES(CHIPS)':
 'A': CDS_PINID='A';
NET_NAME
'P12V_HSC_GATE1'
 '@T6G_MB_LIB.T6G(SCH_1):P12V_HSC_GATE1':
 C_SIGNAL='@t6g_mb_lib.t6g(sch_1):p12v_hsc_gate1';
NODE_NAME     PR2538 2
 '@T6G_MB_LIB.T6G(SCH_1):PAGE302_I74@PURE_QUANTA.Q_RES(CHIPS)':
 'B': CDS_PINID='B';
NODE_NAME     PJ38 8
 '@T6G_MB_LIB.T6G(SCH_1):PAGE371_I42@PURE_QUANTA.SCONN21_9193031121LF(CHIPS)':
 '8': CDS_PINID='\8\';
NET_NAME
'P12V_HSC_GATE2'
 '@T6G_MB_LIB.T6G(SCH_1):P12V_HSC_GATE2':
 C_SIGNAL='@t6g_mb_lib.t6g(sch_1):p12v_hsc_gate2';
NODE_NAME     PR2528 2
 '@T6G_MB_LIB.T6G(SCH_1):PAGE302_I27@PURE_QUANTA.Q_RES(CHIPS)':
 'B': CDS_PINID='B';
NODE_NAME     PR2529 2
 '@T6G_MB_LIB.T6G(SCH_1):PAGE302_I28@PURE_QUANTA.Q_RES(CHIPS)':
 'B': CDS_PINID='B';
NODE_NAME     PR2530 2
 '@T6G_MB_LIB.T6G(SCH_1):PAGE302_I45@PURE_QUANTA.Q_RES(CHIPS)':
 'B': CDS_PINID='B';
NODE_NAME     PR2531 2
 '@T6G_MB_LIB.T6G(SCH_1):PAGE302_I47@PURE_QUANTA.Q_RES(CHIPS)':
 'B': CDS_PINID='B';
NODE_NAME     PR2535 2
 '@T6G_MB_LIB.T6G(SCH_1):PAGE302_I60@PURE_QUANTA.Q_RES(CHIPS)':
 'B': CDS_PINID='B';
NODE_NAME     PR2536 2
 '@T6G_MB_LIB.T6G(SCH_1):PAGE302_I62@PURE_QUANTA.Q_RES(CHIPS)':
 'B': CDS_PINID='B';
NODE_NAME     PC1750 2
 '@T6G_MB_LIB.T6G(SCH_1):PAGE302_I63@PURE_QUANTA.Q_CAP(CHIPS)':
 'B': CDS_PINID='B';
NODE_NAME     PC1751 2
 '@T6G_MB_LIB.T6G(SCH_1):PAGE302_I70@PURE_QUANTA.Q_CAP(CHIPS)':
 'B': CDS_PINID='B';
NODE_NAME     PJ38 9
 '@T6G_MB_LIB.T6G(SCH_1):PAGE371_I42@PURE_QUANTA.SCONN21_9193031121LF(CHIPS)':
 '9': CDS_PINID='\9\';
NET_NAME
'P12V_HSC_GATE_G1'
 '@T6G_MB_LIB.T6G(SCH_1):P12V_HSC_GATE_G1':
 C_SIGNAL='@t6g_mb_lib.t6g(sch_1):p12v_hsc_gate_g1';
NODE_NAME     PR2528 1
 '@T6G_MB_LIB.T6G(SCH_1):PAGE302_I27@PURE_QUANTA.Q_RES(CHIPS)':
 'A': CDS_PINID='A';
NODE_NAME     PPQ5 4
 '@T6G_MB_LIB.T6G(SCH_1):PAGE302_I29@PURE_QUANTA.MOSFET_NCH_1D3S(CHIPS)':
 '4': CDS_PINID='\4\';
NET_NAME
'P12V_HSC_GATE_G2'
 '@T6G_MB_LIB.T6G(SCH_1):P12V_HSC_GATE_G2':
 C_SIGNAL='@t6g_mb_lib.t6g(sch_1):p12v_hsc_gate_g2';
NODE_NAME     PR2529 1
 '@T6G_MB_LIB.T6G(SCH_1):PAGE302_I28@PURE_QUANTA.Q_RES(CHIPS)':
 'A': CDS_PINID='A';
NODE_NAME     PPQ6 4
 '@T6G_MB_LIB.T6G(SCH_1):PAGE302_I46@PURE_QUANTA.MOSFET_NCH_1D3S(CHIPS)':
 '4': CDS_PINID='\4\';
NET_NAME
'P12V_HSC_GATE_G3'
 '@T6G_MB_LIB.T6G(SCH_1):P12V_HSC_GATE_G3':
 C_SIGNAL='@t6g_mb_lib.t6g(sch_1):p12v_hsc_gate_g3';
NODE_NAME     PR2530 1
 '@T6G_MB_LIB.T6G(SCH_1):PAGE302_I45@PURE_QUANTA.Q_RES(CHIPS)':
 'A': CDS_PINID='A';
NODE_NAME     PPQ7 4
 '@T6G_MB_LIB.T6G(SCH_1):PAGE302_I80@PURE_QUANTA.MOSFET_NCH_1D3S(CHIPS)':
 '4': CDS_PINID='\4\';
NET_NAME
'P12V_HSC_GATE_G4'
 '@T6G_MB_LIB.T6G(SCH_1):P12V_HSC_GATE_G4':
 C_SIGNAL='@t6g_mb_lib.t6g(sch_1):p12v_hsc_gate_g4';
NODE_NAME     PR2531 1
 '@T6G_MB_LIB.T6G(SCH_1):PAGE302_I47@PURE_QUANTA.Q_RES(CHIPS)':
 'A': CDS_PINID='A';
NODE_NAME     PPQ8 4
 '@T6G_MB_LIB.T6G(SCH_1):PAGE302_I79@PURE_QUANTA.MOSFET_NCH_1D3S(CHIPS)':
 '4': CDS_PINID='\4\';
NET_NAME
'P12V_HSC_GATE_G5'
 '@T6G_MB_LIB.T6G(SCH_1):P12V_HSC_GATE_G5':
 C_SIGNAL='@t6g_mb_lib.t6g(sch_1):p12v_hsc_gate_g5';
NODE_NAME     PR2535 1
 '@T6G_MB_LIB.T6G(SCH_1):PAGE302_I60@PURE_QUANTA.Q_RES(CHIPS)':
 'A': CDS_PINID='A';
NODE_NAME     PPQ1 4
 '@T6G_MB_LIB.T6G(SCH_1):PAGE302_I61@PURE_QUANTA.MOSFET_NCH_1D3S(CHIPS)':
 '4': CDS_PINID='\4\';
NET_NAME
'P12V_HSC_GATE_G6'
 '@T6G_MB_LIB.T6G(SCH_1):P12V_HSC_GATE_G6':
 C_SIGNAL='@t6g_mb_lib.t6g(sch_1):p12v_hsc_gate_g6';
NODE_NAME     PR2536 1
 '@T6G_MB_LIB.T6G(SCH_1):PAGE302_I62@PURE_QUANTA.Q_RES(CHIPS)':
 'A': CDS_PINID='A';
NODE_NAME     PPQ2 4
 '@T6G_MB_LIB.T6G(SCH_1):PAGE302_I64@PURE_QUANTA.MOSFET_NCH_1D3S(CHIPS)':
 '4': CDS_PINID='\4\';
NET_NAME
'P12V_HSC_GATE_RC'
 '@T6G_MB_LIB.T6G(SCH_1):P12V_HSC_GATE_RC':
 C_SIGNAL='@t6g_mb_lib.t6g(sch_1):p12v_hsc_gate_rc';
NODE_NAME     PC1751 1
 '@T6G_MB_LIB.T6G(SCH_1):PAGE302_I70@PURE_QUANTA.Q_CAP(CHIPS)':
 'A': CDS_PINID='A';
NODE_NAME     PR2537 2
 '@T6G_MB_LIB.T6G(SCH_1):PAGE302_I71@PURE_QUANTA.Q_RES(CHIPS)':
 'B': CDS_PINID='B';
NET_NAME
'P12V_HSC_SENSE1_N'
 '@T6G_MB_LIB.T6G(SCH_1):P12V_HSC_SENSE1_N':
 C_SIGNAL='@t6g_mb_lib.t6g(sch_1):p12v_hsc_sense1_n';
NODE_NAME     PJ38 3
 '@T6G_MB_LIB.T6G(SCH_1):PAGE371_I42@PURE_QUANTA.SCONN21_9193031121LF(CHIPS)':
 '3': CDS_PINID='\3\';
NODE_NAME     PR6002 2B
 '@T6G_MB_LIB.T6G(SCH_1):PAGE302_I81@PURE_QUANTA.Q_SP_RES4P(CHIPS)':
 '2B': CDS_PINID='\2b\';
NODE_NAME     PR2519 2
 '@T6G_MB_LIB.T6G(SCH_1):PAGE302_I87@PURE_QUANTA.Q_RES(CHIPS)':
 'B': CDS_PINID='B';
NET_NAME
'P12V_HSC_SENSE1_P'
 '@T6G_MB_LIB.T6G(SCH_1):P12V_HSC_SENSE1_P':
 C_SIGNAL='@t6g_mb_lib.t6g(sch_1):p12v_hsc_sense1_p';
NODE_NAME     PJ38 2
 '@T6G_MB_LIB.T6G(SCH_1):PAGE371_I42@PURE_QUANTA.SCONN21_9193031121LF(CHIPS)':
 '2': CDS_PINID='\2\';
NODE_NAME     PR6002 1B
 '@T6G_MB_LIB.T6G(SCH_1):PAGE302_I81@PURE_QUANTA.Q_SP_RES4P(CHIPS)':
 '1B': CDS_PINID='\1b\';
NODE_NAME     PR2514 2
 '@T6G_MB_LIB.T6G(SCH_1):PAGE302_I82@PURE_QUANTA.Q_RES(CHIPS)':
 'B': CDS_PINID='B';
NET_NAME
'P12V_HSC_SENSE2_N'
 '@T6G_MB_LIB.T6G(SCH_1):P12V_HSC_SENSE2_N':
 C_SIGNAL='@t6g_mb_lib.t6g(sch_1):p12v_hsc_sense2_n';
NODE_NAME     PJ38 5
 '@T6G_MB_LIB.T6G(SCH_1):PAGE371_I42@PURE_QUANTA.SCONN21_9193031121LF(CHIPS)':
 '5': CDS_PINID='\5\';
NODE_NAME     PR2524 1
 '@T6G_MB_LIB.T6G(SCH_1):PAGE302_I88@PURE_QUANTA.Q_RES(CHIPS)':
 'A': CDS_PINID='A';
NODE_NAME     PR2525 1
 '@T6G_MB_LIB.T6G(SCH_1):PAGE302_I89@PURE_QUANTA.Q_RES(CHIPS)':
 'A': CDS_PINID='A';
NODE_NAME     PR2526 1
 '@T6G_MB_LIB.T6G(SCH_1):PAGE302_I90@PURE_QUANTA.Q_RES(CHIPS)':
 'A': CDS_PINID='A';
NODE_NAME     PR2527 1
 '@T6G_MB_LIB.T6G(SCH_1):PAGE302_I91@PURE_QUANTA.Q_RES(CHIPS)':
 'A': CDS_PINID='A';
NET_NAME
'P12V_HSC_SENSE2_P'
 '@T6G_MB_LIB.T6G(SCH_1):P12V_HSC_SENSE2_P':
 C_SIGNAL='@t6g_mb_lib.t6g(sch_1):p12v_hsc_sense2_p';
NODE_NAME     PR2523 1
 '@T6G_MB_LIB.T6G(SCH_1):PAGE302_I5@PURE_QUANTA.Q_RES(CHIPS)':
 'A': CDS_PINID='A';
NODE_NAME     PR2521 1
 '@T6G_MB_LIB.T6G(SCH_1):PAGE302_I6@PURE_QUANTA.Q_RES(CHIPS)':
 'A': CDS_PINID='A';
NODE_NAME     PR2522 1
 '@T6G_MB_LIB.T6G(SCH_1):PAGE302_I7@PURE_QUANTA.Q_RES(CHIPS)':
 'A': CDS_PINID='A';
NODE_NAME     PR2520 1
 '@T6G_MB_LIB.T6G(SCH_1):PAGE302_I8@PURE_QUANTA.Q_RES(CHIPS)':
 'A': CDS_PINID='A';
NODE_NAME     PJ38 4
 '@T6G_MB_LIB.T6G(SCH_1):PAGE371_I42@PURE_QUANTA.SCONN21_9193031121LF(CHIPS)':
 '4': CDS_PINID='\4\';
NET_NAME
'P12V_HSC_SENSE2_R1_N'
 '@T6G_MB_LIB.T6G(SCH_1):P12V_HSC_SENSE2_R1_N':
 C_SIGNAL='@t6g_mb_lib.t6g(sch_1):p12v_hsc_sense2_r1_n';
NODE_NAME     PR6001 2B
 '@T6G_MB_LIB.T6G(SCH_1):PAGE302_I55@PURE_QUANTA.Q_SP_RES4P(CHIPS)':
 '2B': CDS_PINID='\2b\';
NODE_NAME     PR2515 2
 '@T6G_MB_LIB.T6G(SCH_1):PAGE302_I83@PURE_QUANTA.Q_RES(CHIPS)':
 'B': CDS_PINID='B';
NODE_NAME     PR2524 2
 '@T6G_MB_LIB.T6G(SCH_1):PAGE302_I88@PURE_QUANTA.Q_RES(CHIPS)':
 'B': CDS_PINID='B';
NET_NAME
'P12V_HSC_SENSE2_R1_P'
 '@T6G_MB_LIB.T6G(SCH_1):P12V_HSC_SENSE2_R1_P':
 C_SIGNAL='@t6g_mb_lib.t6g(sch_1):p12v_hsc_sense2_r1_p';
NODE_NAME     PR2520 2
 '@T6G_MB_LIB.T6G(SCH_1):PAGE302_I8@PURE_QUANTA.Q_RES(CHIPS)':
 'B': CDS_PINID='B';
NODE_NAME     PR2510 2
 '@T6G_MB_LIB.T6G(SCH_1):PAGE302_I18@PURE_QUANTA.Q_RES(CHIPS)':
 'B': CDS_PINID='B';
NODE_NAME     PR6001 1B
 '@T6G_MB_LIB.T6G(SCH_1):PAGE302_I55@PURE_QUANTA.Q_SP_RES4P(CHIPS)':
 '1B': CDS_PINID='\1b\';
NET_NAME
'P12V_HSC_SENSE2_R2_N'
 '@T6G_MB_LIB.T6G(SCH_1):P12V_HSC_SENSE2_R2_N':
 C_SIGNAL='@t6g_mb_lib.t6g(sch_1):p12v_hsc_sense2_r2_n';
NODE_NAME     PR2532 2B
 '@T6G_MB_LIB.T6G(SCH_1):PAGE302_I54@PURE_QUANTA.Q_SP_RES4P(CHIPS)':
 '2B': CDS_PINID='\2b\';
NODE_NAME     PR2516 2
 '@T6G_MB_LIB.T6G(SCH_1):PAGE302_I84@PURE_QUANTA.Q_RES(CHIPS)':
 'B': CDS_PINID='B';
NODE_NAME     PR2525 2
 '@T6G_MB_LIB.T6G(SCH_1):PAGE302_I89@PURE_QUANTA.Q_RES(CHIPS)':
 'B': CDS_PINID='B';
NET_NAME
'P12V_HSC_SENSE2_R2_P'
 '@T6G_MB_LIB.T6G(SCH_1):P12V_HSC_SENSE2_R2_P':
 C_SIGNAL='@t6g_mb_lib.t6g(sch_1):p12v_hsc_sense2_r2_p';
NODE_NAME     PR2521 2
 '@T6G_MB_LIB.T6G(SCH_1):PAGE302_I6@PURE_QUANTA.Q_RES(CHIPS)':
 'B': CDS_PINID='B';
NODE_NAME     PR2511 2
 '@T6G_MB_LIB.T6G(SCH_1):PAGE302_I17@PURE_QUANTA.Q_RES(CHIPS)':
 'B': CDS_PINID='B';
NODE_NAME     PR2532 1B
 '@T6G_MB_LIB.T6G(SCH_1):PAGE302_I54@PURE_QUANTA.Q_SP_RES4P(CHIPS)':
 '1B': CDS_PINID='\1b\';
NET_NAME
'P12V_HSC_SENSE2_R3_N'
 '@T6G_MB_LIB.T6G(SCH_1):P12V_HSC_SENSE2_R3_N':
 C_SIGNAL='@t6g_mb_lib.t6g(sch_1):p12v_hsc_sense2_r3_n';
NODE_NAME     PR2533 2B
 '@T6G_MB_LIB.T6G(SCH_1):PAGE302_I53@PURE_QUANTA.Q_SP_RES4P(CHIPS)':
 '2B': CDS_PINID='\2b\';
NODE_NAME     PR2517 2
 '@T6G_MB_LIB.T6G(SCH_1):PAGE302_I85@PURE_QUANTA.Q_RES(CHIPS)':
 'B': CDS_PINID='B';
NODE_NAME     PR2526 2
 '@T6G_MB_LIB.T6G(SCH_1):PAGE302_I90@PURE_QUANTA.Q_RES(CHIPS)':
 'B': CDS_PINID='B';
NET_NAME
'P12V_HSC_SENSE2_R3_P'
 '@T6G_MB_LIB.T6G(SCH_1):P12V_HSC_SENSE2_R3_P':
 C_SIGNAL='@t6g_mb_lib.t6g(sch_1):p12v_hsc_sense2_r3_p';
NODE_NAME     PR2522 2
 '@T6G_MB_LIB.T6G(SCH_1):PAGE302_I7@PURE_QUANTA.Q_RES(CHIPS)':
 'B': CDS_PINID='B';
NODE_NAME     PR2512 2
 '@T6G_MB_LIB.T6G(SCH_1):PAGE302_I16@PURE_QUANTA.Q_RES(CHIPS)':
 'B': CDS_PINID='B';
NODE_NAME     PR2533 1B
 '@T6G_MB_LIB.T6G(SCH_1):PAGE302_I53@PURE_QUANTA.Q_SP_RES4P(CHIPS)':
 '1B': CDS_PINID='\1b\';
NET_NAME
'P12V_HSC_SENSE2_R4_N'
 '@T6G_MB_LIB.T6G(SCH_1):P12V_HSC_SENSE2_R4_N':
 C_SIGNAL='@t6g_mb_lib.t6g(sch_1):p12v_hsc_sense2_r4_n';
NODE_NAME     PR2534 2B
 '@T6G_MB_LIB.T6G(SCH_1):PAGE302_I52@PURE_QUANTA.Q_SP_RES4P(CHIPS)':
 '2B': CDS_PINID='\2b\';
NODE_NAME     PR2518 2
 '@T6G_MB_LIB.T6G(SCH_1):PAGE302_I86@PURE_QUANTA.Q_RES(CHIPS)':
 'B': CDS_PINID='B';
NODE_NAME     PR2527 2
 '@T6G_MB_LIB.T6G(SCH_1):PAGE302_I91@PURE_QUANTA.Q_RES(CHIPS)':
 'B': CDS_PINID='B';
NET_NAME
'P12V_HSC_SENSE2_R4_P'
 '@T6G_MB_LIB.T6G(SCH_1):P12V_HSC_SENSE2_R4_P':
 C_SIGNAL='@t6g_mb_lib.t6g(sch_1):p12v_hsc_sense2_r4_p';
NODE_NAME     PR2523 2
 '@T6G_MB_LIB.T6G(SCH_1):PAGE302_I5@PURE_QUANTA.Q_RES(CHIPS)':
 'B': CDS_PINID='B';
NODE_NAME     PR2513 2
 '@T6G_MB_LIB.T6G(SCH_1):PAGE302_I15@PURE_QUANTA.Q_RES(CHIPS)':
 'B': CDS_PINID='B';
NODE_NAME     PR2534 1B
 '@T6G_MB_LIB.T6G(SCH_1):PAGE302_I52@PURE_QUANTA.Q_SP_RES4P(CHIPS)':
 '1B': CDS_PINID='\1b\';
NET_NAME
'P12V_HSC_TEMP_ALERT_N'
 '@T6G_MB_LIB.T6G(SCH_1):P12V_HSC_TEMP_ALERT_N':
 C_SIGNAL='@t6g_mb_lib.t6g(sch_1):p12v_hsc_temp_alert_n';
NODE_NAME     U143 6
 '@T6G_MB_LIB.T6G(SCH_1):PAGE371_I8@PURE_QUANTA.NCT7718W(CHIPS)':
 'ALERT#': CDS_PINID='\alert#\';
NODE_NAME     R2628 1
 '@T6G_MB_LIB.T6G(SCH_1):PAGE371_I10@PURE_QUANTA.Q_RES(CHIPS)':
 'A': CDS_PINID='A';
NET_NAME
'P12V_HSC_TEMP_ALERT_R_N'
 '@T6G_MB_LIB.T6G(SCH_1):P12V_HSC_TEMP_ALERT_R_N':
 C_SIGNAL='@t6g_mb_lib.t6g(sch_1):p12v_hsc_temp_alert_r_n';
NODE_NAME     U18 N7
 '@T6G_MB_LIB.T6G(SCH_1):PAGE81_I143@PURE_QUANTA.LCMXO3LF9400C5BG484C(CHIPS)':
 'PL20D': CDS_PINID='PL20D';
NODE_NAME     R2628 2
 '@T6G_MB_LIB.T6G(SCH_1):PAGE371_I10@PURE_QUANTA.Q_RES(CHIPS)':
 'B': CDS_PINID='B';
NODE_NAME     R355 2
 '@T6G_MB_LIB.T6G(SCH_1):PAGE371_I79@PURE_QUANTA.Q_RES(CHIPS)':
 'B': CDS_PINID='B';
NET_NAME
'P12V_HSC_TEMP_D+'
 '@T6G_MB_LIB.T6G(SCH_1):P12V_HSC_TEMP_D+':
 C_SIGNAL='@t6g_mb_lib.t6g(sch_1):\p12v_hsc_temp_d+\';
NODE_NAME     R2625 2
 '@T6G_MB_LIB.T6G(SCH_1):PAGE371_I3@PURE_QUANTA.Q_RES(CHIPS)':
 'B': CDS_PINID='B';
NODE_NAME     C1786 1
 '@T6G_MB_LIB.T6G(SCH_1):PAGE371_I4@PURE_QUANTA.Q_CAP(CHIPS)':
 'A': CDS_PINID='A';
NODE_NAME     U143 2
 '@T6G_MB_LIB.T6G(SCH_1):PAGE371_I8@PURE_QUANTA.NCT7718W(CHIPS)':
 'D+': CDS_PINID='\d+\';
NET_NAME
'P12V_HSC_TEMP_D-'
 '@T6G_MB_LIB.T6G(SCH_1):P12V_HSC_TEMP_D-':
 C_SIGNAL='@t6g_mb_lib.t6g(sch_1):\p12v_hsc_temp_d-\';
NODE_NAME     R2624 2
 '@T6G_MB_LIB.T6G(SCH_1):PAGE371_I2@PURE_QUANTA.Q_RES(CHIPS)':
 'B': CDS_PINID='B';
NODE_NAME     C1786 2
 '@T6G_MB_LIB.T6G(SCH_1):PAGE371_I4@PURE_QUANTA.Q_CAP(CHIPS)':
 'B': CDS_PINID='B';
NODE_NAME     U143 3
 '@T6G_MB_LIB.T6G(SCH_1):PAGE371_I8@PURE_QUANTA.NCT7718W(CHIPS)':
 'D-': CDS_PINID='\d-\';
NET_NAME
'P12V_HSC_TEMP_E'
 '@T6G_MB_LIB.T6G(SCH_1):P12V_HSC_TEMP_E':
 C_SIGNAL='@t6g_mb_lib.t6g(sch_1):p12v_hsc_temp_e';
NODE_NAME     Q6001 E
 '@T6G_MB_LIB.T6G(SCH_1):PAGE371_I1@PURE_QUANTA.METR3904G(CHIPS)':
 '2': CDS_PINID='\2\';
NODE_NAME     R2624 1
 '@T6G_MB_LIB.T6G(SCH_1):PAGE371_I2@PURE_QUANTA.Q_RES(CHIPS)':
 'A': CDS_PINID='A';
NET_NAME
'P12V_HSC_TEMP_R'
 '@T6G_MB_LIB.T6G(SCH_1):P12V_HSC_TEMP_R':
 C_SIGNAL='@t6g_mb_lib.t6g(sch_1):p12v_hsc_temp_r';
NODE_NAME     Q6001 B
 '@T6G_MB_LIB.T6G(SCH_1):PAGE371_I1@PURE_QUANTA.METR3904G(CHIPS)':
 '1': CDS_PINID='\1\';
NODE_NAME     Q6001 C
 '@T6G_MB_LIB.T6G(SCH_1):PAGE371_I1@PURE_QUANTA.METR3904G(CHIPS)':
 '3': CDS_PINID='\3\';
NODE_NAME     R2625 1
 '@T6G_MB_LIB.T6G(SCH_1):PAGE371_I3@PURE_QUANTA.Q_RES(CHIPS)':
 'A': CDS_PINID='A';
NET_NAME
'P12V_HSC_T_CRIT_N'
 '@T6G_MB_LIB.T6G(SCH_1):P12V_HSC_T_CRIT_N':
 C_SIGNAL='@t6g_mb_lib.t6g(sch_1):p12v_hsc_t_crit_n';
NODE_NAME     U143 4
 '@T6G_MB_LIB.T6G(SCH_1):PAGE371_I8@PURE_QUANTA.NCT7718W(CHIPS)':
 'T_CRIT#': CDS_PINID='\t_crit#\';
NODE_NAME     R353 1
 '@T6G_MB_LIB.T6G(SCH_1):PAGE371_I74@PURE_QUANTA.Q_RES(CHIPS)':
 'A': CDS_PINID='A';
NET_NAME
'P12V_HSC_T_CRIT_R_N'
 '@T6G_MB_LIB.T6G(SCH_1):P12V_HSC_T_CRIT_R_N':
 C_SIGNAL='@t6g_mb_lib.t6g(sch_1):p12v_hsc_t_crit_r_n';
NODE_NAME     U18 K4
 '@T6G_MB_LIB.T6G(SCH_1):PAGE81_I143@PURE_QUANTA.LCMXO3LF9400C5BG484C(CHIPS)':
 'PL13C': CDS_PINID='PL13C';
NODE_NAME     R353 2
 '@T6G_MB_LIB.T6G(SCH_1):PAGE371_I74@PURE_QUANTA.Q_RES(CHIPS)':
 'B': CDS_PINID='B';
NODE_NAME     R354 2
 '@T6G_MB_LIB.T6G(SCH_1):PAGE371_I76@PURE_QUANTA.Q_RES(CHIPS)':
 'B': CDS_PINID='B';
NET_NAME
'P12V_MAIN_R'
 '@T6G_MB_LIB.T6G(SCH_1):P12V_MAIN_R':
 C_SIGNAL='@t6g_mb_lib.t6g(sch_1):p12v_main_r',
 CDS_GLOBAL_NET='TRUE';
NODE_NAME     PPQ5 5
 '@T6G_MB_LIB.T6G(SCH_1):PAGE302_I29@PURE_QUANTA.MOSFET_NCH_1D3S(CHIPS)':
 '5': CDS_PINID='\5\';
NODE_NAME     PPQ6 5
 '@T6G_MB_LIB.T6G(SCH_1):PAGE302_I46@PURE_QUANTA.MOSFET_NCH_1D3S(CHIPS)':
 '5': CDS_PINID='\5\';
NODE_NAME     PR2534 2A
 '@T6G_MB_LIB.T6G(SCH_1):PAGE302_I52@PURE_QUANTA.Q_SP_RES4P(CHIPS)':
 '2A': CDS_PINID='\2a\';
NODE_NAME     PR2533 2A
 '@T6G_MB_LIB.T6G(SCH_1):PAGE302_I53@PURE_QUANTA.Q_SP_RES4P(CHIPS)':
 '2A': CDS_PINID='\2a\';
NODE_NAME     PR2532 2A
 '@T6G_MB_LIB.T6G(SCH_1):PAGE302_I54@PURE_QUANTA.Q_SP_RES4P(CHIPS)':
 '2A': CDS_PINID='\2a\';
NODE_NAME     PR6001 2A
 '@T6G_MB_LIB.T6G(SCH_1):PAGE302_I55@PURE_QUANTA.Q_SP_RES4P(CHIPS)':
 '2A': CDS_PINID='\2a\';
NODE_NAME     PPQ1 5
 '@T6G_MB_LIB.T6G(SCH_1):PAGE302_I61@PURE_QUANTA.MOSFET_NCH_1D3S(CHIPS)':
 '5': CDS_PINID='\5\';
NODE_NAME     PPQ2 5
 '@T6G_MB_LIB.T6G(SCH_1):PAGE302_I64@PURE_QUANTA.MOSFET_NCH_1D3S(CHIPS)':
 '5': CDS_PINID='\5\';
NODE_NAME     PPQ8 5
 '@T6G_MB_LIB.T6G(SCH_1):PAGE302_I79@PURE_QUANTA.MOSFET_NCH_1D3S(CHIPS)':
 '5': CDS_PINID='\5\';
NODE_NAME     PPQ7 5
 '@T6G_MB_LIB.T6G(SCH_1):PAGE302_I80@PURE_QUANTA.MOSFET_NCH_1D3S(CHIPS)':
 '5': CDS_PINID='\5\';
NET_NAME
'P12V_MAIN_R_0'
 '@T6G_MB_LIB.T6G(SCH_1):P12V_MAIN_R_0':
 C_SIGNAL='@t6g_mb_lib.t6g(sch_1):p12v_main_r_0',
 CDS_GLOBAL_NET='TRUE';
NODE_NAME     PPQ9 5
 '@T6G_MB_LIB.T6G(SCH_1):PAGE302_I75@PURE_QUANTA.MOSFET_NCH_1D3S(CHIPS)':
 '5': CDS_PINID='\5\';
NODE_NAME     PR6002 2A
 '@T6G_MB_LIB.T6G(SCH_1):PAGE302_I81@PURE_QUANTA.Q_SP_RES4P(CHIPS)':
 '2A': CDS_PINID='\2a\';
NET_NAME
'P12V_MEM_CPU0'
 '@T6G_MB_LIB.T6G(SCH_1):P12V_MEM_CPU0':
 C_SIGNAL='@t6g_mb_lib.t6g(sch_1):p12v_mem_cpu0',
 CDS_GLOBAL_NET='TRUE';
NODE_NAME     C89 1
 '@T6G_MB_LIB.T6G(SCH_1):PAGE85_I519@PURE_QUANTA.Q_CAP(CHIPS)':
 'A': CDS_PINID='A';
NODE_NAME     C142 1
 '@T6G_MB_LIB.T6G(SCH_1):PAGE85_I534@PURE_QUANTA.Q_CAP(CHIPS)':
 'A': CDS_PINID='A';
NODE_NAME     J15 1
 '@T6G_MB_LIB.T6G(SCH_1):PAGE86_I352@PURE_QUANTA.SCONN288_DDR506112002KQ(CHIPS)':
 'VIN_BULK0': CDS_PINID='VIN_BULK0';
NODE_NAME     J15 145
 '@T6G_MB_LIB.T6G(SCH_1):PAGE86_I352@PURE_QUANTA.SCONN288_DDR506112002KQ(CHIPS)':
 'VIN_BULK1': CDS_PINID='VIN_BULK1';
NODE_NAME     J15 146
 '@T6G_MB_LIB.T6G(SCH_1):PAGE86_I352@PURE_QUANTA.SCONN288_DDR506112002KQ(CHIPS)':
 'VIN_BULK2': CDS_PINID='VIN_BULK2';
NODE_NAME     C143 1
 '@T6G_MB_LIB.T6G(SCH_1):PAGE86_I369@PURE_QUANTA.Q_CAP(CHIPS)':
 'A': CDS_PINID='A';
NODE_NAME     C145 1
 '@T6G_MB_LIB.T6G(SCH_1):PAGE86_I370@PURE_QUANTA.Q_CAP(CHIPS)':
 'A': CDS_PINID='A';
NODE_NAME     J17 1
 '@T6G_MB_LIB.T6G(SCH_1):PAGE87_I352@PURE_QUANTA.SCONN288_DDR506112002KQ(CHIPS)':
 'VIN_BULK0': CDS_PINID='VIN_BULK0';
NODE_NAME     J17 145
 '@T6G_MB_LIB.T6G(SCH_1):PAGE87_I352@PURE_QUANTA.SCONN288_DDR506112002KQ(CHIPS)':
 'VIN_BULK1': CDS_PINID='VIN_BULK1';
NODE_NAME     J17 146
 '@T6G_MB_LIB.T6G(SCH_1):PAGE87_I352@PURE_QUANTA.SCONN288_DDR506112002KQ(CHIPS)':
 'VIN_BULK2': CDS_PINID='VIN_BULK2';
NODE_NAME     C146 1
 '@T6G_MB_LIB.T6G(SCH_1):PAGE87_I413@PURE_QUANTA.Q_CAP(CHIPS)':
 'A': CDS_PINID='A';
NODE_NAME     C147 1
 '@T6G_MB_LIB.T6G(SCH_1):PAGE87_I414@PURE_QUANTA.Q_CAP(CHIPS)':
 'A': CDS_PINID='A';
NODE_NAME     J19 1
 '@T6G_MB_LIB.T6G(SCH_1):PAGE88_I352@PURE_QUANTA.SCONN288_DDR506112002KQ(CHIPS)':
 'VIN_BULK0': CDS_PINID='VIN_BULK0';
NODE_NAME     J19 145
 '@T6G_MB_LIB.T6G(SCH_1):PAGE88_I352@PURE_QUANTA.SCONN288_DDR506112002KQ(CHIPS)':
 'VIN_BULK1': CDS_PINID='VIN_BULK1';
NODE_NAME     J19 146
 '@T6G_MB_LIB.T6G(SCH_1):PAGE88_I352@PURE_QUANTA.SCONN288_DDR506112002KQ(CHIPS)':
 'VIN_BULK2': CDS_PINID='VIN_BULK2';
NODE_NAME     C149 1
 '@T6G_MB_LIB.T6G(SCH_1):PAGE88_I417@PURE_QUANTA.Q_CAP(CHIPS)':
 'A': CDS_PINID='A';
NODE_NAME     C150 1
 '@T6G_MB_LIB.T6G(SCH_1):PAGE88_I418@PURE_QUANTA.Q_CAP(CHIPS)':
 'A': CDS_PINID='A';
NODE_NAME     J21 1
 '@T6G_MB_LIB.T6G(SCH_1):PAGE89_I350@PURE_QUANTA.SCONN288_DDR506112002KQ(CHIPS)':
 'VIN_BULK0': CDS_PINID='VIN_BULK0';
NODE_NAME     J21 145
 '@T6G_MB_LIB.T6G(SCH_1):PAGE89_I350@PURE_QUANTA.SCONN288_DDR506112002KQ(CHIPS)':
 'VIN_BULK1': CDS_PINID='VIN_BULK1';
NODE_NAME     J21 146
 '@T6G_MB_LIB.T6G(SCH_1):PAGE89_I350@PURE_QUANTA.SCONN288_DDR506112002KQ(CHIPS)':
 'VIN_BULK2': CDS_PINID='VIN_BULK2';
NODE_NAME     C151 1
 '@T6G_MB_LIB.T6G(SCH_1):PAGE89_I412@PURE_QUANTA.Q_CAP(CHIPS)':
 'A': CDS_PINID='A';
NODE_NAME     C153 1
 '@T6G_MB_LIB.T6G(SCH_1):PAGE89_I413@PURE_QUANTA.Q_CAP(CHIPS)':
 'A': CDS_PINID='A';
NODE_NAME     J23 1
 '@T6G_MB_LIB.T6G(SCH_1):PAGE90_I352@PURE_QUANTA.SCONN288_DDR506112002KQ(CHIPS)':
 'VIN_BULK0': CDS_PINID='VIN_BULK0';
NODE_NAME     J23 145
 '@T6G_MB_LIB.T6G(SCH_1):PAGE90_I352@PURE_QUANTA.SCONN288_DDR506112002KQ(CHIPS)':
 'VIN_BULK1': CDS_PINID='VIN_BULK1';
NODE_NAME     J23 146
 '@T6G_MB_LIB.T6G(SCH_1):PAGE90_I352@PURE_QUANTA.SCONN288_DDR506112002KQ(CHIPS)':
 'VIN_BULK2': CDS_PINID='VIN_BULK2';
NODE_NAME     C154 1
 '@T6G_MB_LIB.T6G(SCH_1):PAGE90_I414@PURE_QUANTA.Q_CAP(CHIPS)':
 'A': CDS_PINID='A';
NODE_NAME     C155 1
 '@T6G_MB_LIB.T6G(SCH_1):PAGE90_I415@PURE_QUANTA.Q_CAP(CHIPS)':
 'A': CDS_PINID='A';
NODE_NAME     J16 1
 '@T6G_MB_LIB.T6G(SCH_1):PAGE91_I177@PURE_QUANTA.SCONN288_DDR506112002KQ(CHIPS)':
 'VIN_BULK0': CDS_PINID='VIN_BULK0';
NODE_NAME     J16 145
 '@T6G_MB_LIB.T6G(SCH_1):PAGE91_I177@PURE_QUANTA.SCONN288_DDR506112002KQ(CHIPS)':
 'VIN_BULK1': CDS_PINID='VIN_BULK1';
NODE_NAME     J16 146
 '@T6G_MB_LIB.T6G(SCH_1):PAGE91_I177@PURE_QUANTA.SCONN288_DDR506112002KQ(CHIPS)':
 'VIN_BULK2': CDS_PINID='VIN_BULK2';
NODE_NAME     C157 1
 '@T6G_MB_LIB.T6G(SCH_1):PAGE91_I238@PURE_QUANTA.Q_CAP(CHIPS)':
 'A': CDS_PINID='A';
NODE_NAME     C158 1
 '@T6G_MB_LIB.T6G(SCH_1):PAGE91_I239@PURE_QUANTA.Q_CAP(CHIPS)':
 'A': CDS_PINID='A';
NODE_NAME     J69 1
 '@T6G_MB_LIB.T6G(SCH_1):PAGE92_I177@PURE_QUANTA.SCONN288_DDR506112002KQ(CHIPS)':
 'VIN_BULK0': CDS_PINID='VIN_BULK0';
NODE_NAME     J69 145
 '@T6G_MB_LIB.T6G(SCH_1):PAGE92_I177@PURE_QUANTA.SCONN288_DDR506112002KQ(CHIPS)':
 'VIN_BULK1': CDS_PINID='VIN_BULK1';
NODE_NAME     J69 146
 '@T6G_MB_LIB.T6G(SCH_1):PAGE92_I177@PURE_QUANTA.SCONN288_DDR506112002KQ(CHIPS)':
 'VIN_BULK2': CDS_PINID='VIN_BULK2';
NODE_NAME     C159 1
 '@T6G_MB_LIB.T6G(SCH_1):PAGE92_I239@PURE_QUANTA.Q_CAP(CHIPS)':
 'A': CDS_PINID='A';
NODE_NAME     C161 1
 '@T6G_MB_LIB.T6G(SCH_1):PAGE92_I240@PURE_QUANTA.Q_CAP(CHIPS)':
 'A': CDS_PINID='A';
NODE_NAME     J18 1
 '@T6G_MB_LIB.T6G(SCH_1):PAGE93_I143@PURE_QUANTA.SCONN288_DDR506112002KQ(CHIPS)':
 'VIN_BULK0': CDS_PINID='VIN_BULK0';
NODE_NAME     J18 145
 '@T6G_MB_LIB.T6G(SCH_1):PAGE93_I143@PURE_QUANTA.SCONN288_DDR506112002KQ(CHIPS)':
 'VIN_BULK1': CDS_PINID='VIN_BULK1';
NODE_NAME     J18 146
 '@T6G_MB_LIB.T6G(SCH_1):PAGE93_I143@PURE_QUANTA.SCONN288_DDR506112002KQ(CHIPS)':
 'VIN_BULK2': CDS_PINID='VIN_BULK2';
NODE_NAME     C162 1
 '@T6G_MB_LIB.T6G(SCH_1):PAGE93_I238@PURE_QUANTA.Q_CAP(CHIPS)':
 'A': CDS_PINID='A';
NODE_NAME     C163 1
 '@T6G_MB_LIB.T6G(SCH_1):PAGE93_I239@PURE_QUANTA.Q_CAP(CHIPS)':
 'A': CDS_PINID='A';
NODE_NAME     J68 1
 '@T6G_MB_LIB.T6G(SCH_1):PAGE94_I177@PURE_QUANTA.SCONN288_DDR506112002KQ(CHIPS)':
 'VIN_BULK0': CDS_PINID='VIN_BULK0';
NODE_NAME     J68 145
 '@T6G_MB_LIB.T6G(SCH_1):PAGE94_I177@PURE_QUANTA.SCONN288_DDR506112002KQ(CHIPS)':
 'VIN_BULK1': CDS_PINID='VIN_BULK1';
NODE_NAME     J68 146
 '@T6G_MB_LIB.T6G(SCH_1):PAGE94_I177@PURE_QUANTA.SCONN288_DDR506112002KQ(CHIPS)':
 'VIN_BULK2': CDS_PINID='VIN_BULK2';
NODE_NAME     C165 1
 '@T6G_MB_LIB.T6G(SCH_1):PAGE94_I238@PURE_QUANTA.Q_CAP(CHIPS)':
 'A': CDS_PINID='A';
NODE_NAME     C166 1
 '@T6G_MB_LIB.T6G(SCH_1):PAGE94_I239@PURE_QUANTA.Q_CAP(CHIPS)':
 'A': CDS_PINID='A';
NODE_NAME     J20 1
 '@T6G_MB_LIB.T6G(SCH_1):PAGE95_I177@PURE_QUANTA.SCONN288_DDR506112002KQ(CHIPS)':
 'VIN_BULK0': CDS_PINID='VIN_BULK0';
NODE_NAME     J20 145
 '@T6G_MB_LIB.T6G(SCH_1):PAGE95_I177@PURE_QUANTA.SCONN288_DDR506112002KQ(CHIPS)':
 'VIN_BULK1': CDS_PINID='VIN_BULK1';
NODE_NAME     J20 146
 '@T6G_MB_LIB.T6G(SCH_1):PAGE95_I177@PURE_QUANTA.SCONN288_DDR506112002KQ(CHIPS)':
 'VIN_BULK2': CDS_PINID='VIN_BULK2';
NODE_NAME     C167 1
 '@T6G_MB_LIB.T6G(SCH_1):PAGE95_I238@PURE_QUANTA.Q_CAP(CHIPS)':
 'A': CDS_PINID='A';
NODE_NAME     C169 1
 '@T6G_MB_LIB.T6G(SCH_1):PAGE95_I239@PURE_QUANTA.Q_CAP(CHIPS)':
 'A': CDS_PINID='A';
NODE_NAME     J67 1
 '@T6G_MB_LIB.T6G(SCH_1):PAGE96_I140@PURE_QUANTA.SCONN288_DDR506112002KQ(CHIPS)':
 'VIN_BULK0': CDS_PINID='VIN_BULK0';
NODE_NAME     J67 145
 '@T6G_MB_LIB.T6G(SCH_1):PAGE96_I140@PURE_QUANTA.SCONN288_DDR506112002KQ(CHIPS)':
 'VIN_BULK1': CDS_PINID='VIN_BULK1';
NODE_NAME     J67 146
 '@T6G_MB_LIB.T6G(SCH_1):PAGE96_I140@PURE_QUANTA.SCONN288_DDR506112002KQ(CHIPS)':
 'VIN_BULK2': CDS_PINID='VIN_BULK2';
NODE_NAME     C170 1
 '@T6G_MB_LIB.T6G(SCH_1):PAGE96_I238@PURE_QUANTA.Q_CAP(CHIPS)':
 'A': CDS_PINID='A';
NODE_NAME     C171 1
 '@T6G_MB_LIB.T6G(SCH_1):PAGE96_I239@PURE_QUANTA.Q_CAP(CHIPS)':
 'A': CDS_PINID='A';
NODE_NAME     J1 1
 '@T6G_MB_LIB.T6G(SCH_1):PAGE85_I538@PURE_QUANTA.SCONN288_DDR506112002KQ(CHIPS)':
 'VIN_BULK0': CDS_PINID='VIN_BULK0';
NODE_NAME     J1 145
 '@T6G_MB_LIB.T6G(SCH_1):PAGE85_I538@PURE_QUANTA.SCONN288_DDR506112002KQ(CHIPS)':
 'VIN_BULK1': CDS_PINID='VIN_BULK1';
NODE_NAME     J1 146
 '@T6G_MB_LIB.T6G(SCH_1):PAGE85_I538@PURE_QUANTA.SCONN288_DDR506112002KQ(CHIPS)':
 'VIN_BULK2': CDS_PINID='VIN_BULK2';
NODE_NAME     R1442 1
 '@T6G_MB_LIB.T6G(SCH_1):PAGE264_I30@PURE_QUANTA.Q_RES(CHIPS)':
 'A': CDS_PINID='A';
NODE_NAME     R1838 2
 '@T6G_MB_LIB.T6G(SCH_1):PAGE264_I58@PURE_QUANTA.Q_RES_4P_12(CHIPS)':
 '2': CDS_PINID='\2\';
NET_NAME
'P12V_MEM_CPU1'
 '@T6G_MB_LIB.T6G(SCH_1):P12V_MEM_CPU1':
 C_SIGNAL='@t6g_mb_lib.t6g(sch_1):p12v_mem_cpu1',
 CDS_GLOBAL_NET='TRUE';
NODE_NAME     J24 1
 '@T6G_MB_LIB.T6G(SCH_1):PAGE97_I177@PURE_QUANTA.SCONN288_DDR506112002KQ(CHIPS)':
 'VIN_BULK0': CDS_PINID='VIN_BULK0';
NODE_NAME     J24 145
 '@T6G_MB_LIB.T6G(SCH_1):PAGE97_I177@PURE_QUANTA.SCONN288_DDR506112002KQ(CHIPS)':
 'VIN_BULK1': CDS_PINID='VIN_BULK1';
NODE_NAME     J24 146
 '@T6G_MB_LIB.T6G(SCH_1):PAGE97_I177@PURE_QUANTA.SCONN288_DDR506112002KQ(CHIPS)':
 'VIN_BULK2': CDS_PINID='VIN_BULK2';
NODE_NAME     C173 1
 '@T6G_MB_LIB.T6G(SCH_1):PAGE97_I240@PURE_QUANTA.Q_CAP(CHIPS)':
 'A': CDS_PINID='A';
NODE_NAME     C174 1
 '@T6G_MB_LIB.T6G(SCH_1):PAGE97_I241@PURE_QUANTA.Q_CAP(CHIPS)':
 'A': CDS_PINID='A';
NODE_NAME     J26 1
 '@T6G_MB_LIB.T6G(SCH_1):PAGE98_I160@PURE_QUANTA.SCONN288_DDR506112002KQ(CHIPS)':
 'VIN_BULK0': CDS_PINID='VIN_BULK0';
NODE_NAME     J26 145
 '@T6G_MB_LIB.T6G(SCH_1):PAGE98_I160@PURE_QUANTA.SCONN288_DDR506112002KQ(CHIPS)':
 'VIN_BULK1': CDS_PINID='VIN_BULK1';
NODE_NAME     J26 146
 '@T6G_MB_LIB.T6G(SCH_1):PAGE98_I160@PURE_QUANTA.SCONN288_DDR506112002KQ(CHIPS)':
 'VIN_BULK2': CDS_PINID='VIN_BULK2';
NODE_NAME     C175 1
 '@T6G_MB_LIB.T6G(SCH_1):PAGE98_I238@PURE_QUANTA.Q_CAP(CHIPS)':
 'A': CDS_PINID='A';
NODE_NAME     C177 1
 '@T6G_MB_LIB.T6G(SCH_1):PAGE98_I239@PURE_QUANTA.Q_CAP(CHIPS)':
 'A': CDS_PINID='A';
NODE_NAME     J28 1
 '@T6G_MB_LIB.T6G(SCH_1):PAGE99_I155@PURE_QUANTA.SCONN288_DDR506112002KQ(CHIPS)':
 'VIN_BULK0': CDS_PINID='VIN_BULK0';
NODE_NAME     J28 145
 '@T6G_MB_LIB.T6G(SCH_1):PAGE99_I155@PURE_QUANTA.SCONN288_DDR506112002KQ(CHIPS)':
 'VIN_BULK1': CDS_PINID='VIN_BULK1';
NODE_NAME     J28 146
 '@T6G_MB_LIB.T6G(SCH_1):PAGE99_I155@PURE_QUANTA.SCONN288_DDR506112002KQ(CHIPS)':
 'VIN_BULK2': CDS_PINID='VIN_BULK2';
NODE_NAME     C178 1
 '@T6G_MB_LIB.T6G(SCH_1):PAGE99_I238@PURE_QUANTA.Q_CAP(CHIPS)':
 'A': CDS_PINID='A';
NODE_NAME     C179 1
 '@T6G_MB_LIB.T6G(SCH_1):PAGE99_I239@PURE_QUANTA.Q_CAP(CHIPS)':
 'A': CDS_PINID='A';
NODE_NAME     J30 1
 '@T6G_MB_LIB.T6G(SCH_1):PAGE100_I161@PURE_QUANTA.SCONN288_DDR506112002KQ(CHIPS)':
 'VIN_BULK0': CDS_PINID='VIN_BULK0';
NODE_NAME     J30 145
 '@T6G_MB_LIB.T6G(SCH_1):PAGE100_I161@PURE_QUANTA.SCONN288_DDR506112002KQ(CHIPS)':
 'VIN_BULK1': CDS_PINID='VIN_BULK1';
NODE_NAME     J30 146
 '@T6G_MB_LIB.T6G(SCH_1):PAGE100_I161@PURE_QUANTA.SCONN288_DDR506112002KQ(CHIPS)':
 'VIN_BULK2': CDS_PINID='VIN_BULK2';
NODE_NAME     C181 1
 '@T6G_MB_LIB.T6G(SCH_1):PAGE100_I238@PURE_QUANTA.Q_CAP(CHIPS)':
 'A': CDS_PINID='A';
NODE_NAME     C182 1
 '@T6G_MB_LIB.T6G(SCH_1):PAGE100_I239@PURE_QUANTA.Q_CAP(CHIPS)':
 'A': CDS_PINID='A';
NODE_NAME     J32 1
 '@T6G_MB_LIB.T6G(SCH_1):PAGE101_I175@PURE_QUANTA.SCONN288_DDR506112002KQ(CHIPS)':
 'VIN_BULK0': CDS_PINID='VIN_BULK0';
NODE_NAME     J32 145
 '@T6G_MB_LIB.T6G(SCH_1):PAGE101_I175@PURE_QUANTA.SCONN288_DDR506112002KQ(CHIPS)':
 'VIN_BULK1': CDS_PINID='VIN_BULK1';
NODE_NAME     J32 146
 '@T6G_MB_LIB.T6G(SCH_1):PAGE101_I175@PURE_QUANTA.SCONN288_DDR506112002KQ(CHIPS)':
 'VIN_BULK2': CDS_PINID='VIN_BULK2';
NODE_NAME     C183 1
 '@T6G_MB_LIB.T6G(SCH_1):PAGE101_I238@PURE_QUANTA.Q_CAP(CHIPS)':
 'A': CDS_PINID='A';
NODE_NAME     C509 1
 '@T6G_MB_LIB.T6G(SCH_1):PAGE101_I239@PURE_QUANTA.Q_CAP(CHIPS)':
 'A': CDS_PINID='A';
NODE_NAME     J33 1
 '@T6G_MB_LIB.T6G(SCH_1):PAGE102_I142@PURE_QUANTA.SCONN288_DDR506112002KQ(CHIPS)':
 'VIN_BULK0': CDS_PINID='VIN_BULK0';
NODE_NAME     J33 145
 '@T6G_MB_LIB.T6G(SCH_1):PAGE102_I142@PURE_QUANTA.SCONN288_DDR506112002KQ(CHIPS)':
 'VIN_BULK1': CDS_PINID='VIN_BULK1';
NODE_NAME     J33 146
 '@T6G_MB_LIB.T6G(SCH_1):PAGE102_I142@PURE_QUANTA.SCONN288_DDR506112002KQ(CHIPS)':
 'VIN_BULK2': CDS_PINID='VIN_BULK2';
NODE_NAME     C518 1
 '@T6G_MB_LIB.T6G(SCH_1):PAGE102_I238@PURE_QUANTA.Q_CAP(CHIPS)':
 'A': CDS_PINID='A';
NODE_NAME     C527 1
 '@T6G_MB_LIB.T6G(SCH_1):PAGE102_I239@PURE_QUANTA.Q_CAP(CHIPS)':
 'A': CDS_PINID='A';
NODE_NAME     J102 1
 '@T6G_MB_LIB.T6G(SCH_1):PAGE103_I142@PURE_QUANTA.SCONN288_DDR506112002KQ(CHIPS)':
 'VIN_BULK0': CDS_PINID='VIN_BULK0';
NODE_NAME     J102 145
 '@T6G_MB_LIB.T6G(SCH_1):PAGE103_I142@PURE_QUANTA.SCONN288_DDR506112002KQ(CHIPS)':
 'VIN_BULK1': CDS_PINID='VIN_BULK1';
NODE_NAME     J102 146
 '@T6G_MB_LIB.T6G(SCH_1):PAGE103_I142@PURE_QUANTA.SCONN288_DDR506112002KQ(CHIPS)':
 'VIN_BULK2': CDS_PINID='VIN_BULK2';
NODE_NAME     C530 1
 '@T6G_MB_LIB.T6G(SCH_1):PAGE103_I240@PURE_QUANTA.Q_CAP(CHIPS)':
 'A': CDS_PINID='A';
NODE_NAME     C531 1
 '@T6G_MB_LIB.T6G(SCH_1):PAGE103_I241@PURE_QUANTA.Q_CAP(CHIPS)':
 'A': CDS_PINID='A';
NODE_NAME     J27 1
 '@T6G_MB_LIB.T6G(SCH_1):PAGE104_I174@PURE_QUANTA.SCONN288_DDR506112002KQ(CHIPS)':
 'VIN_BULK0': CDS_PINID='VIN_BULK0';
NODE_NAME     J27 145
 '@T6G_MB_LIB.T6G(SCH_1):PAGE104_I174@PURE_QUANTA.SCONN288_DDR506112002KQ(CHIPS)':
 'VIN_BULK1': CDS_PINID='VIN_BULK1';
NODE_NAME     J27 146
 '@T6G_MB_LIB.T6G(SCH_1):PAGE104_I174@PURE_QUANTA.SCONN288_DDR506112002KQ(CHIPS)':
 'VIN_BULK2': CDS_PINID='VIN_BULK2';
NODE_NAME     C532 1
 '@T6G_MB_LIB.T6G(SCH_1):PAGE104_I240@PURE_QUANTA.Q_CAP(CHIPS)':
 'A': CDS_PINID='A';
NODE_NAME     C533 1
 '@T6G_MB_LIB.T6G(SCH_1):PAGE104_I241@PURE_QUANTA.Q_CAP(CHIPS)':
 'A': CDS_PINID='A';
NODE_NAME     J100 1
 '@T6G_MB_LIB.T6G(SCH_1):PAGE105_I176@PURE_QUANTA.SCONN288_DDR506112002KQ(CHIPS)':
 'VIN_BULK0': CDS_PINID='VIN_BULK0';
NODE_NAME     J100 145
 '@T6G_MB_LIB.T6G(SCH_1):PAGE105_I176@PURE_QUANTA.SCONN288_DDR506112002KQ(CHIPS)':
 'VIN_BULK1': CDS_PINID='VIN_BULK1';
NODE_NAME     J100 146
 '@T6G_MB_LIB.T6G(SCH_1):PAGE105_I176@PURE_QUANTA.SCONN288_DDR506112002KQ(CHIPS)':
 'VIN_BULK2': CDS_PINID='VIN_BULK2';
NODE_NAME     C534 1
 '@T6G_MB_LIB.T6G(SCH_1):PAGE105_I238@PURE_QUANTA.Q_CAP(CHIPS)':
 'A': CDS_PINID='A';
NODE_NAME     C535 1
 '@T6G_MB_LIB.T6G(SCH_1):PAGE105_I239@PURE_QUANTA.Q_CAP(CHIPS)':
 'A': CDS_PINID='A';
NODE_NAME     J29 1
 '@T6G_MB_LIB.T6G(SCH_1):PAGE106_I143@PURE_QUANTA.SCONN288_DDR506112002KQ(CHIPS)':
 'VIN_BULK0': CDS_PINID='VIN_BULK0';
NODE_NAME     J29 145
 '@T6G_MB_LIB.T6G(SCH_1):PAGE106_I143@PURE_QUANTA.SCONN288_DDR506112002KQ(CHIPS)':
 'VIN_BULK1': CDS_PINID='VIN_BULK1';
NODE_NAME     J29 146
 '@T6G_MB_LIB.T6G(SCH_1):PAGE106_I143@PURE_QUANTA.SCONN288_DDR506112002KQ(CHIPS)':
 'VIN_BULK2': CDS_PINID='VIN_BULK2';
NODE_NAME     C536 1
 '@T6G_MB_LIB.T6G(SCH_1):PAGE106_I238@PURE_QUANTA.Q_CAP(CHIPS)':
 'A': CDS_PINID='A';
NODE_NAME     C537 1
 '@T6G_MB_LIB.T6G(SCH_1):PAGE106_I239@PURE_QUANTA.Q_CAP(CHIPS)':
 'A': CDS_PINID='A';
NODE_NAME     J99 1
 '@T6G_MB_LIB.T6G(SCH_1):PAGE107_I139@PURE_QUANTA.SCONN288_DDR506112002KQ(CHIPS)':
 'VIN_BULK0': CDS_PINID='VIN_BULK0';
NODE_NAME     J99 145
 '@T6G_MB_LIB.T6G(SCH_1):PAGE107_I139@PURE_QUANTA.SCONN288_DDR506112002KQ(CHIPS)':
 'VIN_BULK1': CDS_PINID='VIN_BULK1';
NODE_NAME     J99 146
 '@T6G_MB_LIB.T6G(SCH_1):PAGE107_I139@PURE_QUANTA.SCONN288_DDR506112002KQ(CHIPS)':
 'VIN_BULK2': CDS_PINID='VIN_BULK2';
NODE_NAME     C546 1
 '@T6G_MB_LIB.T6G(SCH_1):PAGE107_I237@PURE_QUANTA.Q_CAP(CHIPS)':
 'A': CDS_PINID='A';
NODE_NAME     C547 1
 '@T6G_MB_LIB.T6G(SCH_1):PAGE107_I238@PURE_QUANTA.Q_CAP(CHIPS)':
 'A': CDS_PINID='A';
NODE_NAME     J37 1
 '@T6G_MB_LIB.T6G(SCH_1):PAGE108_I138@PURE_QUANTA.SCONN288_DDR506112002KQ(CHIPS)':
 'VIN_BULK0': CDS_PINID='VIN_BULK0';
NODE_NAME     J37 145
 '@T6G_MB_LIB.T6G(SCH_1):PAGE108_I138@PURE_QUANTA.SCONN288_DDR506112002KQ(CHIPS)':
 'VIN_BULK1': CDS_PINID='VIN_BULK1';
NODE_NAME     J37 146
 '@T6G_MB_LIB.T6G(SCH_1):PAGE108_I138@PURE_QUANTA.SCONN288_DDR506112002KQ(CHIPS)':
 'VIN_BULK2': CDS_PINID='VIN_BULK2';
NODE_NAME     C548 1
 '@T6G_MB_LIB.T6G(SCH_1):PAGE108_I237@PURE_QUANTA.Q_CAP(CHIPS)':
 'A': CDS_PINID='A';
NODE_NAME     C549 1
 '@T6G_MB_LIB.T6G(SCH_1):PAGE108_I238@PURE_QUANTA.Q_CAP(CHIPS)':
 'A': CDS_PINID='A';
NODE_NAME     R1440 1
 '@T6G_MB_LIB.T6G(SCH_1):PAGE264_I25@PURE_QUANTA.Q_RES(CHIPS)':
 'A': CDS_PINID='A';
NODE_NAME     R1837 2
 '@T6G_MB_LIB.T6G(SCH_1):PAGE264_I54@PURE_QUANTA.Q_RES_4P_12(CHIPS)':
 '2': CDS_PINID='\2\';
NET_NAME
'P12V_OCP_1_EN_G'
 '@T6G_MB_LIB.T6G(SCH_1):P12V_OCP_1_EN_G':
 C_SIGNAL='@t6g_mb_lib.t6g(sch_1):p12v_ocp_1_en_g';
NODE_NAME     Q123 6
 '@T6G_MB_LIB.T6G(SCH_1):PAGE338_I11@PURE_QUANTA.MOSFET_NCH_DUAL(CHIPS)':
 'D1': CDS_PINID='D1';
NODE_NAME     R4068 2
 '@T6G_MB_LIB.T6G(SCH_1):PAGE338_I17@PURE_QUANTA.Q_RES(CHIPS)':
 'B': CDS_PINID='B';
NODE_NAME     Q123 5
 '@T6G_MB_LIB.T6G(SCH_1):PAGE338_I19@PURE_QUANTA.MOSFET_NCH_DUAL(CHIPS)':
 'G2': CDS_PINID='G2';
NET_NAME
'P12V_OCP_2_EN_G'
 '@T6G_MB_LIB.T6G(SCH_1):P12V_OCP_2_EN_G':
 C_SIGNAL='@t6g_mb_lib.t6g(sch_1):p12v_ocp_2_en_g';
NODE_NAME     Q118 6
 '@T6G_MB_LIB.T6G(SCH_1):PAGE343_I10@PURE_QUANTA.MOSFET_NCH_DUAL(CHIPS)':
 'D1': CDS_PINID='D1';
NODE_NAME     Q118 5
 '@T6G_MB_LIB.T6G(SCH_1):PAGE343_I19@PURE_QUANTA.MOSFET_NCH_DUAL(CHIPS)':
 'G2': CDS_PINID='G2';
NODE_NAME     R4065 2
 '@T6G_MB_LIB.T6G(SCH_1):PAGE343_I17@PURE_QUANTA.Q_RES(CHIPS)':
 'B': CDS_PINID='B';
NET_NAME
'P12V_OCP_AVIN_PD_1'
 '@T6G_MB_LIB.T6G(SCH_1):P12V_OCP_AVIN_PD_1':
 C_SIGNAL='@t6g_mb_lib.t6g(sch_1):p12v_ocp_avin_pd_1';
NODE_NAME     PR3838 2
 '@T6G_MB_LIB.T6G(SCH_1):PAGE339_I76@PURE_QUANTA.Q_RES(CHIPS)':
 'B': CDS_PINID='B';
NODE_NAME     PC2158 1
 '@T6G_MB_LIB.T6G(SCH_1):PAGE339_I86@PURE_QUANTA.Q_CAP(CHIPS)':
 'A': CDS_PINID='A';
NODE_NAME     PR3843 2
 '@T6G_MB_LIB.T6G(SCH_1):PAGE339_I88@PURE_QUANTA.Q_RES(CHIPS)':
 'B': CDS_PINID='B';
NODE_NAME     PU204 12
 '@T6G_MB_LIB.T6G(SCH_1):PAGE339_I137@PURE_QUANTA.RS31312R(CHIPS)':
 'AVIN': CDS_PINID='AVIN';
NET_NAME
'P12V_OCP_AVIN_PD_2'
 '@T6G_MB_LIB.T6G(SCH_1):P12V_OCP_AVIN_PD_2':
 C_SIGNAL='@t6g_mb_lib.t6g(sch_1):p12v_ocp_avin_pd_2';
NODE_NAME     PC1320 1
 '@T6G_MB_LIB.T6G(SCH_1):PAGE344_I24@PURE_QUANTA.Q_CAP(CHIPS)':
 'A': CDS_PINID='A';
NODE_NAME     PR3850 2
 '@T6G_MB_LIB.T6G(SCH_1):PAGE344_I30@PURE_QUANTA.Q_RES(CHIPS)':
 'B': CDS_PINID='B';
NODE_NAME     PR3857 2
 '@T6G_MB_LIB.T6G(SCH_1):PAGE344_I37@PURE_QUANTA.Q_RES(CHIPS)':
 'B': CDS_PINID='B';
NODE_NAME     PU206 12
 '@T6G_MB_LIB.T6G(SCH_1):PAGE344_I82@PURE_QUANTA.RS31312R(CHIPS)':
 'AVIN': CDS_PINID='AVIN';
NET_NAME
'P12V_OCP_CB_1'
 '@T6G_MB_LIB.T6G(SCH_1):P12V_OCP_CB_1':
 C_SIGNAL='@t6g_mb_lib.t6g(sch_1):p12v_ocp_cb_1';
NODE_NAME     PR5484 1
 '@T6G_MB_LIB.T6G(SCH_1):PAGE338_I48@PURE_QUANTA.Q_RES(CHIPS)':
 'A': CDS_PINID='A';
NODE_NAME     PU203 B1
 '@T6G_MB_LIB.T6G(SCH_1):PAGE338_I50@PURE_QUANTA.MAX15090BEWIT(CHIPS)':
 'CB': CDS_PINID='CB';
NET_NAME
'P12V_OCP_CB_2'
 '@T6G_MB_LIB.T6G(SCH_1):P12V_OCP_CB_2':
 C_SIGNAL='@t6g_mb_lib.t6g(sch_1):p12v_ocp_cb_2';
NODE_NAME     PR3821 1
 '@T6G_MB_LIB.T6G(SCH_1):PAGE343_I63@PURE_QUANTA.Q_RES(CHIPS)':
 'A': CDS_PINID='A';
NODE_NAME     PU201 B1
 '@T6G_MB_LIB.T6G(SCH_1):PAGE343_I67@PURE_QUANTA.MAX15090BEWIT(CHIPS)':
 'CB': CDS_PINID='CB';
NET_NAME
'P12V_OCP_EN_1_R'
 '@T6G_MB_LIB.T6G(SCH_1):P12V_OCP_EN_1_R':
 C_SIGNAL='@t6g_mb_lib.t6g(sch_1):p12v_ocp_en_1_r';
NODE_NAME     Q123 2
 '@T6G_MB_LIB.T6G(SCH_1):PAGE338_I11@PURE_QUANTA.MOSFET_NCH_DUAL(CHIPS)':
 'G1': CDS_PINID='G1';
NODE_NAME     R4061 2
 '@T6G_MB_LIB.T6G(SCH_1):PAGE338_I123@PURE_QUANTA.Q_RES(CHIPS)':
 'B': CDS_PINID='B';
NODE_NAME     R561 2
 '@T6G_MB_LIB.T6G(SCH_1):PAGE338_I125@PURE_QUANTA.Q_RES(CHIPS)':
 'B': CDS_PINID='B';
NODE_NAME     R6045 1
 '@T6G_MB_LIB.T6G(SCH_1):PAGE338_I130@PURE_QUANTA.Q_RES(CHIPS)':
 'A': CDS_PINID='A';
NET_NAME
'P12V_OCP_EN_1_R2'
 '@T6G_MB_LIB.T6G(SCH_1):P12V_OCP_EN_1_R2':
 C_SIGNAL='@t6g_mb_lib.t6g(sch_1):p12v_ocp_en_1_r2';
NODE_NAME     R3834 2
 '@T6G_MB_LIB.T6G(SCH_1):PAGE339_I128@PURE_QUANTA.Q_RES(CHIPS)':
 'B': CDS_PINID='B';
NODE_NAME     R591 2
 '@T6G_MB_LIB.T6G(SCH_1):PAGE339_I130@PURE_QUANTA.Q_RES(CHIPS)':
 'B': CDS_PINID='B';
NODE_NAME     PU204 1
 '@T6G_MB_LIB.T6G(SCH_1):PAGE339_I137@PURE_QUANTA.RS31312R(CHIPS)':
 'EN': CDS_PINID='EN';
NET_NAME
'P12V_OCP_EN_2_R'
 '@T6G_MB_LIB.T6G(SCH_1):P12V_OCP_EN_2_R':
 C_SIGNAL='@t6g_mb_lib.t6g(sch_1):p12v_ocp_en_2_r';
NODE_NAME     Q118 2
 '@T6G_MB_LIB.T6G(SCH_1):PAGE343_I10@PURE_QUANTA.MOSFET_NCH_DUAL(CHIPS)':
 'G1': CDS_PINID='G1';
NODE_NAME     R4059 2
 '@T6G_MB_LIB.T6G(SCH_1):PAGE343_I119@PURE_QUANTA.Q_RES(CHIPS)':
 'B': CDS_PINID='B';
NODE_NAME     R6060 1
 '@T6G_MB_LIB.T6G(SCH_1):PAGE343_I120@PURE_QUANTA.Q_RES(CHIPS)':
 'A': CDS_PINID='A';
NODE_NAME     R1181 2
 '@T6G_MB_LIB.T6G(SCH_1):PAGE343_I123@PURE_QUANTA.Q_RES(CHIPS)':
 'B': CDS_PINID='B';
NET_NAME
'P12V_OCP_FAULT_1'
 '@T6G_MB_LIB.T6G(SCH_1):P12V_OCP_FAULT_1':
 C_SIGNAL='@t6g_mb_lib.t6g(sch_1):p12v_ocp_fault_1';
NODE_NAME     PU203 C7
 '@T6G_MB_LIB.T6G(SCH_1):PAGE338_I50@PURE_QUANTA.MAX15090BEWIT(CHIPS)':
 'FAULT#': CDS_PINID='\fault#\';
NODE_NAME     R3799 2
 '@T6G_MB_LIB.T6G(SCH_1):PAGE338_I83@PURE_QUANTA.Q_RES(CHIPS)':
 'B': CDS_PINID='B';
NET_NAME
'P12V_OCP_FAULT_2'
 '@T6G_MB_LIB.T6G(SCH_1):P12V_OCP_FAULT_2':
 C_SIGNAL='@t6g_mb_lib.t6g(sch_1):p12v_ocp_fault_2';
NODE_NAME     PU201 C7
 '@T6G_MB_LIB.T6G(SCH_1):PAGE343_I67@PURE_QUANTA.MAX15090BEWIT(CHIPS)':
 'FAULT#': CDS_PINID='\fault#\';
NODE_NAME     R3816 2
 '@T6G_MB_LIB.T6G(SCH_1):PAGE343_I79@PURE_QUANTA.Q_RES(CHIPS)':
 'B': CDS_PINID='B';
NET_NAME
'P12V_OCP_FLTB_1'
 '@T6G_MB_LIB.T6G(SCH_1):P12V_OCP_FLTB_1':
 C_SIGNAL='@t6g_mb_lib.t6g(sch_1):p12v_ocp_fltb_1';
NODE_NAME     PR3839 1
 '@T6G_MB_LIB.T6G(SCH_1):PAGE339_I74@PURE_QUANTA.Q_RES(CHIPS)':
 'A': CDS_PINID='A';
NODE_NAME     PU204 9
 '@T6G_MB_LIB.T6G(SCH_1):PAGE339_I137@PURE_QUANTA.RS31312R(CHIPS)':
 'FLTB': CDS_PINID='FLTB';
NET_NAME
'P12V_OCP_FLTB_2'
 '@T6G_MB_LIB.T6G(SCH_1):P12V_OCP_FLTB_2':
 C_SIGNAL='@t6g_mb_lib.t6g(sch_1):p12v_ocp_fltb_2';
NODE_NAME     PR3851 1
 '@T6G_MB_LIB.T6G(SCH_1):PAGE344_I18@PURE_QUANTA.Q_RES(CHIPS)':
 'A': CDS_PINID='A';
NODE_NAME     PU206 9
 '@T6G_MB_LIB.T6G(SCH_1):PAGE344_I82@PURE_QUANTA.RS31312R(CHIPS)':
 'FLTB': CDS_PINID='FLTB';
NET_NAME
'P12V_OCP_GATE_1'
 '@T6G_MB_LIB.T6G(SCH_1):P12V_OCP_GATE_1':
 C_SIGNAL='@t6g_mb_lib.t6g(sch_1):p12v_ocp_gate_1';
NODE_NAME     PU203 A6
 '@T6G_MB_LIB.T6G(SCH_1):PAGE338_I50@PURE_QUANTA.MAX15090BEWIT(CHIPS)':
 'GATE': CDS_PINID='GATE';
NODE_NAME     PC2088 2
 '@T6G_MB_LIB.T6G(SCH_1):PAGE338_I74@PURE_QUANTA.Q_CAP(CHIPS)':
 'B': CDS_PINID='B';
NODE_NAME     PR4524 2
 '@T6G_MB_LIB.T6G(SCH_1):PAGE338_I76@PURE_QUANTA.Q_RES(CHIPS)':
 'B': CDS_PINID='B';
NODE_NAME     PC4056 1
 '@T6G_MB_LIB.T6G(SCH_1):PAGE338_I77@PURE_QUANTA.Q_CAP(CHIPS)':
 'A': CDS_PINID='A';
NET_NAME
'P12V_OCP_GATE_2'
 '@T6G_MB_LIB.T6G(SCH_1):P12V_OCP_GATE_2':
 C_SIGNAL='@t6g_mb_lib.t6g(sch_1):p12v_ocp_gate_2';
NODE_NAME     PU201 A6
 '@T6G_MB_LIB.T6G(SCH_1):PAGE343_I67@PURE_QUANTA.MAX15090BEWIT(CHIPS)':
 'GATE': CDS_PINID='GATE';
NODE_NAME     C40 2
 '@T6G_MB_LIB.T6G(SCH_1):PAGE343_I72@PURE_QUANTA.Q_CAP(CHIPS)':
 'B': CDS_PINID='B';
NODE_NAME     PC2150 1
 '@T6G_MB_LIB.T6G(SCH_1):PAGE343_I75@PURE_QUANTA.Q_CAP(CHIPS)':
 'A': CDS_PINID='A';
NODE_NAME     PR4522 2
 '@T6G_MB_LIB.T6G(SCH_1):PAGE343_I76@PURE_QUANTA.Q_RES(CHIPS)':
 'B': CDS_PINID='B';
NET_NAME
'P12V_OCP_IMON_1'
 '@T6G_MB_LIB.T6G(SCH_1):P12V_OCP_IMON_1':
 C_SIGNAL='@t6g_mb_lib.t6g(sch_1):p12v_ocp_imon_1';
NODE_NAME     PR3837 1
 '@T6G_MB_LIB.T6G(SCH_1):PAGE339_I71@PURE_QUANTA.Q_RES(CHIPS)':
 'A': CDS_PINID='A';
NODE_NAME     PC2156 1
 '@T6G_MB_LIB.T6G(SCH_1):PAGE339_I73@PURE_QUANTA.Q_CAP(CHIPS)':
 'A': CDS_PINID='A';
NODE_NAME     R3872 1
 '@T6G_MB_LIB.T6G(SCH_1):PAGE339_I84@PURE_QUANTA.Q_RES(CHIPS)':
 'A': CDS_PINID='A';
NODE_NAME     R3871 1
 '@T6G_MB_LIB.T6G(SCH_1):PAGE339_I85@PURE_QUANTA.Q_RES(CHIPS)':
 'A': CDS_PINID='A';
NODE_NAME     PU204 8
 '@T6G_MB_LIB.T6G(SCH_1):PAGE339_I137@PURE_QUANTA.RS31312R(CHIPS)':
 'IMON': CDS_PINID='IMON';
NET_NAME
'P12V_OCP_IMON_2'
 '@T6G_MB_LIB.T6G(SCH_1):P12V_OCP_IMON_2':
 C_SIGNAL='@t6g_mb_lib.t6g(sch_1):p12v_ocp_imon_2';
NODE_NAME     PR3849 1
 '@T6G_MB_LIB.T6G(SCH_1):PAGE344_I15@PURE_QUANTA.Q_RES(CHIPS)':
 'A': CDS_PINID='A';
NODE_NAME     R3874 1
 '@T6G_MB_LIB.T6G(SCH_1):PAGE344_I22@PURE_QUANTA.Q_RES(CHIPS)':
 'A': CDS_PINID='A';
NODE_NAME     R3873 1
 '@T6G_MB_LIB.T6G(SCH_1):PAGE344_I23@PURE_QUANTA.Q_RES(CHIPS)':
 'A': CDS_PINID='A';
NODE_NAME     PC2167 1
 '@T6G_MB_LIB.T6G(SCH_1):PAGE344_I58@PURE_QUANTA.Q_CAP(CHIPS)':
 'A': CDS_PINID='A';
NODE_NAME     PU206 8
 '@T6G_MB_LIB.T6G(SCH_1):PAGE344_I82@PURE_QUANTA.RS31312R(CHIPS)':
 'IMON': CDS_PINID='IMON';
NET_NAME
'P12V_OCP_ISET_1'
 '@T6G_MB_LIB.T6G(SCH_1):P12V_OCP_ISET_1':
 C_SIGNAL='@t6g_mb_lib.t6g(sch_1):p12v_ocp_iset_1';
NODE_NAME     PR3835 1
 '@T6G_MB_LIB.T6G(SCH_1):PAGE339_I63@PURE_QUANTA.Q_RES(CHIPS)':
 'A': CDS_PINID='A';
NODE_NAME     PU204 5
 '@T6G_MB_LIB.T6G(SCH_1):PAGE339_I137@PURE_QUANTA.RS31312R(CHIPS)':
 'ISET': CDS_PINID='ISET';
NET_NAME
'P12V_OCP_ISET_2'
 '@T6G_MB_LIB.T6G(SCH_1):P12V_OCP_ISET_2':
 C_SIGNAL='@t6g_mb_lib.t6g(sch_1):p12v_ocp_iset_2';
NODE_NAME     PR3847 1
 '@T6G_MB_LIB.T6G(SCH_1):PAGE344_I4@PURE_QUANTA.Q_RES(CHIPS)':
 'A': CDS_PINID='A';
NODE_NAME     PU206 5
 '@T6G_MB_LIB.T6G(SCH_1):PAGE344_I82@PURE_QUANTA.RS31312R(CHIPS)':
 'ISET': CDS_PINID='ISET';
NET_NAME
'P12V_OCP_OV_1'
 '@T6G_MB_LIB.T6G(SCH_1):P12V_OCP_OV_1':
 C_SIGNAL='@t6g_mb_lib.t6g(sch_1):p12v_ocp_ov_1';
NODE_NAME     PR3788 1
 '@T6G_MB_LIB.T6G(SCH_1):PAGE338_I36@PURE_QUANTA.Q_RES(CHIPS)':
 'A': CDS_PINID='A';
NODE_NAME     PR3787 2
 '@T6G_MB_LIB.T6G(SCH_1):PAGE338_I42@PURE_QUANTA.Q_RES(CHIPS)':
 'B': CDS_PINID='B';
NODE_NAME     PU203 D3
 '@T6G_MB_LIB.T6G(SCH_1):PAGE338_I50@PURE_QUANTA.MAX15090BEWIT(CHIPS)':
 'OV': CDS_PINID='OV';
NET_NAME
'P12V_OCP_OV_2'
 '@T6G_MB_LIB.T6G(SCH_1):P12V_OCP_OV_2':
 C_SIGNAL='@t6g_mb_lib.t6g(sch_1):p12v_ocp_ov_2';
NODE_NAME     PR3806 2
 '@T6G_MB_LIB.T6G(SCH_1):PAGE343_I35@PURE_QUANTA.Q_RES(CHIPS)':
 'B': CDS_PINID='B';
NODE_NAME     PU201 D3
 '@T6G_MB_LIB.T6G(SCH_1):PAGE343_I67@PURE_QUANTA.MAX15090BEWIT(CHIPS)':
 'OV': CDS_PINID='OV';
NODE_NAME     PR3828 1
 '@T6G_MB_LIB.T6G(SCH_1):PAGE343_I31@PURE_QUANTA.Q_RES(CHIPS)':
 'A': CDS_PINID='A';
NET_NAME
'P12V_OCP_OV_FB_1'
 '@T6G_MB_LIB.T6G(SCH_1):P12V_OCP_OV_FB_1':
 C_SIGNAL='@t6g_mb_lib.t6g(sch_1):p12v_ocp_ov_fb_1';
NODE_NAME     PR3842 1
 '@T6G_MB_LIB.T6G(SCH_1):PAGE339_I80@PURE_QUANTA.Q_RES(CHIPS)':
 'A': CDS_PINID='A';
NODE_NAME     PR3840 2
 '@T6G_MB_LIB.T6G(SCH_1):PAGE339_I81@PURE_QUANTA.Q_RES(CHIPS)':
 'B': CDS_PINID='B';
NODE_NAME     PR3841 2
 '@T6G_MB_LIB.T6G(SCH_1):PAGE339_I82@PURE_QUANTA.Q_RES(CHIPS)':
 'B': CDS_PINID='B';
NODE_NAME     PU204 11
 '@T6G_MB_LIB.T6G(SCH_1):PAGE339_I137@PURE_QUANTA.RS31312R(CHIPS)':
 'OV': CDS_PINID='OV';
NET_NAME
'P12V_OCP_OV_FB_2'
 '@T6G_MB_LIB.T6G(SCH_1):P12V_OCP_OV_FB_2':
 C_SIGNAL='@t6g_mb_lib.t6g(sch_1):p12v_ocp_ov_fb_2';
NODE_NAME     PR3854 1
 '@T6G_MB_LIB.T6G(SCH_1):PAGE344_I20@PURE_QUANTA.Q_RES(CHIPS)':
 'A': CDS_PINID='A';
NODE_NAME     PR3852 2
 '@T6G_MB_LIB.T6G(SCH_1):PAGE344_I31@PURE_QUANTA.Q_RES(CHIPS)':
 'B': CDS_PINID='B';
NODE_NAME     PR3853 2
 '@T6G_MB_LIB.T6G(SCH_1):PAGE344_I36@PURE_QUANTA.Q_RES(CHIPS)':
 'B': CDS_PINID='B';
NODE_NAME     PU206 11
 '@T6G_MB_LIB.T6G(SCH_1):PAGE344_I82@PURE_QUANTA.RS31312R(CHIPS)':
 'OV': CDS_PINID='OV';
NET_NAME
'P12V_OCP_PWRGD_1'
 '@T6G_MB_LIB.T6G(SCH_1):P12V_OCP_PWRGD_1':
 C_SIGNAL='@t6g_mb_lib.t6g(sch_1):p12v_ocp_pwrgd_1';
NODE_NAME     PU203 D7
 '@T6G_MB_LIB.T6G(SCH_1):PAGE338_I50@PURE_QUANTA.MAX15090BEWIT(CHIPS)':
 'PG': CDS_PINID='PG';
NODE_NAME     R3144 1
 '@T6G_MB_LIB.T6G(SCH_1):PAGE338_I75@PURE_QUANTA.Q_RES(CHIPS)':
 'A': CDS_PINID='A';
NET_NAME
'P12V_OCP_PWRGD_2'
 '@T6G_MB_LIB.T6G(SCH_1):P12V_OCP_PWRGD_2':
 C_SIGNAL='@t6g_mb_lib.t6g(sch_1):p12v_ocp_pwrgd_2';
NODE_NAME     PU201 D7
 '@T6G_MB_LIB.T6G(SCH_1):PAGE343_I67@PURE_QUANTA.MAX15090BEWIT(CHIPS)':
 'PG': CDS_PINID='PG';
NODE_NAME     R3831 1
 '@T6G_MB_LIB.T6G(SCH_1):PAGE343_I77@PURE_QUANTA.Q_RES(CHIPS)':
 'A': CDS_PINID='A';
NET_NAME
'P12V_OCP_REG_1'
 '@T6G_MB_LIB.T6G(SCH_1):P12V_OCP_REG_1':
 C_SIGNAL='@t6g_mb_lib.t6g(sch_1):p12v_ocp_reg_1';
NODE_NAME     PU203 D1
 '@T6G_MB_LIB.T6G(SCH_1):PAGE338_I50@PURE_QUANTA.MAX15090BEWIT(CHIPS)':
 'REG': CDS_PINID='REG';
NODE_NAME     PC2087 2
 '@T6G_MB_LIB.T6G(SCH_1):PAGE338_I54@PURE_QUANTA.Q_CAP(CHIPS)':
 'B': CDS_PINID='B';
NET_NAME
'P12V_OCP_REG_2'
 '@T6G_MB_LIB.T6G(SCH_1):P12V_OCP_REG_2':
 C_SIGNAL='@t6g_mb_lib.t6g(sch_1):p12v_ocp_reg_2';
NODE_NAME     PC2146 2
 '@T6G_MB_LIB.T6G(SCH_1):PAGE343_I66@PURE_QUANTA.Q_CAP(CHIPS)':
 'B': CDS_PINID='B';
NODE_NAME     PU201 D1
 '@T6G_MB_LIB.T6G(SCH_1):PAGE343_I67@PURE_QUANTA.MAX15090BEWIT(CHIPS)':
 'REG': CDS_PINID='REG';
NET_NAME
'P12V_OCP_SENSE_1'
 '@T6G_MB_LIB.T6G(SCH_1):P12V_OCP_SENSE_1':
 C_SIGNAL='@t6g_mb_lib.t6g(sch_1):p12v_ocp_sense_1';
NODE_NAME     PU203 A1
 '@T6G_MB_LIB.T6G(SCH_1):PAGE338_I50@PURE_QUANTA.MAX15090BEWIT(CHIPS)':
 'ISENSE': CDS_PINID='ISENSE';
NODE_NAME     PR3781 1
 '@T6G_MB_LIB.T6G(SCH_1):PAGE338_I73@PURE_QUANTA.Q_RES(CHIPS)':
 'A': CDS_PINID='A';
NODE_NAME     R3870 1
 '@T6G_MB_LIB.T6G(SCH_1):PAGE338_I80@PURE_QUANTA.Q_RES(CHIPS)':
 'A': CDS_PINID='A';
NODE_NAME     R3869 1
 '@T6G_MB_LIB.T6G(SCH_1):PAGE338_I82@PURE_QUANTA.Q_RES(CHIPS)':
 'A': CDS_PINID='A';
NET_NAME
'P12V_OCP_SENSE_2'
 '@T6G_MB_LIB.T6G(SCH_1):P12V_OCP_SENSE_2':
 C_SIGNAL='@t6g_mb_lib.t6g(sch_1):p12v_ocp_sense_2';
NODE_NAME     PU201 A1
 '@T6G_MB_LIB.T6G(SCH_1):PAGE343_I67@PURE_QUANTA.MAX15090BEWIT(CHIPS)':
 'ISENSE': CDS_PINID='ISENSE';
NODE_NAME     PR3823 1
 '@T6G_MB_LIB.T6G(SCH_1):PAGE343_I71@PURE_QUANTA.Q_RES(CHIPS)':
 'A': CDS_PINID='A';
NODE_NAME     R3868 1
 '@T6G_MB_LIB.T6G(SCH_1):PAGE343_I73@PURE_QUANTA.Q_RES(CHIPS)':
 'A': CDS_PINID='A';
NODE_NAME     R3867 1
 '@T6G_MB_LIB.T6G(SCH_1):PAGE343_I74@PURE_QUANTA.Q_RES(CHIPS)':
 'A': CDS_PINID='A';
NET_NAME
'P12V_OCP_SFF'
 '@T6G_MB_LIB.T6G(SCH_1):P12V_OCP_SFF':
 C_SIGNAL='@t6g_mb_lib.t6g(sch_1):p12v_ocp_sff',
 CDS_GLOBAL_NET='TRUE';
NODE_NAME     PU203 A4
 '@T6G_MB_LIB.T6G(SCH_1):PAGE338_I50@PURE_QUANTA.MAX15090BEWIT(CHIPS)':
 'OUT_A4': CDS_PINID='OUT_A4';
NODE_NAME     PU203 B4
 '@T6G_MB_LIB.T6G(SCH_1):PAGE338_I50@PURE_QUANTA.MAX15090BEWIT(CHIPS)':
 'OUT_B4': CDS_PINID='OUT_B4';
NODE_NAME     PU203 B6
 '@T6G_MB_LIB.T6G(SCH_1):PAGE338_I50@PURE_QUANTA.MAX15090BEWIT(CHIPS)':
 'OUT_B6': CDS_PINID='OUT_B6';
NODE_NAME     PU203 C4
 '@T6G_MB_LIB.T6G(SCH_1):PAGE338_I50@PURE_QUANTA.MAX15090BEWIT(CHIPS)':
 'OUT_C4': CDS_PINID='OUT_C4';
NODE_NAME     PU203 C6
 '@T6G_MB_LIB.T6G(SCH_1):PAGE338_I50@PURE_QUANTA.MAX15090BEWIT(CHIPS)':
 'OUT_C6': CDS_PINID='OUT_C6';
NODE_NAME     PU203 D4
 '@T6G_MB_LIB.T6G(SCH_1):PAGE338_I50@PURE_QUANTA.MAX15090BEWIT(CHIPS)':
 'OUT_D4': CDS_PINID='OUT_D4';
NODE_NAME     PU203 D6
 '@T6G_MB_LIB.T6G(SCH_1):PAGE338_I50@PURE_QUANTA.MAX15090BEWIT(CHIPS)':
 'OUT_D6': CDS_PINID='OUT_D6';
NODE_NAME     PC2088 1
 '@T6G_MB_LIB.T6G(SCH_1):PAGE338_I74@PURE_QUANTA.Q_CAP(CHIPS)':
 'A': CDS_PINID='A';
NODE_NAME     PR4524 1
 '@T6G_MB_LIB.T6G(SCH_1):PAGE338_I76@PURE_QUANTA.Q_RES(CHIPS)':
 'A': CDS_PINID='A';
NODE_NAME     PD102 C
 '@T6G_MB_LIB.T6G(SCH_1):PAGE338_I79@PURE_QUANTA.SCHOTTKY_AC(CHIPS)':
 'C': CDS_PINID='C';
NODE_NAME     PC2092 1
 '@T6G_MB_LIB.T6G(SCH_1):PAGE338_I86@PURE_QUANTA.Q_CAP(CHIPS)':
 'A': CDS_PINID='A';
NODE_NAME     PC2080 1
 '@T6G_MB_LIB.T6G(SCH_1):PAGE338_I87@PURE_QUANTA.Q_CAP(CHIPS)':
 'A': CDS_PINID='A';
NODE_NAME     PC2082 1
 '@T6G_MB_LIB.T6G(SCH_1):PAGE338_I89@PURE_QUANTA.Q_CAP(CHIPS)':
 'A': CDS_PINID='A';
NODE_NAME     PR3838 1
 '@T6G_MB_LIB.T6G(SCH_1):PAGE339_I76@PURE_QUANTA.Q_RES(CHIPS)':
 'A': CDS_PINID='A';
NODE_NAME     PR3840 1
 '@T6G_MB_LIB.T6G(SCH_1):PAGE339_I81@PURE_QUANTA.Q_RES(CHIPS)':
 'A': CDS_PINID='A';
NODE_NAME     PC2160 1
 '@T6G_MB_LIB.T6G(SCH_1):PAGE339_I91@PURE_QUANTA.Q_CAP(CHIPS)':
 'A': CDS_PINID='A';
NODE_NAME     R1324 2
 '@T6G_MB_LIB.T6G(SCH_1):PAGE466_I2@PURE_QUANTA.Q_RES(CHIPS)':
 'B': CDS_PINID='B';
NODE_NAME     C1108 1
 '@T6G_MB_LIB.T6G(SCH_1):PAGE466_I5@PURE_QUANTA.Q_CAP(CHIPS)':
 'A': CDS_PINID='A';
NODE_NAME     R1284 1
 '@T6G_MB_LIB.T6G(SCH_1):PAGE466_I10@PURE_QUANTA.Q_RES(CHIPS)':
 'A': CDS_PINID='A';
NODE_NAME     U55 11
 '@T6G_MB_LIB.T6G(SCH_1):PAGE466_I28@PURE_QUANTA.ISL28022FRZT(CHIPS)':
 'VBUS': CDS_PINID='VBUS';
NODE_NAME     PU204 13
 '@T6G_MB_LIB.T6G(SCH_1):PAGE339_I137@PURE_QUANTA.RS31312R(CHIPS)':
 'VOUT_13': CDS_PINID='VOUT_13';
NODE_NAME     PU204 14
 '@T6G_MB_LIB.T6G(SCH_1):PAGE339_I137@PURE_QUANTA.RS31312R(CHIPS)':
 'VOUT_14': CDS_PINID='VOUT_14';
NODE_NAME     PU204 15
 '@T6G_MB_LIB.T6G(SCH_1):PAGE339_I137@PURE_QUANTA.RS31312R(CHIPS)':
 'VOUT_15': CDS_PINID='VOUT_15';
NODE_NAME     PU204 16
 '@T6G_MB_LIB.T6G(SCH_1):PAGE339_I137@PURE_QUANTA.RS31312R(CHIPS)':
 'VOUT_16': CDS_PINID='VOUT_16';
NODE_NAME     PU204 17
 '@T6G_MB_LIB.T6G(SCH_1):PAGE339_I137@PURE_QUANTA.RS31312R(CHIPS)':
 'VOUT_17': CDS_PINID='VOUT_17';
NODE_NAME     PU204 18
 '@T6G_MB_LIB.T6G(SCH_1):PAGE339_I137@PURE_QUANTA.RS31312R(CHIPS)':
 'VOUT_18': CDS_PINID='VOUT_18';
NODE_NAME     PU204 19
 '@T6G_MB_LIB.T6G(SCH_1):PAGE339_I137@PURE_QUANTA.RS31312R(CHIPS)':
 'VOUT_19': CDS_PINID='VOUT_19';
NODE_NAME     PU204 20
 '@T6G_MB_LIB.T6G(SCH_1):PAGE339_I137@PURE_QUANTA.RS31312R(CHIPS)':
 'VOUT_20': CDS_PINID='VOUT_20';
NET_NAME
'P12V_OCP_SFF_ADC_ALERT_R'
 '@T6G_MB_LIB.T6G(SCH_1):P12V_OCP_SFF_ADC_ALERT_R':
 C_SIGNAL='@t6g_mb_lib.t6g(sch_1):p12v_ocp_sff_adc_alert_r';
NODE_NAME     R1270 1
 '@T6G_MB_LIB.T6G(SCH_1):PAGE466_I23@PURE_QUANTA.Q_RES(CHIPS)':
 'A': CDS_PINID='A';
NODE_NAME     U55 3
 '@T6G_MB_LIB.T6G(SCH_1):PAGE466_I28@PURE_QUANTA.ISL28022FRZT(CHIPS)':
 'EXT_CLK||INT': CDS_PINID='\ext_clk||int\';
NET_NAME
'P12V_OCP_SFF_BUF_EN'
 '@T6G_MB_LIB.T6G(SCH_1):P12V_OCP_SFF_BUF_EN':
 C_SIGNAL='@t6g_mb_lib.t6g(sch_1):p12v_ocp_sff_buf_en';
NODE_NAME     U23 4
 '@T6G_MB_LIB.T6G(SCH_1):PAGE340_I36@PURE_QUANTA.74LVC1G08W57(CHIPS)':
 'Y': CDS_PINID='Y';
NODE_NAME     R1134 1
 '@T6G_MB_LIB.T6G(SCH_1):PAGE340_I47@PURE_QUANTA.Q_RES(CHIPS)':
 'A': CDS_PINID='A';
NET_NAME
'P12V_OCP_SFF_BUF_EN_R'
 '@T6G_MB_LIB.T6G(SCH_1):P12V_OCP_SFF_BUF_EN_R':
 C_SIGNAL='@t6g_mb_lib.t6g(sch_1):p12v_ocp_sff_buf_en_r';
NODE_NAME     R1134 2
 '@T6G_MB_LIB.T6G(SCH_1):PAGE340_I47@PURE_QUANTA.Q_RES(CHIPS)':
 'B': CDS_PINID='B';
NODE_NAME     R561 1
 '@T6G_MB_LIB.T6G(SCH_1):PAGE338_I125@PURE_QUANTA.Q_RES(CHIPS)':
 'A': CDS_PINID='A';
NODE_NAME     R591 1
 '@T6G_MB_LIB.T6G(SCH_1):PAGE339_I130@PURE_QUANTA.Q_RES(CHIPS)':
 'A': CDS_PINID='A';
NODE_NAME     R1500 2
 '@T6G_MB_LIB.T6G(SCH_1):PAGE248_I43@PURE_QUANTA.Q_RES(CHIPS)':
 'B': CDS_PINID='B';
NODE_NAME     R1486 1
 '@T6G_MB_LIB.T6G(SCH_1):PAGE338_I135@PURE_QUANTA.Q_RES(CHIPS)':
 'A': CDS_PINID='A';
NODE_NAME     R1487 1
 '@T6G_MB_LIB.T6G(SCH_1):PAGE339_I134@PURE_QUANTA.Q_RES(CHIPS)':
 'A': CDS_PINID='A';
NET_NAME
'P12V_OCP_SFF_EN'
 '@T6G_MB_LIB.T6G(SCH_1):P12V_OCP_SFF_EN':
 C_SIGNAL='@t6g_mb_lib.t6g(sch_1):p12v_ocp_sff_en';
NODE_NAME     U18 F9
 '@T6G_MB_LIB.T6G(SCH_1):PAGE79_I94@PURE_QUANTA.LCMXO3LF9400C5BG484C(CHIPS)':
 'PT21C': CDS_PINID='PT21C';
NODE_NAME     R152 1
 '@T6G_MB_LIB.T6G(SCH_1):PAGE79_I153@PURE_QUANTA.Q_RES(CHIPS)':
 'A': CDS_PINID='A';
NET_NAME
'P12V_OCP_SFF_EN_R'
 '@T6G_MB_LIB.T6G(SCH_1):P12V_OCP_SFF_EN_R':
 C_SIGNAL='@t6g_mb_lib.t6g(sch_1):p12v_ocp_sff_en_r';
NODE_NAME     R1195 1
 '@T6G_MB_LIB.T6G(SCH_1):PAGE82_I36@PURE_QUANTA.Q_RES(CHIPS)':
 'A': CDS_PINID='A';
NODE_NAME     R152 2
 '@T6G_MB_LIB.T6G(SCH_1):PAGE79_I153@PURE_QUANTA.Q_RES(CHIPS)':
 'B': CDS_PINID='B';
NODE_NAME     R4061 1
 '@T6G_MB_LIB.T6G(SCH_1):PAGE338_I123@PURE_QUANTA.Q_RES(CHIPS)':
 'A': CDS_PINID='A';
NODE_NAME     R3834 1
 '@T6G_MB_LIB.T6G(SCH_1):PAGE339_I128@PURE_QUANTA.Q_RES(CHIPS)':
 'A': CDS_PINID='A';
NODE_NAME     R1130 1
 '@T6G_MB_LIB.T6G(SCH_1):PAGE340_I49@PURE_QUANTA.Q_RES(CHIPS)':
 'A': CDS_PINID='A';
NET_NAME
'P12V_OCP_SFF_EN_R3'
 '@T6G_MB_LIB.T6G(SCH_1):P12V_OCP_SFF_EN_R3':
 C_SIGNAL='@t6g_mb_lib.t6g(sch_1):p12v_ocp_sff_en_r3';
NODE_NAME     U23 1
 '@T6G_MB_LIB.T6G(SCH_1):PAGE340_I36@PURE_QUANTA.74LVC1G08W57(CHIPS)':
 'A': CDS_PINID='A';
NODE_NAME     R1131 2
 '@T6G_MB_LIB.T6G(SCH_1):PAGE340_I44@PURE_QUANTA.Q_RES(CHIPS)':
 'B': CDS_PINID='B';
NODE_NAME     R1130 2
 '@T6G_MB_LIB.T6G(SCH_1):PAGE340_I49@PURE_QUANTA.Q_RES(CHIPS)':
 'B': CDS_PINID='B';
NET_NAME
'P12V_OCP_SFF_ISENSE_MAM'
 '@T6G_MB_LIB.T6G(SCH_1):P12V_OCP_SFF_ISENSE_MAM':
 C_SIGNAL='@t6g_mb_lib.t6g(sch_1):p12v_ocp_sff_isense_mam';
NODE_NAME     R3864 2
 '@T6G_MB_LIB.T6G(SCH_1):PAGE369_I110@PURE_QUANTA.Q_RES(CHIPS)':
 'B': CDS_PINID='B';
NODE_NAME     C2176 1
 '@T6G_MB_LIB.T6G(SCH_1):PAGE369_I114@PURE_QUANTA.Q_CAP(CHIPS)':
 'A': CDS_PINID='A';
NODE_NAME     R3863 2
 '@T6G_MB_LIB.T6G(SCH_1):PAGE369_I115@PURE_QUANTA.Q_RES(CHIPS)':
 'B': CDS_PINID='B';
NODE_NAME     U193 6
 '@T6G_MB_LIB.T6G(SCH_1):PAGE369_I169@PURE_QUANTA.MAX11617EEET(CHIPS)':
 'AIN1': CDS_PINID='AIN1';
NET_NAME
'P12V_OCP_SFF_ISENSE_MAM_MAM'
 '@T6G_MB_LIB.T6G(SCH_1):P12V_OCP_SFF_ISENSE_MAM_MAM':
 C_SIGNAL='@t6g_mb_lib.t6g(sch_1):p12v_ocp_sff_isense_mam_mam';
NODE_NAME     R3869 2
 '@T6G_MB_LIB.T6G(SCH_1):PAGE338_I82@PURE_QUANTA.Q_RES(CHIPS)':
 'B': CDS_PINID='B';
NODE_NAME     R3863 1
 '@T6G_MB_LIB.T6G(SCH_1):PAGE369_I115@PURE_QUANTA.Q_RES(CHIPS)':
 'A': CDS_PINID='A';
NET_NAME
'P12V_OCP_SFF_ISENSE_MAM_TIC'
 '@T6G_MB_LIB.T6G(SCH_1):P12V_OCP_SFF_ISENSE_MAM_TIC':
 C_SIGNAL='@t6g_mb_lib.t6g(sch_1):p12v_ocp_sff_isense_mam_tic';
NODE_NAME     R3870 2
 '@T6G_MB_LIB.T6G(SCH_1):PAGE338_I80@PURE_QUANTA.Q_RES(CHIPS)':
 'B': CDS_PINID='B';
NODE_NAME     R3865 1
 '@T6G_MB_LIB.T6G(SCH_1):PAGE369_I109@PURE_QUANTA.Q_RES(CHIPS)':
 'A': CDS_PINID='A';
NET_NAME
'P12V_OCP_SFF_ISENSE_MPS_MAM'
 '@T6G_MB_LIB.T6G(SCH_1):P12V_OCP_SFF_ISENSE_MPS_MAM':
 C_SIGNAL='@t6g_mb_lib.t6g(sch_1):p12v_ocp_sff_isense_mps_mam';
NODE_NAME     R3871 2
 '@T6G_MB_LIB.T6G(SCH_1):PAGE339_I85@PURE_QUANTA.Q_RES(CHIPS)':
 'B': CDS_PINID='B';
NODE_NAME     R3864 1
 '@T6G_MB_LIB.T6G(SCH_1):PAGE369_I110@PURE_QUANTA.Q_RES(CHIPS)':
 'A': CDS_PINID='A';
NET_NAME
'P12V_OCP_SFF_ISENSE_MPS_TIC'
 '@T6G_MB_LIB.T6G(SCH_1):P12V_OCP_SFF_ISENSE_MPS_TIC':
 C_SIGNAL='@t6g_mb_lib.t6g(sch_1):p12v_ocp_sff_isense_mps_tic';
NODE_NAME     R3872 2
 '@T6G_MB_LIB.T6G(SCH_1):PAGE339_I84@PURE_QUANTA.Q_RES(CHIPS)':
 'B': CDS_PINID='B';
NODE_NAME     R3866 1
 '@T6G_MB_LIB.T6G(SCH_1):PAGE369_I108@PURE_QUANTA.Q_RES(CHIPS)':
 'A': CDS_PINID='A';
NET_NAME
'P12V_OCP_SFF_ISENSE_TIC'
 '@T6G_MB_LIB.T6G(SCH_1):P12V_OCP_SFF_ISENSE_TIC':
 C_SIGNAL='@t6g_mb_lib.t6g(sch_1):p12v_ocp_sff_isense_tic';
NODE_NAME     R3866 2
 '@T6G_MB_LIB.T6G(SCH_1):PAGE369_I108@PURE_QUANTA.Q_RES(CHIPS)':
 'B': CDS_PINID='B';
NODE_NAME     R3865 2
 '@T6G_MB_LIB.T6G(SCH_1):PAGE369_I109@PURE_QUANTA.Q_RES(CHIPS)':
 'B': CDS_PINID='B';
NODE_NAME     C37 1
 '@T6G_MB_LIB.T6G(SCH_1):PAGE369_I112@PURE_QUANTA.Q_CAP(CHIPS)':
 'A': CDS_PINID='A';
NODE_NAME     U269 15
 '@T6G_MB_LIB.T6G(SCH_1):PAGE369_I142@PURE_QUANTA.ADC128D818CIMTXNOPB(CHIPS)':
 'IN1': CDS_PINID='IN1';
NET_NAME
'P12V_OCP_SFF_R'
 '@T6G_MB_LIB.T6G(SCH_1):P12V_OCP_SFF_R':
 C_SIGNAL='@t6g_mb_lib.t6g(sch_1):p12v_ocp_sff_r',
 CDS_GLOBAL_NET='TRUE';
NODE_NAME     C21 1
 '@T6G_MB_LIB.T6G(SCH_1):PAGE335_I89@PURE_QUANTA.Q_CAP(CHIPS)':
 'A': CDS_PINID='A';
NODE_NAME     C1235 1
 '@T6G_MB_LIB.T6G(SCH_1):PAGE335_I90@PURE_QUANTA.Q_CAP(CHIPS)':
 'A': CDS_PINID='A';
NODE_NAME     J38 B1
 '@T6G_MB_LIB.T6G(SCH_1):PAGE335_I168@PURE_QUANTA.SCONN168_ME1016810202011(CHIPS)':
 '+12V_EDGE_B1': CDS_PINID='\+12v_edge_b1\';
NODE_NAME     J38 B2
 '@T6G_MB_LIB.T6G(SCH_1):PAGE335_I168@PURE_QUANTA.SCONN168_ME1016810202011(CHIPS)':
 '+12V_EDGE_B2': CDS_PINID='\+12v_edge_b2\';
NODE_NAME     J38 B3
 '@T6G_MB_LIB.T6G(SCH_1):PAGE335_I168@PURE_QUANTA.SCONN168_ME1016810202011(CHIPS)':
 '+12V_EDGE_B3': CDS_PINID='\+12v_edge_b3\';
NODE_NAME     J38 B4
 '@T6G_MB_LIB.T6G(SCH_1):PAGE335_I168@PURE_QUANTA.SCONN168_ME1016810202011(CHIPS)':
 '+12V_EDGE_B4': CDS_PINID='\+12v_edge_b4\';
NODE_NAME     J38 B5
 '@T6G_MB_LIB.T6G(SCH_1):PAGE335_I168@PURE_QUANTA.SCONN168_ME1016810202011(CHIPS)':
 '+12V_EDGE_B5': CDS_PINID='\+12v_edge_b5\';
NODE_NAME     J38 B6
 '@T6G_MB_LIB.T6G(SCH_1):PAGE335_I168@PURE_QUANTA.SCONN168_ME1016810202011(CHIPS)':
 '+12V_EDGE_B6': CDS_PINID='\+12v_edge_b6\';
NODE_NAME     C1213 1
 '@T6G_MB_LIB.T6G(SCH_1):PAGE335_I87@PURE_QUANTA.Q_CAP(CHIPS)':
 'A': CDS_PINID='A';
NODE_NAME     C34 1
 '@T6G_MB_LIB.T6G(SCH_1):PAGE335_I88@PURE_QUANTA.Q_CAP(CHIPS)':
 'A': CDS_PINID='A';
NODE_NAME     C27 1
 '@T6G_MB_LIB.T6G(SCH_1):PAGE335_I163@PURE_QUANTA.Q_CAP(CHIPS)':
 'A': CDS_PINID='A';
NODE_NAME     C1236 1
 '@T6G_MB_LIB.T6G(SCH_1):PAGE335_I164@PURE_QUANTA.Q_CAP(CHIPS)':
 'A': CDS_PINID='A';
NODE_NAME     R1324 1
 '@T6G_MB_LIB.T6G(SCH_1):PAGE466_I2@PURE_QUANTA.Q_RES(CHIPS)':
 'A': CDS_PINID='A';
NODE_NAME     R1301 1
 '@T6G_MB_LIB.T6G(SCH_1):PAGE466_I11@PURE_QUANTA.Q_RES(CHIPS)':
 'A': CDS_PINID='A';
NET_NAME
'P12V_OCP_SS_1'
 '@T6G_MB_LIB.T6G(SCH_1):P12V_OCP_SS_1':
 C_SIGNAL='@t6g_mb_lib.t6g(sch_1):p12v_ocp_ss_1';
NODE_NAME     PC2155 1
 '@T6G_MB_LIB.T6G(SCH_1):PAGE339_I64@PURE_QUANTA.Q_CAP(CHIPS)':
 'A': CDS_PINID='A';
NODE_NAME     PU204 6
 '@T6G_MB_LIB.T6G(SCH_1):PAGE339_I137@PURE_QUANTA.RS31312R(CHIPS)':
 'SS': CDS_PINID='SS';
NET_NAME
'P12V_OCP_SS_2'
 '@T6G_MB_LIB.T6G(SCH_1):P12V_OCP_SS_2':
 C_SIGNAL='@t6g_mb_lib.t6g(sch_1):p12v_ocp_ss_2';
NODE_NAME     PC2166 1
 '@T6G_MB_LIB.T6G(SCH_1):PAGE344_I6@PURE_QUANTA.Q_CAP(CHIPS)':
 'A': CDS_PINID='A';
NODE_NAME     PU206 6
 '@T6G_MB_LIB.T6G(SCH_1):PAGE344_I82@PURE_QUANTA.RS31312R(CHIPS)':
 'SS': CDS_PINID='SS';
NET_NAME
'P12V_OCP_TIMER_1'
 '@T6G_MB_LIB.T6G(SCH_1):P12V_OCP_TIMER_1':
 C_SIGNAL='@t6g_mb_lib.t6g(sch_1):p12v_ocp_timer_1';
NODE_NAME     PC2153 1
 '@T6G_MB_LIB.T6G(SCH_1):PAGE339_I60@PURE_QUANTA.Q_CAP(CHIPS)':
 'A': CDS_PINID='A';
NODE_NAME     PU204 4
 '@T6G_MB_LIB.T6G(SCH_1):PAGE339_I137@PURE_QUANTA.RS31312R(CHIPS)':
 'TIMER': CDS_PINID='TIMER';
NET_NAME
'P12V_OCP_TIMER_2'
 '@T6G_MB_LIB.T6G(SCH_1):P12V_OCP_TIMER_2':
 C_SIGNAL='@t6g_mb_lib.t6g(sch_1):p12v_ocp_timer_2';
NODE_NAME     PC2164 1
 '@T6G_MB_LIB.T6G(SCH_1):PAGE344_I2@PURE_QUANTA.Q_CAP(CHIPS)':
 'A': CDS_PINID='A';
NODE_NAME     PU206 4
 '@T6G_MB_LIB.T6G(SCH_1):PAGE344_I82@PURE_QUANTA.RS31312R(CHIPS)':
 'TIMER': CDS_PINID='TIMER';
NET_NAME
'P12V_OCP_UV_1'
 '@T6G_MB_LIB.T6G(SCH_1):P12V_OCP_UV_1':
 C_SIGNAL='@t6g_mb_lib.t6g(sch_1):p12v_ocp_uv_1';
NODE_NAME     R3784 2
 '@T6G_MB_LIB.T6G(SCH_1):PAGE338_I40@PURE_QUANTA.Q_RES(CHIPS)':
 'B': CDS_PINID='B';
NODE_NAME     PR3787 1
 '@T6G_MB_LIB.T6G(SCH_1):PAGE338_I42@PURE_QUANTA.Q_RES(CHIPS)':
 'A': CDS_PINID='A';
NODE_NAME     PR3786 2
 '@T6G_MB_LIB.T6G(SCH_1):PAGE338_I43@PURE_QUANTA.Q_RES(CHIPS)':
 'B': CDS_PINID='B';
NODE_NAME     PU203 D2
 '@T6G_MB_LIB.T6G(SCH_1):PAGE338_I50@PURE_QUANTA.MAX15090BEWIT(CHIPS)':
 'UV': CDS_PINID='UV';
NET_NAME
'P12V_OCP_UV_1_R'
 '@T6G_MB_LIB.T6G(SCH_1):P12V_OCP_UV_1_R':
 C_SIGNAL='@t6g_mb_lib.t6g(sch_1):p12v_ocp_uv_1_r';
NODE_NAME     Q123 3
 '@T6G_MB_LIB.T6G(SCH_1):PAGE338_I19@PURE_QUANTA.MOSFET_NCH_DUAL(CHIPS)':
 'D2': CDS_PINID='D2';
NODE_NAME     R3784 1
 '@T6G_MB_LIB.T6G(SCH_1):PAGE338_I40@PURE_QUANTA.Q_RES(CHIPS)':
 'A': CDS_PINID='A';
NET_NAME
'P12V_OCP_UV_2'
 '@T6G_MB_LIB.T6G(SCH_1):P12V_OCP_UV_2':
 C_SIGNAL='@t6g_mb_lib.t6g(sch_1):p12v_ocp_uv_2';
NODE_NAME     R3827 2
 '@T6G_MB_LIB.T6G(SCH_1):PAGE343_I33@PURE_QUANTA.Q_RES(CHIPS)':
 'B': CDS_PINID='B';
NODE_NAME     PR3806 1
 '@T6G_MB_LIB.T6G(SCH_1):PAGE343_I35@PURE_QUANTA.Q_RES(CHIPS)':
 'A': CDS_PINID='A';
NODE_NAME     PR3805 2
 '@T6G_MB_LIB.T6G(SCH_1):PAGE343_I36@PURE_QUANTA.Q_RES(CHIPS)':
 'B': CDS_PINID='B';
NODE_NAME     PU201 D2
 '@T6G_MB_LIB.T6G(SCH_1):PAGE343_I67@PURE_QUANTA.MAX15090BEWIT(CHIPS)':
 'UV': CDS_PINID='UV';
NET_NAME
'P12V_OCP_UV_2_R'
 '@T6G_MB_LIB.T6G(SCH_1):P12V_OCP_UV_2_R':
 C_SIGNAL='@t6g_mb_lib.t6g(sch_1):p12v_ocp_uv_2_r';
NODE_NAME     Q118 3
 '@T6G_MB_LIB.T6G(SCH_1):PAGE343_I19@PURE_QUANTA.MOSFET_NCH_DUAL(CHIPS)':
 'D2': CDS_PINID='D2';
NODE_NAME     R3827 1
 '@T6G_MB_LIB.T6G(SCH_1):PAGE343_I33@PURE_QUANTA.Q_RES(CHIPS)':
 'A': CDS_PINID='A';
NET_NAME
'P12V_OCP_V3_1_PLD_PWRGD'
 '@T6G_MB_LIB.T6G(SCH_1):P12V_OCP_V3_1_PLD_PWRGD':
 C_SIGNAL='@t6g_mb_lib.t6g(sch_1):p12v_ocp_v3_1_pld_pwrgd';
NODE_NAME     R6051 2
 '@T6G_MB_LIB.T6G(SCH_1):PAGE81_I102@PURE_QUANTA.Q_RES(CHIPS)':
 'B': CDS_PINID='B';
NODE_NAME     R1132 2
 '@T6G_MB_LIB.T6G(SCH_1):PAGE340_I58@PURE_QUANTA.Q_RES(CHIPS)':
 'B': CDS_PINID='B';
NODE_NAME     R1133 2
 '@T6G_MB_LIB.T6G(SCH_1):PAGE340_I61@PURE_QUANTA.Q_RES(CHIPS)':
 'B': CDS_PINID='B';
NET_NAME
'P12V_OCP_V3_1_PLD_R_PWRGD'
 '@T6G_MB_LIB.T6G(SCH_1):P12V_OCP_V3_1_PLD_R_PWRGD':
 C_SIGNAL='@t6g_mb_lib.t6g(sch_1):p12v_ocp_v3_1_pld_r_pwrgd';
NODE_NAME     U28 4
 '@T6G_MB_LIB.T6G(SCH_1):PAGE340_I51@PURE_QUANTA.SN74LVC1G07DBVR(CHIPS)':
 'Y': CDS_PINID='Y';
NODE_NAME     R1132 1
 '@T6G_MB_LIB.T6G(SCH_1):PAGE340_I58@PURE_QUANTA.Q_RES(CHIPS)':
 'A': CDS_PINID='A';
NET_NAME
'P12V_OCP_V3_1_PWRGD'
 '@T6G_MB_LIB.T6G(SCH_1):P12V_OCP_V3_1_PWRGD':
 C_SIGNAL='@t6g_mb_lib.t6g(sch_1):p12v_ocp_v3_1_pwrgd';
NODE_NAME     R6051 1
 '@T6G_MB_LIB.T6G(SCH_1):PAGE81_I102@PURE_QUANTA.Q_RES(CHIPS)':
 'A': CDS_PINID='A';
NODE_NAME     U18 W2
 '@T6G_MB_LIB.T6G(SCH_1):PAGE81_I143@PURE_QUANTA.LCMXO3LF9400C5BG484C(CHIPS)':
 'PL28B': CDS_PINID='PL28B';
NET_NAME
'P12V_OCP_V3_2'
 '@T6G_MB_LIB.T6G(SCH_1):P12V_OCP_V3_2':
 C_SIGNAL='@t6g_mb_lib.t6g(sch_1):p12v_ocp_v3_2',
 CDS_GLOBAL_NET='TRUE';
NODE_NAME     PU201 A4
 '@T6G_MB_LIB.T6G(SCH_1):PAGE343_I67@PURE_QUANTA.MAX15090BEWIT(CHIPS)':
 'OUT_A4': CDS_PINID='OUT_A4';
NODE_NAME     PU201 B4
 '@T6G_MB_LIB.T6G(SCH_1):PAGE343_I67@PURE_QUANTA.MAX15090BEWIT(CHIPS)':
 'OUT_B4': CDS_PINID='OUT_B4';
NODE_NAME     PU201 B6
 '@T6G_MB_LIB.T6G(SCH_1):PAGE343_I67@PURE_QUANTA.MAX15090BEWIT(CHIPS)':
 'OUT_B6': CDS_PINID='OUT_B6';
NODE_NAME     PU201 C4
 '@T6G_MB_LIB.T6G(SCH_1):PAGE343_I67@PURE_QUANTA.MAX15090BEWIT(CHIPS)':
 'OUT_C4': CDS_PINID='OUT_C4';
NODE_NAME     PU201 C6
 '@T6G_MB_LIB.T6G(SCH_1):PAGE343_I67@PURE_QUANTA.MAX15090BEWIT(CHIPS)':
 'OUT_C6': CDS_PINID='OUT_C6';
NODE_NAME     PU201 D4
 '@T6G_MB_LIB.T6G(SCH_1):PAGE343_I67@PURE_QUANTA.MAX15090BEWIT(CHIPS)':
 'OUT_D4': CDS_PINID='OUT_D4';
NODE_NAME     PU201 D6
 '@T6G_MB_LIB.T6G(SCH_1):PAGE343_I67@PURE_QUANTA.MAX15090BEWIT(CHIPS)':
 'OUT_D6': CDS_PINID='OUT_D6';
NODE_NAME     PD108 C
 '@T6G_MB_LIB.T6G(SCH_1):PAGE343_I92@PURE_QUANTA.SCHOTTKY_AC(CHIPS)':
 'C': CDS_PINID='C';
NODE_NAME     PC2152 1
 '@T6G_MB_LIB.T6G(SCH_1):PAGE343_I97@PURE_QUANTA.Q_CAP(CHIPS)':
 'A': CDS_PINID='A';
NODE_NAME     PC2141 1
 '@T6G_MB_LIB.T6G(SCH_1):PAGE343_I99@PURE_QUANTA.Q_CAP(CHIPS)':
 'A': CDS_PINID='A';
NODE_NAME     PC2143 1
 '@T6G_MB_LIB.T6G(SCH_1):PAGE343_I101@PURE_QUANTA.Q_CAP(CHIPS)':
 'A': CDS_PINID='A';
NODE_NAME     PR3850 1
 '@T6G_MB_LIB.T6G(SCH_1):PAGE344_I30@PURE_QUANTA.Q_RES(CHIPS)':
 'A': CDS_PINID='A';
NODE_NAME     PR3852 1
 '@T6G_MB_LIB.T6G(SCH_1):PAGE344_I31@PURE_QUANTA.Q_RES(CHIPS)':
 'A': CDS_PINID='A';
NODE_NAME     PC2174 1
 '@T6G_MB_LIB.T6G(SCH_1):PAGE344_I40@PURE_QUANTA.Q_CAP(CHIPS)':
 'A': CDS_PINID='A';
NODE_NAME     C40 1
 '@T6G_MB_LIB.T6G(SCH_1):PAGE343_I72@PURE_QUANTA.Q_CAP(CHIPS)':
 'A': CDS_PINID='A';
NODE_NAME     PR4522 1
 '@T6G_MB_LIB.T6G(SCH_1):PAGE343_I76@PURE_QUANTA.Q_RES(CHIPS)':
 'A': CDS_PINID='A';
NODE_NAME     U56 11
 '@T6G_MB_LIB.T6G(SCH_1):PAGE466_I29@PURE_QUANTA.ISL28022FRZT(CHIPS)':
 'VBUS': CDS_PINID='VBUS';
NODE_NAME     R1291 1
 '@T6G_MB_LIB.T6G(SCH_1):PAGE466_I43@PURE_QUANTA.Q_RES(CHIPS)':
 'A': CDS_PINID='A';
NODE_NAME     C1109 1
 '@T6G_MB_LIB.T6G(SCH_1):PAGE466_I51@PURE_QUANTA.Q_CAP(CHIPS)':
 'A': CDS_PINID='A';
NODE_NAME     R1325 2
 '@T6G_MB_LIB.T6G(SCH_1):PAGE466_I53@PURE_QUANTA.Q_RES(CHIPS)':
 'B': CDS_PINID='B';
NODE_NAME     PU206 13
 '@T6G_MB_LIB.T6G(SCH_1):PAGE344_I82@PURE_QUANTA.RS31312R(CHIPS)':
 'VOUT_13': CDS_PINID='VOUT_13';
NODE_NAME     PU206 14
 '@T6G_MB_LIB.T6G(SCH_1):PAGE344_I82@PURE_QUANTA.RS31312R(CHIPS)':
 'VOUT_14': CDS_PINID='VOUT_14';
NODE_NAME     PU206 15
 '@T6G_MB_LIB.T6G(SCH_1):PAGE344_I82@PURE_QUANTA.RS31312R(CHIPS)':
 'VOUT_15': CDS_PINID='VOUT_15';
NODE_NAME     PU206 16
 '@T6G_MB_LIB.T6G(SCH_1):PAGE344_I82@PURE_QUANTA.RS31312R(CHIPS)':
 'VOUT_16': CDS_PINID='VOUT_16';
NODE_NAME     PU206 17
 '@T6G_MB_LIB.T6G(SCH_1):PAGE344_I82@PURE_QUANTA.RS31312R(CHIPS)':
 'VOUT_17': CDS_PINID='VOUT_17';
NODE_NAME     PU206 18
 '@T6G_MB_LIB.T6G(SCH_1):PAGE344_I82@PURE_QUANTA.RS31312R(CHIPS)':
 'VOUT_18': CDS_PINID='VOUT_18';
NODE_NAME     PU206 19
 '@T6G_MB_LIB.T6G(SCH_1):PAGE344_I82@PURE_QUANTA.RS31312R(CHIPS)':
 'VOUT_19': CDS_PINID='VOUT_19';
NODE_NAME     PU206 20
 '@T6G_MB_LIB.T6G(SCH_1):PAGE344_I82@PURE_QUANTA.RS31312R(CHIPS)':
 'VOUT_20': CDS_PINID='VOUT_20';
NET_NAME
'P12V_OCP_V3_2_ADC_ALERT_R'
 '@T6G_MB_LIB.T6G(SCH_1):P12V_OCP_V3_2_ADC_ALERT_R':
 C_SIGNAL='@t6g_mb_lib.t6g(sch_1):p12v_ocp_v3_2_adc_alert_r';
NODE_NAME     U56 3
 '@T6G_MB_LIB.T6G(SCH_1):PAGE466_I29@PURE_QUANTA.ISL28022FRZT(CHIPS)':
 'EXT_CLK||INT': CDS_PINID='\ext_clk||int\';
NODE_NAME     R1271 1
 '@T6G_MB_LIB.T6G(SCH_1):PAGE466_I33@PURE_QUANTA.Q_RES(CHIPS)':
 'A': CDS_PINID='A';
NET_NAME
'P12V_OCP_V3_2_BUF_EN'
 '@T6G_MB_LIB.T6G(SCH_1):P12V_OCP_V3_2_BUF_EN':
 C_SIGNAL='@t6g_mb_lib.t6g(sch_1):p12v_ocp_v3_2_buf_en';
NODE_NAME     U31 4
 '@T6G_MB_LIB.T6G(SCH_1):PAGE257_I31@PURE_QUANTA.74LVC1G08W57(CHIPS)':
 'Y': CDS_PINID='Y';
NODE_NAME     R1168 1
 '@T6G_MB_LIB.T6G(SCH_1):PAGE257_I57@PURE_QUANTA.Q_RES(CHIPS)':
 'A': CDS_PINID='A';
NET_NAME
'P12V_OCP_V3_2_BUF_EN_R'
 '@T6G_MB_LIB.T6G(SCH_1):P12V_OCP_V3_2_BUF_EN_R':
 C_SIGNAL='@t6g_mb_lib.t6g(sch_1):p12v_ocp_v3_2_buf_en_r';
NODE_NAME     R1168 2
 '@T6G_MB_LIB.T6G(SCH_1):PAGE257_I57@PURE_QUANTA.Q_RES(CHIPS)':
 'B': CDS_PINID='B';
NODE_NAME     R1181 1
 '@T6G_MB_LIB.T6G(SCH_1):PAGE343_I123@PURE_QUANTA.Q_RES(CHIPS)':
 'A': CDS_PINID='A';
NODE_NAME     R1193 1
 '@T6G_MB_LIB.T6G(SCH_1):PAGE344_I76@PURE_QUANTA.Q_RES(CHIPS)':
 'A': CDS_PINID='A';
NODE_NAME     R1522 2
 '@T6G_MB_LIB.T6G(SCH_1):PAGE248_I44@PURE_QUANTA.Q_RES(CHIPS)':
 'B': CDS_PINID='B';
NODE_NAME     R1520 1
 '@T6G_MB_LIB.T6G(SCH_1):PAGE343_I130@PURE_QUANTA.Q_RES(CHIPS)':
 'A': CDS_PINID='A';
NODE_NAME     R1521 1
 '@T6G_MB_LIB.T6G(SCH_1):PAGE344_I80@PURE_QUANTA.Q_RES(CHIPS)':
 'A': CDS_PINID='A';
NET_NAME
'P12V_OCP_V3_2_EN_2_R3'
 '@T6G_MB_LIB.T6G(SCH_1):P12V_OCP_V3_2_EN_2_R3':
 C_SIGNAL='@t6g_mb_lib.t6g(sch_1):p12v_ocp_v3_2_en_2_r3';
NODE_NAME     R3630 2
 '@T6G_MB_LIB.T6G(SCH_1):PAGE344_I73@PURE_QUANTA.Q_RES(CHIPS)':
 'B': CDS_PINID='B';
NODE_NAME     R1193 2
 '@T6G_MB_LIB.T6G(SCH_1):PAGE344_I76@PURE_QUANTA.Q_RES(CHIPS)':
 'B': CDS_PINID='B';
NODE_NAME     PU206 1
 '@T6G_MB_LIB.T6G(SCH_1):PAGE344_I82@PURE_QUANTA.RS31312R(CHIPS)':
 'EN': CDS_PINID='EN';
NET_NAME
'P12V_OCP_V3_2_EN_R'
 '@T6G_MB_LIB.T6G(SCH_1):P12V_OCP_V3_2_EN_R':
 C_SIGNAL='@t6g_mb_lib.t6g(sch_1):p12v_ocp_v3_2_en_r';
NODE_NAME     R6061 1
 '@T6G_MB_LIB.T6G(SCH_1):PAGE82_I39@PURE_QUANTA.Q_RES(CHIPS)':
 'A': CDS_PINID='A';
NODE_NAME     U18 AA20
 '@T6G_MB_LIB.T6G(SCH_1):PAGE80_I216@PURE_QUANTA.LCMXO3LF9400C5BG484C(CHIPS)':
 'PB44B': CDS_PINID='PB44B';
NODE_NAME     R1164 1
 '@T6G_MB_LIB.T6G(SCH_1):PAGE257_I28@PURE_QUANTA.Q_RES(CHIPS)':
 'A': CDS_PINID='A';
NODE_NAME     R4059 1
 '@T6G_MB_LIB.T6G(SCH_1):PAGE343_I119@PURE_QUANTA.Q_RES(CHIPS)':
 'A': CDS_PINID='A';
NODE_NAME     R3630 1
 '@T6G_MB_LIB.T6G(SCH_1):PAGE344_I73@PURE_QUANTA.Q_RES(CHIPS)':
 'A': CDS_PINID='A';
NET_NAME
'P12V_OCP_V3_2_EN_R3'
 '@T6G_MB_LIB.T6G(SCH_1):P12V_OCP_V3_2_EN_R3':
 C_SIGNAL='@t6g_mb_lib.t6g(sch_1):p12v_ocp_v3_2_en_r3';
NODE_NAME     R1164 2
 '@T6G_MB_LIB.T6G(SCH_1):PAGE257_I28@PURE_QUANTA.Q_RES(CHIPS)':
 'B': CDS_PINID='B';
NODE_NAME     U31 1
 '@T6G_MB_LIB.T6G(SCH_1):PAGE257_I31@PURE_QUANTA.74LVC1G08W57(CHIPS)':
 'A': CDS_PINID='A';
NODE_NAME     R1165 2
 '@T6G_MB_LIB.T6G(SCH_1):PAGE257_I32@PURE_QUANTA.Q_RES(CHIPS)':
 'B': CDS_PINID='B';
NET_NAME
'P12V_OCP_V3_2_ISENSE_MAM'
 '@T6G_MB_LIB.T6G(SCH_1):P12V_OCP_V3_2_ISENSE_MAM':
 C_SIGNAL='@t6g_mb_lib.t6g(sch_1):p12v_ocp_v3_2_isense_mam';
NODE_NAME     R3860 2
 '@T6G_MB_LIB.T6G(SCH_1):PAGE369_I83@PURE_QUANTA.Q_RES(CHIPS)':
 'B': CDS_PINID='B';
NODE_NAME     C59 1
 '@T6G_MB_LIB.T6G(SCH_1):PAGE369_I87@PURE_QUANTA.Q_CAP(CHIPS)':
 'A': CDS_PINID='A';
NODE_NAME     R3859 2
 '@T6G_MB_LIB.T6G(SCH_1):PAGE369_I107@PURE_QUANTA.Q_RES(CHIPS)':
 'B': CDS_PINID='B';
NODE_NAME     U193 7
 '@T6G_MB_LIB.T6G(SCH_1):PAGE369_I169@PURE_QUANTA.MAX11617EEET(CHIPS)':
 'AIN2': CDS_PINID='AIN2';
NET_NAME
'P12V_OCP_V3_2_ISENSE_MAM_MAM'
 '@T6G_MB_LIB.T6G(SCH_1):P12V_OCP_V3_2_ISENSE_MAM_MAM':
 C_SIGNAL='@t6g_mb_lib.t6g(sch_1):p12v_ocp_v3_2_isense_mam_mam';
NODE_NAME     R3867 2
 '@T6G_MB_LIB.T6G(SCH_1):PAGE343_I74@PURE_QUANTA.Q_RES(CHIPS)':
 'B': CDS_PINID='B';
NODE_NAME     R3859 1
 '@T6G_MB_LIB.T6G(SCH_1):PAGE369_I107@PURE_QUANTA.Q_RES(CHIPS)':
 'A': CDS_PINID='A';
NET_NAME
'P12V_OCP_V3_2_ISENSE_MAM_TIC'
 '@T6G_MB_LIB.T6G(SCH_1):P12V_OCP_V3_2_ISENSE_MAM_TIC':
 C_SIGNAL='@t6g_mb_lib.t6g(sch_1):p12v_ocp_v3_2_isense_mam_tic';
NODE_NAME     R3868 2
 '@T6G_MB_LIB.T6G(SCH_1):PAGE343_I73@PURE_QUANTA.Q_RES(CHIPS)':
 'B': CDS_PINID='B';
NODE_NAME     R3861 1
 '@T6G_MB_LIB.T6G(SCH_1):PAGE369_I82@PURE_QUANTA.Q_RES(CHIPS)':
 'A': CDS_PINID='A';
NET_NAME
'P12V_OCP_V3_2_ISENSE_MPS_MAM'
 '@T6G_MB_LIB.T6G(SCH_1):P12V_OCP_V3_2_ISENSE_MPS_MAM':
 C_SIGNAL='@t6g_mb_lib.t6g(sch_1):p12v_ocp_v3_2_isense_mps_mam';
NODE_NAME     R3873 2
 '@T6G_MB_LIB.T6G(SCH_1):PAGE344_I23@PURE_QUANTA.Q_RES(CHIPS)':
 'B': CDS_PINID='B';
NODE_NAME     R3860 1
 '@T6G_MB_LIB.T6G(SCH_1):PAGE369_I83@PURE_QUANTA.Q_RES(CHIPS)':
 'A': CDS_PINID='A';
NET_NAME
'P12V_OCP_V3_2_ISENSE_MPS_TIC'
 '@T6G_MB_LIB.T6G(SCH_1):P12V_OCP_V3_2_ISENSE_MPS_TIC':
 C_SIGNAL='@t6g_mb_lib.t6g(sch_1):p12v_ocp_v3_2_isense_mps_tic';
NODE_NAME     R3874 2
 '@T6G_MB_LIB.T6G(SCH_1):PAGE344_I22@PURE_QUANTA.Q_RES(CHIPS)':
 'B': CDS_PINID='B';
NODE_NAME     R3862 1
 '@T6G_MB_LIB.T6G(SCH_1):PAGE369_I81@PURE_QUANTA.Q_RES(CHIPS)':
 'A': CDS_PINID='A';
NET_NAME
'P12V_OCP_V3_2_ISENSE_TIC'
 '@T6G_MB_LIB.T6G(SCH_1):P12V_OCP_V3_2_ISENSE_TIC':
 C_SIGNAL='@t6g_mb_lib.t6g(sch_1):p12v_ocp_v3_2_isense_tic';
NODE_NAME     R3862 2
 '@T6G_MB_LIB.T6G(SCH_1):PAGE369_I81@PURE_QUANTA.Q_RES(CHIPS)':
 'B': CDS_PINID='B';
NODE_NAME     R3861 2
 '@T6G_MB_LIB.T6G(SCH_1):PAGE369_I82@PURE_QUANTA.Q_RES(CHIPS)':
 'B': CDS_PINID='B';
NODE_NAME     C33 1
 '@T6G_MB_LIB.T6G(SCH_1):PAGE369_I84@PURE_QUANTA.Q_CAP(CHIPS)':
 'A': CDS_PINID='A';
NODE_NAME     U269 14
 '@T6G_MB_LIB.T6G(SCH_1):PAGE369_I142@PURE_QUANTA.ADC128D818CIMTXNOPB(CHIPS)':
 'IN2': CDS_PINID='IN2';
NET_NAME
'P12V_OCP_V3_2_PLD_PWRGD'
 '@T6G_MB_LIB.T6G(SCH_1):P12V_OCP_V3_2_PLD_PWRGD':
 C_SIGNAL='@t6g_mb_lib.t6g(sch_1):p12v_ocp_v3_2_pld_pwrgd';
NODE_NAME     R407 1
 '@T6G_MB_LIB.T6G(SCH_1):PAGE79_I139@PURE_QUANTA.Q_RES(CHIPS)':
 'A': CDS_PINID='A';
NODE_NAME     R1166 2
 '@T6G_MB_LIB.T6G(SCH_1):PAGE257_I18@PURE_QUANTA.Q_RES(CHIPS)':
 'B': CDS_PINID='B';
NODE_NAME     R1167 2
 '@T6G_MB_LIB.T6G(SCH_1):PAGE257_I19@PURE_QUANTA.Q_RES(CHIPS)':
 'B': CDS_PINID='B';
NET_NAME
'P12V_OCP_V3_2_PLD_R_PWRGD'
 '@T6G_MB_LIB.T6G(SCH_1):P12V_OCP_V3_2_PLD_R_PWRGD':
 C_SIGNAL='@t6g_mb_lib.t6g(sch_1):p12v_ocp_v3_2_pld_r_pwrgd';
NODE_NAME     R1166 1
 '@T6G_MB_LIB.T6G(SCH_1):PAGE257_I18@PURE_QUANTA.Q_RES(CHIPS)':
 'A': CDS_PINID='A';
NODE_NAME     U33 4
 '@T6G_MB_LIB.T6G(SCH_1):PAGE257_I64@PURE_QUANTA.SN74LVC1G07DBVR(CHIPS)':
 'Y': CDS_PINID='Y';
NET_NAME
'P12V_OCP_V3_2_R'
 '@T6G_MB_LIB.T6G(SCH_1):P12V_OCP_V3_2_R':
 C_SIGNAL='@t6g_mb_lib.t6g(sch_1):p12v_ocp_v3_2_r',
 CDS_GLOBAL_NET='TRUE';
NODE_NAME     C1834 1
 '@T6G_MB_LIB.T6G(SCH_1):PAGE341_I20@PURE_QUANTA.Q_CAP(CHIPS)':
 'A': CDS_PINID='A';
NODE_NAME     J35 B1
 '@T6G_MB_LIB.T6G(SCH_1):PAGE341_I168@PURE_QUANTA.SCONN168_ME1016810202011(CHIPS)':
 '+12V_EDGE_B1': CDS_PINID='\+12v_edge_b1\';
NODE_NAME     J35 B2
 '@T6G_MB_LIB.T6G(SCH_1):PAGE341_I168@PURE_QUANTA.SCONN168_ME1016810202011(CHIPS)':
 '+12V_EDGE_B2': CDS_PINID='\+12v_edge_b2\';
NODE_NAME     J35 B3
 '@T6G_MB_LIB.T6G(SCH_1):PAGE341_I168@PURE_QUANTA.SCONN168_ME1016810202011(CHIPS)':
 '+12V_EDGE_B3': CDS_PINID='\+12v_edge_b3\';
NODE_NAME     J35 B4
 '@T6G_MB_LIB.T6G(SCH_1):PAGE341_I168@PURE_QUANTA.SCONN168_ME1016810202011(CHIPS)':
 '+12V_EDGE_B4': CDS_PINID='\+12v_edge_b4\';
NODE_NAME     J35 B5
 '@T6G_MB_LIB.T6G(SCH_1):PAGE341_I168@PURE_QUANTA.SCONN168_ME1016810202011(CHIPS)':
 '+12V_EDGE_B5': CDS_PINID='\+12v_edge_b5\';
NODE_NAME     J35 B6
 '@T6G_MB_LIB.T6G(SCH_1):PAGE341_I168@PURE_QUANTA.SCONN168_ME1016810202011(CHIPS)':
 '+12V_EDGE_B6': CDS_PINID='\+12v_edge_b6\';
NODE_NAME     C1829 1
 '@T6G_MB_LIB.T6G(SCH_1):PAGE341_I13@PURE_QUANTA.Q_CAP(CHIPS)':
 'A': CDS_PINID='A';
NODE_NAME     C1830 1
 '@T6G_MB_LIB.T6G(SCH_1):PAGE341_I14@PURE_QUANTA.Q_CAP(CHIPS)':
 'A': CDS_PINID='A';
NODE_NAME     C1831 1
 '@T6G_MB_LIB.T6G(SCH_1):PAGE341_I15@PURE_QUANTA.Q_CAP(CHIPS)':
 'A': CDS_PINID='A';
NODE_NAME     C1832 1
 '@T6G_MB_LIB.T6G(SCH_1):PAGE341_I16@PURE_QUANTA.Q_CAP(CHIPS)':
 'A': CDS_PINID='A';
NODE_NAME     C1833 1
 '@T6G_MB_LIB.T6G(SCH_1):PAGE341_I17@PURE_QUANTA.Q_CAP(CHIPS)':
 'A': CDS_PINID='A';
NODE_NAME     C1839 1
 '@T6G_MB_LIB.T6G(SCH_1):PAGE341_I18@PURE_QUANTA.Q_CAP(CHIPS)':
 'A': CDS_PINID='A';
NODE_NAME     R1325 1
 '@T6G_MB_LIB.T6G(SCH_1):PAGE466_I53@PURE_QUANTA.Q_RES(CHIPS)':
 'A': CDS_PINID='A';
NODE_NAME     R1302 1
 '@T6G_MB_LIB.T6G(SCH_1):PAGE466_I55@PURE_QUANTA.Q_RES(CHIPS)':
 'A': CDS_PINID='A';
NET_NAME
'P12V_OCP_VCC_1'
 '@T6G_MB_LIB.T6G(SCH_1):P12V_OCP_VCC_1':
 C_SIGNAL='@t6g_mb_lib.t6g(sch_1):p12v_ocp_vcc_1';
NODE_NAME     PU203 A2
 '@T6G_MB_LIB.T6G(SCH_1):PAGE338_I50@PURE_QUANTA.MAX15090BEWIT(CHIPS)':
 'VCC': CDS_PINID='VCC';
NODE_NAME     PC2085 1
 '@T6G_MB_LIB.T6G(SCH_1):PAGE338_I55@PURE_QUANTA.Q_CAP(CHIPS)':
 'A': CDS_PINID='A';
NODE_NAME     PR3792 2
 '@T6G_MB_LIB.T6G(SCH_1):PAGE338_I56@PURE_QUANTA.Q_RES(CHIPS)':
 'B': CDS_PINID='B';
NET_NAME
'P12V_OCP_VCC_2'
 '@T6G_MB_LIB.T6G(SCH_1):P12V_OCP_VCC_2':
 C_SIGNAL='@t6g_mb_lib.t6g(sch_1):p12v_ocp_vcc_2';
NODE_NAME     PC2098 1
 '@T6G_MB_LIB.T6G(SCH_1):PAGE343_I65@PURE_QUANTA.Q_CAP(CHIPS)':
 'A': CDS_PINID='A';
NODE_NAME     PU201 A2
 '@T6G_MB_LIB.T6G(SCH_1):PAGE343_I67@PURE_QUANTA.MAX15090BEWIT(CHIPS)':
 'VCC': CDS_PINID='VCC';
NODE_NAME     PR3830 2
 '@T6G_MB_LIB.T6G(SCH_1):PAGE343_I84@PURE_QUANTA.Q_RES(CHIPS)':
 'B': CDS_PINID='B';
NET_NAME
'P12V_PSU'
 '@T6G_MB_LIB.T6G(SCH_1):P12V_PSU':
 C_SIGNAL='@t6g_mb_lib.t6g(sch_1):p12v_psu',
 CDS_GLOBAL_NET='TRUE';
NODE_NAME     PU288 9
 '@T6G_MB_LIB.T6G(SCH_1):PAGE301_I16@PURE_QUANTA.MP5991GLUZ(CHIPS)':
 'VIN1': CDS_PINID='VIN1';
NODE_NAME     PU288 10
 '@T6G_MB_LIB.T6G(SCH_1):PAGE301_I16@PURE_QUANTA.MP5991GLUZ(CHIPS)':
 'VIN2': CDS_PINID='VIN2';
NODE_NAME     PU288 11
 '@T6G_MB_LIB.T6G(SCH_1):PAGE301_I16@PURE_QUANTA.MP5991GLUZ(CHIPS)':
 'VIN3': CDS_PINID='VIN3';
NODE_NAME     PU288 12
 '@T6G_MB_LIB.T6G(SCH_1):PAGE301_I16@PURE_QUANTA.MP5991GLUZ(CHIPS)':
 'VIN4': CDS_PINID='VIN4';
NODE_NAME     PU288 13
 '@T6G_MB_LIB.T6G(SCH_1):PAGE301_I16@PURE_QUANTA.MP5991GLUZ(CHIPS)':
 'VIN5': CDS_PINID='VIN5';
NODE_NAME     PU288 14
 '@T6G_MB_LIB.T6G(SCH_1):PAGE301_I16@PURE_QUANTA.MP5991GLUZ(CHIPS)':
 'VIN6': CDS_PINID='VIN6';
NODE_NAME     PU288 15
 '@T6G_MB_LIB.T6G(SCH_1):PAGE301_I16@PURE_QUANTA.MP5991GLUZ(CHIPS)':
 'VIN7': CDS_PINID='VIN7';
NODE_NAME     PU288 16
 '@T6G_MB_LIB.T6G(SCH_1):PAGE301_I16@PURE_QUANTA.MP5991GLUZ(CHIPS)':
 'VIN8': CDS_PINID='VIN8';
NODE_NAME     PU288 33
 '@T6G_MB_LIB.T6G(SCH_1):PAGE301_I16@PURE_QUANTA.MP5991GLUZ(CHIPS)':
 'VIN9': CDS_PINID='VIN9';
NODE_NAME     PU287 9
 '@T6G_MB_LIB.T6G(SCH_1):PAGE301_I35@PURE_QUANTA.MP5991GLUZ(CHIPS)':
 'VIN1': CDS_PINID='VIN1';
NODE_NAME     PU287 10
 '@T6G_MB_LIB.T6G(SCH_1):PAGE301_I35@PURE_QUANTA.MP5991GLUZ(CHIPS)':
 'VIN2': CDS_PINID='VIN2';
NODE_NAME     PU287 11
 '@T6G_MB_LIB.T6G(SCH_1):PAGE301_I35@PURE_QUANTA.MP5991GLUZ(CHIPS)':
 'VIN3': CDS_PINID='VIN3';
NODE_NAME     PU287 12
 '@T6G_MB_LIB.T6G(SCH_1):PAGE301_I35@PURE_QUANTA.MP5991GLUZ(CHIPS)':
 'VIN4': CDS_PINID='VIN4';
NODE_NAME     PU287 13
 '@T6G_MB_LIB.T6G(SCH_1):PAGE301_I35@PURE_QUANTA.MP5991GLUZ(CHIPS)':
 'VIN5': CDS_PINID='VIN5';
NODE_NAME     PU287 14
 '@T6G_MB_LIB.T6G(SCH_1):PAGE301_I35@PURE_QUANTA.MP5991GLUZ(CHIPS)':
 'VIN6': CDS_PINID='VIN6';
NODE_NAME     PU287 15
 '@T6G_MB_LIB.T6G(SCH_1):PAGE301_I35@PURE_QUANTA.MP5991GLUZ(CHIPS)':
 'VIN7': CDS_PINID='VIN7';
NODE_NAME     PU287 16
 '@T6G_MB_LIB.T6G(SCH_1):PAGE301_I35@PURE_QUANTA.MP5991GLUZ(CHIPS)':
 'VIN8': CDS_PINID='VIN8';
NODE_NAME     PU287 33
 '@T6G_MB_LIB.T6G(SCH_1):PAGE301_I35@PURE_QUANTA.MP5991GLUZ(CHIPS)':
 'VIN9': CDS_PINID='VIN9';
NODE_NAME     PU297 9
 '@T6G_MB_LIB.T6G(SCH_1):PAGE325_I17@PURE_QUANTA.MP5991GLUZ(CHIPS)':
 'VIN1': CDS_PINID='VIN1';
NODE_NAME     PU297 10
 '@T6G_MB_LIB.T6G(SCH_1):PAGE325_I17@PURE_QUANTA.MP5991GLUZ(CHIPS)':
 'VIN2': CDS_PINID='VIN2';
NODE_NAME     PU297 11
 '@T6G_MB_LIB.T6G(SCH_1):PAGE325_I17@PURE_QUANTA.MP5991GLUZ(CHIPS)':
 'VIN3': CDS_PINID='VIN3';
NODE_NAME     PU297 12
 '@T6G_MB_LIB.T6G(SCH_1):PAGE325_I17@PURE_QUANTA.MP5991GLUZ(CHIPS)':
 'VIN4': CDS_PINID='VIN4';
NODE_NAME     PU297 13
 '@T6G_MB_LIB.T6G(SCH_1):PAGE325_I17@PURE_QUANTA.MP5991GLUZ(CHIPS)':
 'VIN5': CDS_PINID='VIN5';
NODE_NAME     PU297 14
 '@T6G_MB_LIB.T6G(SCH_1):PAGE325_I17@PURE_QUANTA.MP5991GLUZ(CHIPS)':
 'VIN6': CDS_PINID='VIN6';
NODE_NAME     PU297 15
 '@T6G_MB_LIB.T6G(SCH_1):PAGE325_I17@PURE_QUANTA.MP5991GLUZ(CHIPS)':
 'VIN7': CDS_PINID='VIN7';
NODE_NAME     PU297 16
 '@T6G_MB_LIB.T6G(SCH_1):PAGE325_I17@PURE_QUANTA.MP5991GLUZ(CHIPS)':
 'VIN8': CDS_PINID='VIN8';
NODE_NAME     PU297 33
 '@T6G_MB_LIB.T6G(SCH_1):PAGE325_I17@PURE_QUANTA.MP5991GLUZ(CHIPS)':
 'VIN9': CDS_PINID='VIN9';
NODE_NAME     PU296 9
 '@T6G_MB_LIB.T6G(SCH_1):PAGE325_I35@PURE_QUANTA.MP5991GLUZ(CHIPS)':
 'VIN1': CDS_PINID='VIN1';
NODE_NAME     PU296 10
 '@T6G_MB_LIB.T6G(SCH_1):PAGE325_I35@PURE_QUANTA.MP5991GLUZ(CHIPS)':
 'VIN2': CDS_PINID='VIN2';
NODE_NAME     PU296 11
 '@T6G_MB_LIB.T6G(SCH_1):PAGE325_I35@PURE_QUANTA.MP5991GLUZ(CHIPS)':
 'VIN3': CDS_PINID='VIN3';
NODE_NAME     PU296 12
 '@T6G_MB_LIB.T6G(SCH_1):PAGE325_I35@PURE_QUANTA.MP5991GLUZ(CHIPS)':
 'VIN4': CDS_PINID='VIN4';
NODE_NAME     PU296 13
 '@T6G_MB_LIB.T6G(SCH_1):PAGE325_I35@PURE_QUANTA.MP5991GLUZ(CHIPS)':
 'VIN5': CDS_PINID='VIN5';
NODE_NAME     PU296 14
 '@T6G_MB_LIB.T6G(SCH_1):PAGE325_I35@PURE_QUANTA.MP5991GLUZ(CHIPS)':
 'VIN6': CDS_PINID='VIN6';
NODE_NAME     PU296 15
 '@T6G_MB_LIB.T6G(SCH_1):PAGE325_I35@PURE_QUANTA.MP5991GLUZ(CHIPS)':
 'VIN7': CDS_PINID='VIN7';
NODE_NAME     PU296 16
 '@T6G_MB_LIB.T6G(SCH_1):PAGE325_I35@PURE_QUANTA.MP5991GLUZ(CHIPS)':
 'VIN8': CDS_PINID='VIN8';
NODE_NAME     PU296 33
 '@T6G_MB_LIB.T6G(SCH_1):PAGE325_I35@PURE_QUANTA.MP5991GLUZ(CHIPS)':
 'VIN9': CDS_PINID='VIN9';
NODE_NAME     PC2188 1
 '@T6G_MB_LIB.T6G(SCH_1):PAGE267_I46@PURE_QUANTA.Q_CAP(CHIPS)':
 'A': CDS_PINID='A';
NODE_NAME     PR3926 1
 '@T6G_MB_LIB.T6G(SCH_1):PAGE267_I48@PURE_QUANTA.Q_RES(CHIPS)':
 'A': CDS_PINID='A';
NODE_NAME     PU289 1
 '@T6G_MB_LIB.T6G(SCH_1):PAGE267_I58@PURE_QUANTA.MP5990GMA1111Z(CHIPS)':
 'VIN1': CDS_PINID='VIN1';
NODE_NAME     PU289 2
 '@T6G_MB_LIB.T6G(SCH_1):PAGE267_I58@PURE_QUANTA.MP5990GMA1111Z(CHIPS)':
 'VIN2': CDS_PINID='VIN2';
NODE_NAME     PU289 3
 '@T6G_MB_LIB.T6G(SCH_1):PAGE267_I58@PURE_QUANTA.MP5990GMA1111Z(CHIPS)':
 'VIN3': CDS_PINID='VIN3';
NODE_NAME     PU289 4
 '@T6G_MB_LIB.T6G(SCH_1):PAGE267_I58@PURE_QUANTA.MP5990GMA1111Z(CHIPS)':
 'VIN4': CDS_PINID='VIN4';
NODE_NAME     PU289 5
 '@T6G_MB_LIB.T6G(SCH_1):PAGE267_I58@PURE_QUANTA.MP5990GMA1111Z(CHIPS)':
 'VIN5': CDS_PINID='VIN5';
NODE_NAME     PU289 6
 '@T6G_MB_LIB.T6G(SCH_1):PAGE267_I58@PURE_QUANTA.MP5990GMA1111Z(CHIPS)':
 'VIN6': CDS_PINID='VIN6';
NODE_NAME     PU289 7
 '@T6G_MB_LIB.T6G(SCH_1):PAGE267_I58@PURE_QUANTA.MP5990GMA1111Z(CHIPS)':
 'VIN7': CDS_PINID='VIN7';
NODE_NAME     PU289 8
 '@T6G_MB_LIB.T6G(SCH_1):PAGE267_I58@PURE_QUANTA.MP5990GMA1111Z(CHIPS)':
 'VIN8': CDS_PINID='VIN8';
NODE_NAME     PU289 42
 '@T6G_MB_LIB.T6G(SCH_1):PAGE267_I58@PURE_QUANTA.MP5990GMA1111Z(CHIPS)':
 'VIN9': CDS_PINID='VIN9';
NODE_NAME     PU289 43
 '@T6G_MB_LIB.T6G(SCH_1):PAGE267_I58@PURE_QUANTA.MP5990GMA1111Z(CHIPS)':
 'VIN10': CDS_PINID='VIN10';
NODE_NAME     FS1 1
 '@T6G_MB_LIB.T6G(SCH_1):PAGE372_I6@PURE_QUANTA.Q_FUSE(CHIPS)':
 '1': CDS_PINID='\1\';
NODE_NAME     PR2534 1A
 '@T6G_MB_LIB.T6G(SCH_1):PAGE302_I52@PURE_QUANTA.Q_SP_RES4P(CHIPS)':
 '1A': CDS_PINID='\1a\';
NODE_NAME     PR2533 1A
 '@T6G_MB_LIB.T6G(SCH_1):PAGE302_I53@PURE_QUANTA.Q_SP_RES4P(CHIPS)':
 '1A': CDS_PINID='\1a\';
NODE_NAME     PR2532 1A
 '@T6G_MB_LIB.T6G(SCH_1):PAGE302_I54@PURE_QUANTA.Q_SP_RES4P(CHIPS)':
 '1A': CDS_PINID='\1a\';
NODE_NAME     PR6001 1A
 '@T6G_MB_LIB.T6G(SCH_1):PAGE302_I55@PURE_QUANTA.Q_SP_RES4P(CHIPS)':
 '1A': CDS_PINID='\1a\';
NODE_NAME     PJ38 1
 '@T6G_MB_LIB.T6G(SCH_1):PAGE371_I42@PURE_QUANTA.SCONN21_9193031121LF(CHIPS)':
 '1': CDS_PINID='\1\';
NODE_NAME     PR6002 1A
 '@T6G_MB_LIB.T6G(SCH_1):PAGE302_I81@PURE_QUANTA.Q_SP_RES4P(CHIPS)':
 '1A': CDS_PINID='\1a\';
NODE_NAME     J45 P4_1
 '@T6G_MB_LIB.T6G(SCH_1):PAGE363_I466@PURE_QUANTA.CONN60_101062636003K02LF(CHIPS)':
 'P4_1': CDS_PINID='P4_1';
NODE_NAME     J45 P4_2
 '@T6G_MB_LIB.T6G(SCH_1):PAGE363_I466@PURE_QUANTA.CONN60_101062636003K02LF(CHIPS)':
 'P4_2': CDS_PINID='P4_2';
NODE_NAME     J45 P4_3
 '@T6G_MB_LIB.T6G(SCH_1):PAGE363_I466@PURE_QUANTA.CONN60_101062636003K02LF(CHIPS)':
 'P4_3': CDS_PINID='P4_3';
NODE_NAME     J45 P4_4
 '@T6G_MB_LIB.T6G(SCH_1):PAGE363_I466@PURE_QUANTA.CONN60_101062636003K02LF(CHIPS)':
 'P4_4': CDS_PINID='P4_4';
NODE_NAME     J45 P4_5
 '@T6G_MB_LIB.T6G(SCH_1):PAGE363_I466@PURE_QUANTA.CONN60_101062636003K02LF(CHIPS)':
 'P4_5': CDS_PINID='P4_5';
NODE_NAME     J45 P4_6
 '@T6G_MB_LIB.T6G(SCH_1):PAGE363_I466@PURE_QUANTA.CONN60_101062636003K02LF(CHIPS)':
 'P4_6': CDS_PINID='P4_6';
NODE_NAME     J45 P4_7
 '@T6G_MB_LIB.T6G(SCH_1):PAGE363_I466@PURE_QUANTA.CONN60_101062636003K02LF(CHIPS)':
 'P4_7': CDS_PINID='P4_7';
NODE_NAME     J45 P4_8
 '@T6G_MB_LIB.T6G(SCH_1):PAGE363_I466@PURE_QUANTA.CONN60_101062636003K02LF(CHIPS)':
 'P4_8': CDS_PINID='P4_8';
NODE_NAME     J45 P5_1
 '@T6G_MB_LIB.T6G(SCH_1):PAGE363_I466@PURE_QUANTA.CONN60_101062636003K02LF(CHIPS)':
 'P5_1': CDS_PINID='P5_1';
NODE_NAME     J45 P5_2
 '@T6G_MB_LIB.T6G(SCH_1):PAGE363_I466@PURE_QUANTA.CONN60_101062636003K02LF(CHIPS)':
 'P5_2': CDS_PINID='P5_2';
NODE_NAME     J45 P5_3
 '@T6G_MB_LIB.T6G(SCH_1):PAGE363_I466@PURE_QUANTA.CONN60_101062636003K02LF(CHIPS)':
 'P5_3': CDS_PINID='P5_3';
NODE_NAME     J45 P5_4
 '@T6G_MB_LIB.T6G(SCH_1):PAGE363_I466@PURE_QUANTA.CONN60_101062636003K02LF(CHIPS)':
 'P5_4': CDS_PINID='P5_4';
NODE_NAME     J45 P5_5
 '@T6G_MB_LIB.T6G(SCH_1):PAGE363_I466@PURE_QUANTA.CONN60_101062636003K02LF(CHIPS)':
 'P5_5': CDS_PINID='P5_5';
NODE_NAME     J45 P5_6
 '@T6G_MB_LIB.T6G(SCH_1):PAGE363_I466@PURE_QUANTA.CONN60_101062636003K02LF(CHIPS)':
 'P5_6': CDS_PINID='P5_6';
NODE_NAME     J45 P5_7
 '@T6G_MB_LIB.T6G(SCH_1):PAGE363_I466@PURE_QUANTA.CONN60_101062636003K02LF(CHIPS)':
 'P5_7': CDS_PINID='P5_7';
NODE_NAME     J45 P5_8
 '@T6G_MB_LIB.T6G(SCH_1):PAGE363_I466@PURE_QUANTA.CONN60_101062636003K02LF(CHIPS)':
 'P5_8': CDS_PINID='P5_8';
NODE_NAME     J45 P6_1
 '@T6G_MB_LIB.T6G(SCH_1):PAGE363_I466@PURE_QUANTA.CONN60_101062636003K02LF(CHIPS)':
 'P6_1': CDS_PINID='P6_1';
NODE_NAME     J45 P6_2
 '@T6G_MB_LIB.T6G(SCH_1):PAGE363_I466@PURE_QUANTA.CONN60_101062636003K02LF(CHIPS)':
 'P6_2': CDS_PINID='P6_2';
NODE_NAME     J45 P6_3
 '@T6G_MB_LIB.T6G(SCH_1):PAGE363_I466@PURE_QUANTA.CONN60_101062636003K02LF(CHIPS)':
 'P6_3': CDS_PINID='P6_3';
NODE_NAME     J45 P6_4
 '@T6G_MB_LIB.T6G(SCH_1):PAGE363_I466@PURE_QUANTA.CONN60_101062636003K02LF(CHIPS)':
 'P6_4': CDS_PINID='P6_4';
NODE_NAME     J45 P6_5
 '@T6G_MB_LIB.T6G(SCH_1):PAGE363_I466@PURE_QUANTA.CONN60_101062636003K02LF(CHIPS)':
 'P6_5': CDS_PINID='P6_5';
NODE_NAME     J45 P6_6
 '@T6G_MB_LIB.T6G(SCH_1):PAGE363_I466@PURE_QUANTA.CONN60_101062636003K02LF(CHIPS)':
 'P6_6': CDS_PINID='P6_6';
NODE_NAME     J45 P6_7
 '@T6G_MB_LIB.T6G(SCH_1):PAGE363_I466@PURE_QUANTA.CONN60_101062636003K02LF(CHIPS)':
 'P6_7': CDS_PINID='P6_7';
NODE_NAME     J45 P6_8
 '@T6G_MB_LIB.T6G(SCH_1):PAGE363_I466@PURE_QUANTA.CONN60_101062636003K02LF(CHIPS)':
 'P6_8': CDS_PINID='P6_8';
NODE_NAME     R8027 2
 '@T6G_MB_LIB.T6G(SCH_1):PAGE375_I49@PURE_QUANTA.Q_RES(CHIPS)':
 'B': CDS_PINID='B';
NET_NAME
'P12V_PSU_FUSE'
 '@T6G_MB_LIB.T6G(SCH_1):P12V_PSU_FUSE':
 C_SIGNAL='@t6g_mb_lib.t6g(sch_1):p12v_psu_fuse';
NODE_NAME     PD15 C
 '@T6G_MB_LIB.T6G(SCH_1):PAGE372_I1@PURE_QUANTA.ZENER_AC(CHIPS)':
 'C': CDS_PINID='C';
NODE_NAME     PD13 C
 '@T6G_MB_LIB.T6G(SCH_1):PAGE372_I3@PURE_QUANTA.ZENER_AC(CHIPS)':
 'C': CDS_PINID='C';
NODE_NAME     FS1 2
 '@T6G_MB_LIB.T6G(SCH_1):PAGE372_I6@PURE_QUANTA.Q_FUSE(CHIPS)':
 '2': CDS_PINID='\2\';
NODE_NAME     R3923 1
 '@T6G_MB_LIB.T6G(SCH_1):PAGE372_I16@PURE_QUANTA.Q_RES(CHIPS)':
 'A': CDS_PINID='A';
NODE_NAME     R4901 1
 '@T6G_MB_LIB.T6G(SCH_1):PAGE372_I19@PURE_QUANTA.Q_RES(CHIPS)':
 'A': CDS_PINID='A';
NET_NAME
'P12V_SCM'
 '@T6G_MB_LIB.T6G(SCH_1):P12V_SCM':
 C_SIGNAL='@t6g_mb_lib.t6g(sch_1):p12v_scm',
 CDS_GLOBAL_NET='TRUE';
NODE_NAME     R3579 1
 '@T6G_MB_LIB.T6G(SCH_1):PAGE360_I56@PURE_QUANTA.Q_RES(CHIPS)':
 'A': CDS_PINID='A';
NODE_NAME     R3635 1
 '@T6G_MB_LIB.T6G(SCH_1):PAGE360_I93@PURE_QUANTA.Q_RES(CHIPS)':
 'A': CDS_PINID='A';
NODE_NAME     J41 OB2
 '@T6G_MB_LIB.T6G(SCH_1):PAGE348_I176@PURE_QUANTA.SCONN168_ME1016810202011(CHIPS)':
 'MAIN_PWR_EN': CDS_PINID='MAIN_PWR_EN';
NODE_NAME     J41 OB1
 '@T6G_MB_LIB.T6G(SCH_1):PAGE348_I176@PURE_QUANTA.SCONN168_ME1016810202011(CHIPS)':
 'NIC_PWR_GOOD': CDS_PINID='NIC_PWR_GOOD';
NODE_NAME     J41 OA1
 '@T6G_MB_LIB.T6G(SCH_1):PAGE348_I176@PURE_QUANTA.SCONN168_ME1016810202011(CHIPS)':
 'PERST2#': CDS_PINID='\perst2#\';
NODE_NAME     J41 OA2
 '@T6G_MB_LIB.T6G(SCH_1):PAGE348_I176@PURE_QUANTA.SCONN168_ME1016810202011(CHIPS)':
 'PERST3#': CDS_PINID='\perst3#\';
NET_NAME
'P12V_SCM_ADC_ALERT'
 '@T6G_MB_LIB.T6G(SCH_1):P12V_SCM_ADC_ALERT':
 C_SIGNAL='@t6g_mb_lib.t6g(sch_1):p12v_scm_adc_alert';
NODE_NAME     R3561 2
 '@T6G_MB_LIB.T6G(SCH_1):PAGE360_I64@PURE_QUANTA.Q_RES(CHIPS)':
 'B': CDS_PINID='B';
NODE_NAME     U18 K5
 '@T6G_MB_LIB.T6G(SCH_1):PAGE81_I143@PURE_QUANTA.LCMXO3LF9400C5BG484C(CHIPS)':
 'PL13B': CDS_PINID='PL13B';
NET_NAME
'P12V_SCM_ADC_ALERT_R'
 '@T6G_MB_LIB.T6G(SCH_1):P12V_SCM_ADC_ALERT_R':
 C_SIGNAL='@t6g_mb_lib.t6g(sch_1):p12v_scm_adc_alert_r';
NODE_NAME     R3561 1
 '@T6G_MB_LIB.T6G(SCH_1):PAGE360_I64@PURE_QUANTA.Q_RES(CHIPS)':
 'A': CDS_PINID='A';
NODE_NAME     U265 3
 '@T6G_MB_LIB.T6G(SCH_1):PAGE360_I69@PURE_QUANTA.ISL28022FRZT(CHIPS)':
 'EXT_CLK||INT': CDS_PINID='\ext_clk||int\';
NODE_NAME     R4091 2
 '@T6G_MB_LIB.T6G(SCH_1):PAGE360_I122@PURE_QUANTA.Q_RES(CHIPS)':
 'B': CDS_PINID='B';
NET_NAME
'P12V_SCM_AVIN_PD'
 '@T6G_MB_LIB.T6G(SCH_1):P12V_SCM_AVIN_PD':
 C_SIGNAL='@t6g_mb_lib.t6g(sch_1):p12v_scm_avin_pd';
NODE_NAME     PC2239 1
 '@T6G_MB_LIB.T6G(SCH_1):PAGE350_I52@PURE_QUANTA.Q_CAP(CHIPS)':
 'A': CDS_PINID='A';
NODE_NAME     PR4006 2
 '@T6G_MB_LIB.T6G(SCH_1):PAGE350_I41@PURE_QUANTA.Q_RES(CHIPS)':
 'B': CDS_PINID='B';
NODE_NAME     PR4014 2
 '@T6G_MB_LIB.T6G(SCH_1):PAGE350_I53@PURE_QUANTA.Q_RES(CHIPS)':
 'B': CDS_PINID='B';
NODE_NAME     PU299 12
 '@T6G_MB_LIB.T6G(SCH_1):PAGE350_I95@PURE_QUANTA.RS31312R(CHIPS)':
 'AVIN': CDS_PINID='AVIN';
NET_NAME
'P12V_SCM_CB'
 '@T6G_MB_LIB.T6G(SCH_1):P12V_SCM_CB':
 C_SIGNAL='@t6g_mb_lib.t6g(sch_1):p12v_scm_cb';
NODE_NAME     PR4004 1
 '@T6G_MB_LIB.T6G(SCH_1):PAGE350_I62@PURE_QUANTA.Q_RES(CHIPS)':
 'A': CDS_PINID='A';
NODE_NAME     PU300 B1
 '@T6G_MB_LIB.T6G(SCH_1):PAGE350_I86@PURE_QUANTA.MAX15090BEWIT(CHIPS)':
 'CB': CDS_PINID='CB';
NET_NAME
'P12V_SCM_EN'
 '@T6G_MB_LIB.T6G(SCH_1):P12V_SCM_EN':
 C_SIGNAL='@t6g_mb_lib.t6g(sch_1):p12v_scm_en';
NODE_NAME     R3998 1
 '@T6G_MB_LIB.T6G(SCH_1):PAGE350_I14@PURE_QUANTA.Q_RES(CHIPS)':
 'A': CDS_PINID='A';
NODE_NAME     R3996 2
 '@T6G_MB_LIB.T6G(SCH_1):PAGE350_I17@PURE_QUANTA.Q_RES(CHIPS)':
 'B': CDS_PINID='B';
NODE_NAME     R1857 2
 '@T6G_MB_LIB.T6G(SCH_1):PAGE350_I18@PURE_QUANTA.Q_RES(CHIPS)':
 'B': CDS_PINID='B';
NODE_NAME     R4062 1
 '@T6G_MB_LIB.T6G(SCH_1):PAGE350_I20@PURE_QUANTA.Q_RES(CHIPS)':
 'A': CDS_PINID='A';
NODE_NAME     Q39 D
 '@T6G_MB_LIB.T6G(SCH_1):PAGE350_I9@PURE_QUANTA.MOSFET_NCH_GDS_ESD_PROTECTED(CHIPS)':
 'D': CDS_PINID='D';
NET_NAME
'P12V_SCM_EN_G'
 '@T6G_MB_LIB.T6G(SCH_1):P12V_SCM_EN_G':
 C_SIGNAL='@t6g_mb_lib.t6g(sch_1):p12v_scm_en_g';
NODE_NAME     R4071 2
 '@T6G_MB_LIB.T6G(SCH_1):PAGE350_I25@PURE_QUANTA.Q_RES(CHIPS)':
 'B': CDS_PINID='B';
NODE_NAME     Q125 6
 '@T6G_MB_LIB.T6G(SCH_1):PAGE350_I22@PURE_QUANTA.MOSFET_NCH_DUAL(CHIPS)':
 'D1': CDS_PINID='D1';
NODE_NAME     Q125 5
 '@T6G_MB_LIB.T6G(SCH_1):PAGE350_I24@PURE_QUANTA.MOSFET_NCH_DUAL(CHIPS)':
 'G2': CDS_PINID='G2';
NET_NAME
'P12V_SCM_EN_R'
 '@T6G_MB_LIB.T6G(SCH_1):P12V_SCM_EN_R':
 C_SIGNAL='@t6g_mb_lib.t6g(sch_1):p12v_scm_en_r';
NODE_NAME     R4062 2
 '@T6G_MB_LIB.T6G(SCH_1):PAGE350_I20@PURE_QUANTA.Q_RES(CHIPS)':
 'B': CDS_PINID='B';
NODE_NAME     Q125 2
 '@T6G_MB_LIB.T6G(SCH_1):PAGE350_I22@PURE_QUANTA.MOSFET_NCH_DUAL(CHIPS)':
 'G1': CDS_PINID='G1';
NET_NAME
'P12V_SCM_EN_R2'
 '@T6G_MB_LIB.T6G(SCH_1):P12V_SCM_EN_R2':
 C_SIGNAL='@t6g_mb_lib.t6g(sch_1):p12v_scm_en_r2';
NODE_NAME     R3998 2
 '@T6G_MB_LIB.T6G(SCH_1):PAGE350_I14@PURE_QUANTA.Q_RES(CHIPS)':
 'B': CDS_PINID='B';
NODE_NAME     PU299 1
 '@T6G_MB_LIB.T6G(SCH_1):PAGE350_I95@PURE_QUANTA.RS31312R(CHIPS)':
 'EN': CDS_PINID='EN';
NET_NAME
'P12V_SCM_FAULT_N'
 '@T6G_MB_LIB.T6G(SCH_1):P12V_SCM_FAULT_N':
 C_SIGNAL='@t6g_mb_lib.t6g(sch_1):p12v_scm_fault_n';
NODE_NAME     PU300 C7
 '@T6G_MB_LIB.T6G(SCH_1):PAGE350_I86@PURE_QUANTA.MAX15090BEWIT(CHIPS)':
 'FAULT#': CDS_PINID='\fault#\';
NODE_NAME     R8030 1
 '@T6G_MB_LIB.T6G(SCH_1):PAGE350_I91@PURE_QUANTA.Q_RES(CHIPS)':
 'A': CDS_PINID='A';
NET_NAME
'P12V_SCM_FAULT_R_N'
 '@T6G_MB_LIB.T6G(SCH_1):P12V_SCM_FAULT_R_N':
 C_SIGNAL='@t6g_mb_lib.t6g(sch_1):p12v_scm_fault_r_n';
NODE_NAME     R4013 2
 '@T6G_MB_LIB.T6G(SCH_1):PAGE350_I76@PURE_QUANTA.Q_RES(CHIPS)':
 'B': CDS_PINID='B';
NODE_NAME     Q8001 2
 '@T6G_MB_LIB.T6G(SCH_1):PAGE375_I57@PURE_QUANTA.MOSFET_NCH_DUAL(CHIPS)':
 'G1': CDS_PINID='G1';
NODE_NAME     R8030 2
 '@T6G_MB_LIB.T6G(SCH_1):PAGE350_I91@PURE_QUANTA.Q_RES(CHIPS)':
 'B': CDS_PINID='B';
NODE_NAME     R8031 2
 '@T6G_MB_LIB.T6G(SCH_1):PAGE350_I93@PURE_QUANTA.Q_RES(CHIPS)':
 'B': CDS_PINID='B';
NET_NAME
'P12V_SCM_FLTB_N'
 '@T6G_MB_LIB.T6G(SCH_1):P12V_SCM_FLTB_N':
 C_SIGNAL='@t6g_mb_lib.t6g(sch_1):p12v_scm_fltb_n';
NODE_NAME     PR4007 1
 '@T6G_MB_LIB.T6G(SCH_1):PAGE350_I40@PURE_QUANTA.Q_RES(CHIPS)':
 'A': CDS_PINID='A';
NODE_NAME     R8031 1
 '@T6G_MB_LIB.T6G(SCH_1):PAGE350_I93@PURE_QUANTA.Q_RES(CHIPS)':
 'A': CDS_PINID='A';
NODE_NAME     PU299 9
 '@T6G_MB_LIB.T6G(SCH_1):PAGE350_I95@PURE_QUANTA.RS31312R(CHIPS)':
 'FLTB': CDS_PINID='FLTB';
NET_NAME
'P12V_SCM_GATE'
 '@T6G_MB_LIB.T6G(SCH_1):P12V_SCM_GATE':
 C_SIGNAL='@t6g_mb_lib.t6g(sch_1):p12v_scm_gate';
NODE_NAME     PC2236 2
 '@T6G_MB_LIB.T6G(SCH_1):PAGE350_I71@PURE_QUANTA.Q_CAP(CHIPS)':
 'B': CDS_PINID='B';
NODE_NAME     PC2237 1
 '@T6G_MB_LIB.T6G(SCH_1):PAGE350_I72@PURE_QUANTA.Q_CAP(CHIPS)':
 'A': CDS_PINID='A';
NODE_NAME     PU300 A6
 '@T6G_MB_LIB.T6G(SCH_1):PAGE350_I86@PURE_QUANTA.MAX15090BEWIT(CHIPS)':
 'GATE': CDS_PINID='GATE';
NODE_NAME     PR4526 2
 '@T6G_MB_LIB.T6G(SCH_1):PAGE350_I74@PURE_QUANTA.Q_RES(CHIPS)':
 'B': CDS_PINID='B';
NET_NAME
'P12V_SCM_IMON'
 '@T6G_MB_LIB.T6G(SCH_1):P12V_SCM_IMON':
 C_SIGNAL='@t6g_mb_lib.t6g(sch_1):p12v_scm_imon';
NODE_NAME     PC2235 1
 '@T6G_MB_LIB.T6G(SCH_1):PAGE350_I45@PURE_QUANTA.Q_CAP(CHIPS)':
 'A': CDS_PINID='A';
NODE_NAME     PR4005 1
 '@T6G_MB_LIB.T6G(SCH_1):PAGE350_I35@PURE_QUANTA.Q_RES(CHIPS)':
 'A': CDS_PINID='A';
NODE_NAME     PU299 8
 '@T6G_MB_LIB.T6G(SCH_1):PAGE350_I95@PURE_QUANTA.RS31312R(CHIPS)':
 'IMON': CDS_PINID='IMON';
NET_NAME
'P12V_SCM_ISET'
 '@T6G_MB_LIB.T6G(SCH_1):P12V_SCM_ISET':
 C_SIGNAL='@t6g_mb_lib.t6g(sch_1):p12v_scm_iset';
NODE_NAME     PR3999 1
 '@T6G_MB_LIB.T6G(SCH_1):PAGE350_I11@PURE_QUANTA.Q_RES(CHIPS)':
 'A': CDS_PINID='A';
NODE_NAME     PR4540 1
 '@T6G_MB_LIB.T6G(SCH_1):PAGE350_I12@PURE_QUANTA.Q_RES(CHIPS)':
 'A': CDS_PINID='A';
NODE_NAME     PU299 5
 '@T6G_MB_LIB.T6G(SCH_1):PAGE350_I95@PURE_QUANTA.RS31312R(CHIPS)':
 'ISET': CDS_PINID='ISET';
NET_NAME
'P12V_SCM_ISET_R'
 '@T6G_MB_LIB.T6G(SCH_1):P12V_SCM_ISET_R':
 C_SIGNAL='@t6g_mb_lib.t6g(sch_1):p12v_scm_iset_r';
NODE_NAME     PR4540 2
 '@T6G_MB_LIB.T6G(SCH_1):PAGE350_I12@PURE_QUANTA.Q_RES(CHIPS)':
 'B': CDS_PINID='B';
NODE_NAME     PC2340 1
 '@T6G_MB_LIB.T6G(SCH_1):PAGE350_I6@PURE_QUANTA.Q_CAP(CHIPS)':
 'A': CDS_PINID='A';
NET_NAME
'P12V_SCM_OV'
 '@T6G_MB_LIB.T6G(SCH_1):P12V_SCM_OV':
 C_SIGNAL='@t6g_mb_lib.t6g(sch_1):p12v_scm_ov';
NODE_NAME     PU300 D3
 '@T6G_MB_LIB.T6G(SCH_1):PAGE350_I86@PURE_QUANTA.MAX15090BEWIT(CHIPS)':
 'OV': CDS_PINID='OV';
NODE_NAME     PR4002 1
 '@T6G_MB_LIB.T6G(SCH_1):PAGE350_I60@PURE_QUANTA.Q_RES(CHIPS)':
 'A': CDS_PINID='A';
NODE_NAME     PR4001 2
 '@T6G_MB_LIB.T6G(SCH_1):PAGE350_I63@PURE_QUANTA.Q_RES(CHIPS)':
 'B': CDS_PINID='B';
NET_NAME
'P12V_SCM_OV_FB'
 '@T6G_MB_LIB.T6G(SCH_1):P12V_SCM_OV_FB':
 C_SIGNAL='@t6g_mb_lib.t6g(sch_1):p12v_scm_ov_fb';
NODE_NAME     PR4009 2
 '@T6G_MB_LIB.T6G(SCH_1):PAGE350_I50@PURE_QUANTA.Q_RES(CHIPS)':
 'B': CDS_PINID='B';
NODE_NAME     PR4010 2
 '@T6G_MB_LIB.T6G(SCH_1):PAGE350_I51@PURE_QUANTA.Q_RES(CHIPS)':
 'B': CDS_PINID='B';
NODE_NAME     PR4011 1
 '@T6G_MB_LIB.T6G(SCH_1):PAGE350_I49@PURE_QUANTA.Q_RES(CHIPS)':
 'A': CDS_PINID='A';
NODE_NAME     PU299 11
 '@T6G_MB_LIB.T6G(SCH_1):PAGE350_I95@PURE_QUANTA.RS31312R(CHIPS)':
 'OV': CDS_PINID='OV';
NET_NAME
'P12V_SCM_PWRGD'
 '@T6G_MB_LIB.T6G(SCH_1):P12V_SCM_PWRGD':
 C_SIGNAL='@t6g_mb_lib.t6g(sch_1):p12v_scm_pwrgd';
NODE_NAME     PR4012 1
 '@T6G_MB_LIB.T6G(SCH_1):PAGE350_I73@PURE_QUANTA.Q_RES(CHIPS)':
 'A': CDS_PINID='A';
NODE_NAME     PU300 D7
 '@T6G_MB_LIB.T6G(SCH_1):PAGE350_I86@PURE_QUANTA.MAX15090BEWIT(CHIPS)':
 'PG': CDS_PINID='PG';
NET_NAME
'P12V_SCM_PWRGD_R'
 '@T6G_MB_LIB.T6G(SCH_1):P12V_SCM_PWRGD_R':
 C_SIGNAL='@t6g_mb_lib.t6g(sch_1):p12v_scm_pwrgd_r';
NODE_NAME     R6055 2
 '@T6G_MB_LIB.T6G(SCH_1):PAGE80_I60@PURE_QUANTA.Q_RES(CHIPS)':
 'B': CDS_PINID='B';
NODE_NAME     U18 Y6
 '@T6G_MB_LIB.T6G(SCH_1):PAGE80_I216@PURE_QUANTA.LCMXO3LF9400C5BG484C(CHIPS)':
 'PB10D': CDS_PINID='PB10D';
NET_NAME
'P12V_SCM_R'
 '@T6G_MB_LIB.T6G(SCH_1):P12V_SCM_R':
 C_SIGNAL='@t6g_mb_lib.t6g(sch_1):p12v_scm_r',
 CDS_GLOBAL_NET='TRUE';
NODE_NAME     PR4009 1
 '@T6G_MB_LIB.T6G(SCH_1):PAGE350_I50@PURE_QUANTA.Q_RES(CHIPS)':
 'A': CDS_PINID='A';
NODE_NAME     PC2236 1
 '@T6G_MB_LIB.T6G(SCH_1):PAGE350_I71@PURE_QUANTA.Q_CAP(CHIPS)':
 'A': CDS_PINID='A';
NODE_NAME     PD116 C
 '@T6G_MB_LIB.T6G(SCH_1):PAGE350_I79@PURE_QUANTA.SCHOTTKY_AC(CHIPS)':
 'C': CDS_PINID='C';
NODE_NAME     PC2238 1
 '@T6G_MB_LIB.T6G(SCH_1):PAGE350_I80@PURE_QUANTA.Q_CAP(CHIPS)':
 'A': CDS_PINID='A';
NODE_NAME     C2019 1
 '@T6G_MB_LIB.T6G(SCH_1):PAGE360_I49@PURE_QUANTA.Q_CAP(CHIPS)':
 'A': CDS_PINID='A';
NODE_NAME     R3578 1
 '@T6G_MB_LIB.T6G(SCH_1):PAGE360_I58@PURE_QUANTA.Q_RES(CHIPS)':
 'A': CDS_PINID='A';
NODE_NAME     U265 11
 '@T6G_MB_LIB.T6G(SCH_1):PAGE360_I69@PURE_QUANTA.ISL28022FRZT(CHIPS)':
 'VBUS': CDS_PINID='VBUS';
NODE_NAME     R3635 2
 '@T6G_MB_LIB.T6G(SCH_1):PAGE360_I93@PURE_QUANTA.Q_RES(CHIPS)':
 'B': CDS_PINID='B';
NODE_NAME     PR4006 1
 '@T6G_MB_LIB.T6G(SCH_1):PAGE350_I41@PURE_QUANTA.Q_RES(CHIPS)':
 'A': CDS_PINID='A';
NODE_NAME     PU300 A4
 '@T6G_MB_LIB.T6G(SCH_1):PAGE350_I86@PURE_QUANTA.MAX15090BEWIT(CHIPS)':
 'OUT_A4': CDS_PINID='OUT_A4';
NODE_NAME     PU300 B4
 '@T6G_MB_LIB.T6G(SCH_1):PAGE350_I86@PURE_QUANTA.MAX15090BEWIT(CHIPS)':
 'OUT_B4': CDS_PINID='OUT_B4';
NODE_NAME     PU300 B6
 '@T6G_MB_LIB.T6G(SCH_1):PAGE350_I86@PURE_QUANTA.MAX15090BEWIT(CHIPS)':
 'OUT_B6': CDS_PINID='OUT_B6';
NODE_NAME     PU300 C4
 '@T6G_MB_LIB.T6G(SCH_1):PAGE350_I86@PURE_QUANTA.MAX15090BEWIT(CHIPS)':
 'OUT_C4': CDS_PINID='OUT_C4';
NODE_NAME     PU300 C6
 '@T6G_MB_LIB.T6G(SCH_1):PAGE350_I86@PURE_QUANTA.MAX15090BEWIT(CHIPS)':
 'OUT_C6': CDS_PINID='OUT_C6';
NODE_NAME     PU300 D4
 '@T6G_MB_LIB.T6G(SCH_1):PAGE350_I86@PURE_QUANTA.MAX15090BEWIT(CHIPS)':
 'OUT_D4': CDS_PINID='OUT_D4';
NODE_NAME     PU300 D6
 '@T6G_MB_LIB.T6G(SCH_1):PAGE350_I86@PURE_QUANTA.MAX15090BEWIT(CHIPS)':
 'OUT_D6': CDS_PINID='OUT_D6';
NODE_NAME     PC2241 1
 '@T6G_MB_LIB.T6G(SCH_1):PAGE350_I56@PURE_QUANTA.Q_CAP(CHIPS)':
 'A': CDS_PINID='A';
NODE_NAME     PR4526 1
 '@T6G_MB_LIB.T6G(SCH_1):PAGE350_I74@PURE_QUANTA.Q_RES(CHIPS)':
 'A': CDS_PINID='A';
NODE_NAME     PC2240 1
 '@T6G_MB_LIB.T6G(SCH_1):PAGE350_I81@PURE_QUANTA.Q_CAP(CHIPS)':
 'A': CDS_PINID='A';
NODE_NAME     PC2242 1
 '@T6G_MB_LIB.T6G(SCH_1):PAGE350_I84@PURE_QUANTA.Q_CAP(CHIPS)':
 'A': CDS_PINID='A';
NODE_NAME     PU299 13
 '@T6G_MB_LIB.T6G(SCH_1):PAGE350_I95@PURE_QUANTA.RS31312R(CHIPS)':
 'VOUT_13': CDS_PINID='VOUT_13';
NODE_NAME     PU299 14
 '@T6G_MB_LIB.T6G(SCH_1):PAGE350_I95@PURE_QUANTA.RS31312R(CHIPS)':
 'VOUT_14': CDS_PINID='VOUT_14';
NODE_NAME     PU299 15
 '@T6G_MB_LIB.T6G(SCH_1):PAGE350_I95@PURE_QUANTA.RS31312R(CHIPS)':
 'VOUT_15': CDS_PINID='VOUT_15';
NODE_NAME     PU299 16
 '@T6G_MB_LIB.T6G(SCH_1):PAGE350_I95@PURE_QUANTA.RS31312R(CHIPS)':
 'VOUT_16': CDS_PINID='VOUT_16';
NODE_NAME     PU299 17
 '@T6G_MB_LIB.T6G(SCH_1):PAGE350_I95@PURE_QUANTA.RS31312R(CHIPS)':
 'VOUT_17': CDS_PINID='VOUT_17';
NODE_NAME     PU299 18
 '@T6G_MB_LIB.T6G(SCH_1):PAGE350_I95@PURE_QUANTA.RS31312R(CHIPS)':
 'VOUT_18': CDS_PINID='VOUT_18';
NODE_NAME     PU299 19
 '@T6G_MB_LIB.T6G(SCH_1):PAGE350_I95@PURE_QUANTA.RS31312R(CHIPS)':
 'VOUT_19': CDS_PINID='VOUT_19';
NODE_NAME     PU299 20
 '@T6G_MB_LIB.T6G(SCH_1):PAGE350_I95@PURE_QUANTA.RS31312R(CHIPS)':
 'VOUT_20': CDS_PINID='VOUT_20';
NET_NAME
'P12V_SCM_REG'
 '@T6G_MB_LIB.T6G(SCH_1):P12V_SCM_REG':
 C_SIGNAL='@t6g_mb_lib.t6g(sch_1):p12v_scm_reg';
NODE_NAME     PC2234 2
 '@T6G_MB_LIB.T6G(SCH_1):PAGE350_I67@PURE_QUANTA.Q_CAP(CHIPS)':
 'B': CDS_PINID='B';
NODE_NAME     PU300 D1
 '@T6G_MB_LIB.T6G(SCH_1):PAGE350_I86@PURE_QUANTA.MAX15090BEWIT(CHIPS)':
 'REG': CDS_PINID='REG';
NET_NAME
'P12V_SCM_SENSE'
 '@T6G_MB_LIB.T6G(SCH_1):P12V_SCM_SENSE':
 C_SIGNAL='@t6g_mb_lib.t6g(sch_1):p12v_scm_sense';
NODE_NAME     PR4008 1
 '@T6G_MB_LIB.T6G(SCH_1):PAGE350_I70@PURE_QUANTA.Q_RES(CHIPS)':
 'A': CDS_PINID='A';
NODE_NAME     PU300 A1
 '@T6G_MB_LIB.T6G(SCH_1):PAGE350_I86@PURE_QUANTA.MAX15090BEWIT(CHIPS)':
 'ISENSE': CDS_PINID='ISENSE';
NET_NAME
'P12V_SCM_SS'
 '@T6G_MB_LIB.T6G(SCH_1):P12V_SCM_SS':
 C_SIGNAL='@t6g_mb_lib.t6g(sch_1):p12v_scm_ss';
NODE_NAME     PC2232 1
 '@T6G_MB_LIB.T6G(SCH_1):PAGE350_I33@PURE_QUANTA.Q_CAP(CHIPS)':
 'A': CDS_PINID='A';
NODE_NAME     PU299 6
 '@T6G_MB_LIB.T6G(SCH_1):PAGE350_I95@PURE_QUANTA.RS31312R(CHIPS)':
 'SS': CDS_PINID='SS';
NET_NAME
'P12V_SCM_TIMER'
 '@T6G_MB_LIB.T6G(SCH_1):P12V_SCM_TIMER':
 C_SIGNAL='@t6g_mb_lib.t6g(sch_1):p12v_scm_timer';
NODE_NAME     PC2229 1
 '@T6G_MB_LIB.T6G(SCH_1):PAGE350_I8@PURE_QUANTA.Q_CAP(CHIPS)':
 'A': CDS_PINID='A';
NODE_NAME     PU299 4
 '@T6G_MB_LIB.T6G(SCH_1):PAGE350_I95@PURE_QUANTA.RS31312R(CHIPS)':
 'TIMER': CDS_PINID='TIMER';
NET_NAME
'P12V_SCM_UV'
 '@T6G_MB_LIB.T6G(SCH_1):P12V_SCM_UV':
 C_SIGNAL='@t6g_mb_lib.t6g(sch_1):p12v_scm_uv';
NODE_NAME     R3997 2
 '@T6G_MB_LIB.T6G(SCH_1):PAGE350_I27@PURE_QUANTA.Q_RES(CHIPS)':
 'B': CDS_PINID='B';
NODE_NAME     PR4000 2
 '@T6G_MB_LIB.T6G(SCH_1):PAGE350_I65@PURE_QUANTA.Q_RES(CHIPS)':
 'B': CDS_PINID='B';
NODE_NAME     PU300 D2
 '@T6G_MB_LIB.T6G(SCH_1):PAGE350_I86@PURE_QUANTA.MAX15090BEWIT(CHIPS)':
 'UV': CDS_PINID='UV';
NODE_NAME     PR4001 1
 '@T6G_MB_LIB.T6G(SCH_1):PAGE350_I63@PURE_QUANTA.Q_RES(CHIPS)':
 'A': CDS_PINID='A';
NET_NAME
'P12V_SCM_UV_R'
 '@T6G_MB_LIB.T6G(SCH_1):P12V_SCM_UV_R':
 C_SIGNAL='@t6g_mb_lib.t6g(sch_1):p12v_scm_uv_r';
NODE_NAME     R3997 1
 '@T6G_MB_LIB.T6G(SCH_1):PAGE350_I27@PURE_QUANTA.Q_RES(CHIPS)':
 'A': CDS_PINID='A';
NODE_NAME     Q125 3
 '@T6G_MB_LIB.T6G(SCH_1):PAGE350_I24@PURE_QUANTA.MOSFET_NCH_DUAL(CHIPS)':
 'D2': CDS_PINID='D2';
NET_NAME
'P12V_SCM_VCC'
 '@T6G_MB_LIB.T6G(SCH_1):P12V_SCM_VCC':
 C_SIGNAL='@t6g_mb_lib.t6g(sch_1):p12v_scm_vcc';
NODE_NAME     PC2233 1
 '@T6G_MB_LIB.T6G(SCH_1):PAGE350_I66@PURE_QUANTA.Q_CAP(CHIPS)':
 'A': CDS_PINID='A';
NODE_NAME     PU300 A2
 '@T6G_MB_LIB.T6G(SCH_1):PAGE350_I86@PURE_QUANTA.MAX15090BEWIT(CHIPS)':
 'VCC': CDS_PINID='VCC';
NODE_NAME     PR4003 2
 '@T6G_MB_LIB.T6G(SCH_1):PAGE350_I68@PURE_QUANTA.Q_RES(CHIPS)':
 'B': CDS_PINID='B';
NET_NAME
'P1V2_AUX'
 '@T6G_MB_LIB.T6G(SCH_1):P1V2_AUX':
 C_SIGNAL='@t6g_mb_lib.t6g(sch_1):p1v2_aux',
 CDS_GLOBAL_NET='TRUE';
NODE_NAME     U6001 10
 '@T6G_MB_LIB.T6G(SCH_1):PAGE154_I1@PURE_QUANTA.CYUSB330468LTXI(CHIPS)':
 'AVDD12_1': CDS_PINID='AVDD12_1';
NODE_NAME     U6001 16
 '@T6G_MB_LIB.T6G(SCH_1):PAGE154_I1@PURE_QUANTA.CYUSB330468LTXI(CHIPS)':
 'AVDD12_2': CDS_PINID='AVDD12_2';
NODE_NAME     U6001 34
 '@T6G_MB_LIB.T6G(SCH_1):PAGE154_I1@PURE_QUANTA.CYUSB330468LTXI(CHIPS)':
 'AVDD12_3': CDS_PINID='AVDD12_3';
NODE_NAME     U6001 46
 '@T6G_MB_LIB.T6G(SCH_1):PAGE154_I1@PURE_QUANTA.CYUSB330468LTXI(CHIPS)':
 'AVDD12_4': CDS_PINID='AVDD12_4';
NODE_NAME     U6001 52
 '@T6G_MB_LIB.T6G(SCH_1):PAGE154_I1@PURE_QUANTA.CYUSB330468LTXI(CHIPS)':
 'AVDD12_5': CDS_PINID='AVDD12_5';
NODE_NAME     U6001 53
 '@T6G_MB_LIB.T6G(SCH_1):PAGE154_I1@PURE_QUANTA.CYUSB330468LTXI(CHIPS)':
 'AVDD12_6': CDS_PINID='AVDD12_6';
NODE_NAME     U6001 49
 '@T6G_MB_LIB.T6G(SCH_1):PAGE154_I1@PURE_QUANTA.CYUSB330468LTXI(CHIPS)':
 'DVDD12_4': CDS_PINID='DVDD12_4';
NODE_NAME     U6001 7
 '@T6G_MB_LIB.T6G(SCH_1):PAGE154_I1@PURE_QUANTA.CYUSB330468LTXI(CHIPS)':
 'DVDD12_5': CDS_PINID='DVDD12_5';
NODE_NAME     U6001 13
 '@T6G_MB_LIB.T6G(SCH_1):PAGE154_I1@PURE_QUANTA.CYUSB330468LTXI(CHIPS)':
 'DVDD12_6': CDS_PINID='DVDD12_6';
NODE_NAME     U6001 37
 '@T6G_MB_LIB.T6G(SCH_1):PAGE154_I1@PURE_QUANTA.CYUSB330468LTXI(CHIPS)':
 'DVDD12_7': CDS_PINID='DVDD12_7';
NODE_NAME     U6001 43
 '@T6G_MB_LIB.T6G(SCH_1):PAGE154_I1@PURE_QUANTA.CYUSB330468LTXI(CHIPS)':
 'DVDD12_8': CDS_PINID='DVDD12_8';
NODE_NAME     L6001 1
 '@T6G_MB_LIB.T6G(SCH_1):PAGE154_I26@PURE_QUANTA.Q_INDUCTOR(CHIPS)':
 '1': CDS_PINID='\1\';
NODE_NAME     C6054 1
 '@T6G_MB_LIB.T6G(SCH_1):PAGE154_I43@PURE_QUANTA.Q_CAP(CHIPS)':
 'A': CDS_PINID='A';
NODE_NAME     C6055 1
 '@T6G_MB_LIB.T6G(SCH_1):PAGE154_I44@PURE_QUANTA.Q_CAP(CHIPS)':
 'A': CDS_PINID='A';
NODE_NAME     C6056 1
 '@T6G_MB_LIB.T6G(SCH_1):PAGE154_I46@PURE_QUANTA.Q_CAP(CHIPS)':
 'A': CDS_PINID='A';
NODE_NAME     C6057 1
 '@T6G_MB_LIB.T6G(SCH_1):PAGE154_I47@PURE_QUANTA.Q_CAP(CHIPS)':
 'A': CDS_PINID='A';
NODE_NAME     C6058 1
 '@T6G_MB_LIB.T6G(SCH_1):PAGE154_I49@PURE_QUANTA.Q_CAP(CHIPS)':
 'A': CDS_PINID='A';
NODE_NAME     C6059 1
 '@T6G_MB_LIB.T6G(SCH_1):PAGE154_I50@PURE_QUANTA.Q_CAP(CHIPS)':
 'A': CDS_PINID='A';
NODE_NAME     C6060 1
 '@T6G_MB_LIB.T6G(SCH_1):PAGE154_I52@PURE_QUANTA.Q_CAP(CHIPS)':
 'A': CDS_PINID='A';
NODE_NAME     C6061 1
 '@T6G_MB_LIB.T6G(SCH_1):PAGE154_I53@PURE_QUANTA.Q_CAP(CHIPS)':
 'A': CDS_PINID='A';
NODE_NAME     C6062 1
 '@T6G_MB_LIB.T6G(SCH_1):PAGE154_I55@PURE_QUANTA.Q_CAP(CHIPS)':
 'A': CDS_PINID='A';
NODE_NAME     C6063 1
 '@T6G_MB_LIB.T6G(SCH_1):PAGE154_I56@PURE_QUANTA.Q_CAP(CHIPS)':
 'A': CDS_PINID='A';
NODE_NAME     C6064 1
 '@T6G_MB_LIB.T6G(SCH_1):PAGE154_I58@PURE_QUANTA.Q_CAP(CHIPS)':
 'A': CDS_PINID='A';
NODE_NAME     C6065 1
 '@T6G_MB_LIB.T6G(SCH_1):PAGE154_I59@PURE_QUANTA.Q_CAP(CHIPS)':
 'A': CDS_PINID='A';
NODE_NAME     C6066 1
 '@T6G_MB_LIB.T6G(SCH_1):PAGE154_I60@PURE_QUANTA.Q_CAP(CHIPS)':
 'A': CDS_PINID='A';
NODE_NAME     C6069 1
 '@T6G_MB_LIB.T6G(SCH_1):PAGE154_I63@PURE_QUANTA.Q_CAP(CHIPS)':
 'A': CDS_PINID='A';
NODE_NAME     C6079 1
 '@T6G_MB_LIB.T6G(SCH_1):PAGE154_I64@PURE_QUANTA.Q_CAP(CHIPS)':
 'A': CDS_PINID='A';
NODE_NAME     C6078 1
 '@T6G_MB_LIB.T6G(SCH_1):PAGE154_I65@PURE_QUANTA.Q_CAP(CHIPS)':
 'A': CDS_PINID='A';
NODE_NAME     C6077 1
 '@T6G_MB_LIB.T6G(SCH_1):PAGE154_I66@PURE_QUANTA.Q_CAP(CHIPS)':
 'A': CDS_PINID='A';
NODE_NAME     C6076 1
 '@T6G_MB_LIB.T6G(SCH_1):PAGE154_I68@PURE_QUANTA.Q_CAP(CHIPS)':
 'A': CDS_PINID='A';
NODE_NAME     C6075 1
 '@T6G_MB_LIB.T6G(SCH_1):PAGE154_I69@PURE_QUANTA.Q_CAP(CHIPS)':
 'A': CDS_PINID='A';
NODE_NAME     C6074 1
 '@T6G_MB_LIB.T6G(SCH_1):PAGE154_I71@PURE_QUANTA.Q_CAP(CHIPS)':
 'A': CDS_PINID='A';
NODE_NAME     C6073 1
 '@T6G_MB_LIB.T6G(SCH_1):PAGE154_I73@PURE_QUANTA.Q_CAP(CHIPS)':
 'A': CDS_PINID='A';
NODE_NAME     C6072 1
 '@T6G_MB_LIB.T6G(SCH_1):PAGE154_I74@PURE_QUANTA.Q_CAP(CHIPS)':
 'A': CDS_PINID='A';
NODE_NAME     C6071 1
 '@T6G_MB_LIB.T6G(SCH_1):PAGE154_I75@PURE_QUANTA.Q_CAP(CHIPS)':
 'A': CDS_PINID='A';
NODE_NAME     C6070 1
 '@T6G_MB_LIB.T6G(SCH_1):PAGE154_I76@PURE_QUANTA.Q_CAP(CHIPS)':
 'A': CDS_PINID='A';
NODE_NAME     C6068 1
 '@T6G_MB_LIB.T6G(SCH_1):PAGE154_I78@PURE_QUANTA.Q_CAP(CHIPS)':
 'A': CDS_PINID='A';
NODE_NAME     C6067 1
 '@T6G_MB_LIB.T6G(SCH_1):PAGE154_I79@PURE_QUANTA.Q_CAP(CHIPS)':
 'A': CDS_PINID='A';
NODE_NAME     C6080 1
 '@T6G_MB_LIB.T6G(SCH_1):PAGE154_I81@PURE_QUANTA.Q_CAP(CHIPS)':
 'A': CDS_PINID='A';
NODE_NAME     C6081 1
 '@T6G_MB_LIB.T6G(SCH_1):PAGE154_I82@PURE_QUANTA.Q_CAP(CHIPS)':
 'A': CDS_PINID='A';
NODE_NAME     C6082 1
 '@T6G_MB_LIB.T6G(SCH_1):PAGE154_I83@PURE_QUANTA.Q_CAP(CHIPS)':
 'A': CDS_PINID='A';
NODE_NAME     PC6022 1
 '@T6G_MB_LIB.T6G(SCH_1):PAGE380_I23@PURE_QUANTA.Q_CAP(CHIPS)':
 'A': CDS_PINID='A';
NODE_NAME     PL6001 2
 '@T6G_MB_LIB.T6G(SCH_1):PAGE380_I24@PURE_QUANTA.Q_INDUCTOR(CHIPS)':
 '2': CDS_PINID='\2\';
NODE_NAME     PC852 2
 '@T6G_MB_LIB.T6G(SCH_1):PAGE380_I26@PURE_QUANTA.Q_CAP(CHIPS)':
 'B': CDS_PINID='B';
NODE_NAME     PR6008 2
 '@T6G_MB_LIB.T6G(SCH_1):PAGE380_I27@PURE_QUANTA.Q_RES(CHIPS)':
 'B': CDS_PINID='B';
NODE_NAME     PC6024 1
 '@T6G_MB_LIB.T6G(SCH_1):PAGE380_I28@PURE_QUANTA.Q_CAP(CHIPS)':
 'A': CDS_PINID='A';
NODE_NAME     PC6025 1
 '@T6G_MB_LIB.T6G(SCH_1):PAGE380_I29@PURE_QUANTA.Q_CAP(CHIPS)':
 'A': CDS_PINID='A';
NODE_NAME     PC6026 1
 '@T6G_MB_LIB.T6G(SCH_1):PAGE380_I32@PURE_QUANTA.Q_CAP(CHIPS)':
 'A': CDS_PINID='A';
NODE_NAME     PC6018 1
 '@T6G_MB_LIB.T6G(SCH_1):PAGE380_I33@PURE_QUANTA.Q_CAP(CHIPS)':
 'A': CDS_PINID='A';
NODE_NAME     L6004 1
 '@T6G_MB_LIB.T6G(SCH_1):PAGE157_I20@PURE_QUANTA.Q_INDUCTOR(CHIPS)':
 '1': CDS_PINID='\1\';
NODE_NAME     R1232 1
 '@T6G_MB_LIB.T6G(SCH_1):PAGE263_I179@PURE_QUANTA.Q_RES(CHIPS)':
 'A': CDS_PINID='A';
NET_NAME
'P1V2_AUX_ADC'
 '@T6G_MB_LIB.T6G(SCH_1):P1V2_AUX_ADC':
 C_SIGNAL='@t6g_mb_lib.t6g(sch_1):p1v2_aux_adc';
NODE_NAME     R1245 1
 '@T6G_MB_LIB.T6G(SCH_1):PAGE263_I177@PURE_QUANTA.Q_RES(CHIPS)':
 'A': CDS_PINID='A';
NODE_NAME     R1251 1
 '@T6G_MB_LIB.T6G(SCH_1):PAGE263_I178@PURE_QUANTA.Q_RES(CHIPS)':
 'A': CDS_PINID='A';
NODE_NAME     R1232 2
 '@T6G_MB_LIB.T6G(SCH_1):PAGE263_I179@PURE_QUANTA.Q_RES(CHIPS)':
 'B': CDS_PINID='B';
NODE_NAME     R1221 1
 '@T6G_MB_LIB.T6G(SCH_1):PAGE263_I243@PURE_QUANTA.Q_RES(CHIPS)':
 'A': CDS_PINID='A';
NET_NAME
'P1V2_AUX_ADC_MAM'
 '@T6G_MB_LIB.T6G(SCH_1):P1V2_AUX_ADC_MAM':
 C_SIGNAL='@t6g_mb_lib.t6g(sch_1):p1v2_aux_adc_mam';
NODE_NAME     U50 7
 '@T6G_MB_LIB.T6G(SCH_1):PAGE263_I156@PURE_QUANTA.MAX11617EEET(CHIPS)':
 'AIN2': CDS_PINID='AIN2';
NODE_NAME     C1078 1
 '@T6G_MB_LIB.T6G(SCH_1):PAGE263_I173@PURE_QUANTA.Q_CAP(CHIPS)':
 'A': CDS_PINID='A';
NODE_NAME     R1245 2
 '@T6G_MB_LIB.T6G(SCH_1):PAGE263_I177@PURE_QUANTA.Q_RES(CHIPS)':
 'B': CDS_PINID='B';
NET_NAME
'P1V2_AUX_ADC_TIC'
 '@T6G_MB_LIB.T6G(SCH_1):P1V2_AUX_ADC_TIC':
 C_SIGNAL='@t6g_mb_lib.t6g(sch_1):p1v2_aux_adc_tic';
NODE_NAME     U51 14
 '@T6G_MB_LIB.T6G(SCH_1):PAGE263_I142@PURE_QUANTA.ADC128D818CIMTXNOPB(CHIPS)':
 'IN2': CDS_PINID='IN2';
NODE_NAME     C1086 1
 '@T6G_MB_LIB.T6G(SCH_1):PAGE263_I175@PURE_QUANTA.Q_CAP(CHIPS)':
 'A': CDS_PINID='A';
NODE_NAME     R1251 2
 '@T6G_MB_LIB.T6G(SCH_1):PAGE263_I178@PURE_QUANTA.Q_RES(CHIPS)':
 'B': CDS_PINID='B';
NET_NAME
'P1V2_AUX_CS'
 '@T6G_MB_LIB.T6G(SCH_1):P1V2_AUX_CS':
 C_SIGNAL='@t6g_mb_lib.t6g(sch_1):p1v2_aux_cs';
NODE_NAME     PR6004 1
 '@T6G_MB_LIB.T6G(SCH_1):PAGE380_I6@PURE_QUANTA.Q_RES(CHIPS)':
 'A': CDS_PINID='A';
NODE_NAME     PU6001 4
 '@T6G_MB_LIB.T6G(SCH_1):PAGE380_I16@PURE_QUANTA.MPQ8626GDZ(CHIPS)':
 'CS': CDS_PINID='CS';
NET_NAME
'P1V2_AUX_ENABLE'
 '@T6G_MB_LIB.T6G(SCH_1):P1V2_AUX_ENABLE':
 C_SIGNAL='@t6g_mb_lib.t6g(sch_1):p1v2_aux_enable';
NODE_NAME     PU6001 5
 '@T6G_MB_LIB.T6G(SCH_1):PAGE380_I16@PURE_QUANTA.MPQ8626GDZ(CHIPS)':
 'EN': CDS_PINID='EN';
NODE_NAME     R6240 2
 '@T6G_MB_LIB.T6G(SCH_1):PAGE380_I40@PURE_QUANTA.Q_RES(CHIPS)':
 'B': CDS_PINID='B';
NET_NAME
'P1V2_AUX_FB'
 '@T6G_MB_LIB.T6G(SCH_1):P1V2_AUX_FB':
 C_SIGNAL='@t6g_mb_lib.t6g(sch_1):p1v2_aux_fb';
NODE_NAME     PU6001 6
 '@T6G_MB_LIB.T6G(SCH_1):PAGE380_I16@PURE_QUANTA.MPQ8626GDZ(CHIPS)':
 'FB': CDS_PINID='FB';
NODE_NAME     PR6011 1
 '@T6G_MB_LIB.T6G(SCH_1):PAGE380_I21@PURE_QUANTA.Q_RES(CHIPS)':
 'A': CDS_PINID='A';
NODE_NAME     PC852 1
 '@T6G_MB_LIB.T6G(SCH_1):PAGE380_I26@PURE_QUANTA.Q_CAP(CHIPS)':
 'A': CDS_PINID='A';
NODE_NAME     PR6008 1
 '@T6G_MB_LIB.T6G(SCH_1):PAGE380_I27@PURE_QUANTA.Q_RES(CHIPS)':
 'A': CDS_PINID='A';
NET_NAME
'P1V2_AUX_MODE'
 '@T6G_MB_LIB.T6G(SCH_1):P1V2_AUX_MODE':
 C_SIGNAL='@t6g_mb_lib.t6g(sch_1):p1v2_aux_mode';
NODE_NAME     PR6005 2
 '@T6G_MB_LIB.T6G(SCH_1):PAGE380_I11@PURE_QUANTA.Q_RES(CHIPS)':
 'B': CDS_PINID='B';
NODE_NAME     PU6001 12
 '@T6G_MB_LIB.T6G(SCH_1):PAGE380_I16@PURE_QUANTA.MPQ8626GDZ(CHIPS)':
 'MODE': CDS_PINID='MODE';
NET_NAME
'P1V2_AUX_REF'
 '@T6G_MB_LIB.T6G(SCH_1):P1V2_AUX_REF':
 C_SIGNAL='@t6g_mb_lib.t6g(sch_1):p1v2_aux_ref';
NODE_NAME     PU6001 8
 '@T6G_MB_LIB.T6G(SCH_1):PAGE380_I16@PURE_QUANTA.MPQ8626GDZ(CHIPS)':
 'TRK_REF': CDS_PINID='TRK_REF';
NODE_NAME     PC6016 1
 '@T6G_MB_LIB.T6G(SCH_1):PAGE380_I17@PURE_QUANTA.Q_CAP(CHIPS)':
 'A': CDS_PINID='A';
NET_NAME
'P1V2_AUX_VCC'
 '@T6G_MB_LIB.T6G(SCH_1):P1V2_AUX_VCC':
 C_SIGNAL='@t6g_mb_lib.t6g(sch_1):p1v2_aux_vcc';
NODE_NAME     PC6009 1
 '@T6G_MB_LIB.T6G(SCH_1):PAGE380_I7@PURE_QUANTA.Q_CAP(CHIPS)':
 'A': CDS_PINID='A';
NODE_NAME     PU6001 13
 '@T6G_MB_LIB.T6G(SCH_1):PAGE380_I16@PURE_QUANTA.MPQ8626GDZ(CHIPS)':
 'VCC': CDS_PINID='VCC';
NODE_NAME     R6245 2
 '@T6G_MB_LIB.T6G(SCH_1):PAGE380_I38@PURE_QUANTA.Q_RES(CHIPS)':
 'B': CDS_PINID='B';
NET_NAME
'P1V2_CPU0_USB2_DVDD12'
 '@T6G_MB_LIB.T6G(SCH_1):P1V2_CPU0_USB2_DVDD12':
 C_SIGNAL='@t6g_mb_lib.t6g(sch_1):p1v2_cpu0_usb2_dvdd12',
 CDS_GLOBAL_NET='TRUE';
NODE_NAME     L6004 2
 '@T6G_MB_LIB.T6G(SCH_1):PAGE157_I20@PURE_QUANTA.Q_INDUCTOR(CHIPS)':
 '2': CDS_PINID='\2\';
NODE_NAME     C6105 1
 '@T6G_MB_LIB.T6G(SCH_1):PAGE157_I36@PURE_QUANTA.Q_CAP(CHIPS)':
 'A': CDS_PINID='A';
NODE_NAME     C6108 1
 '@T6G_MB_LIB.T6G(SCH_1):PAGE157_I39@PURE_QUANTA.Q_CAP(CHIPS)':
 'A': CDS_PINID='A';
NODE_NAME     C6107 1
 '@T6G_MB_LIB.T6G(SCH_1):PAGE157_I40@PURE_QUANTA.Q_CAP(CHIPS)':
 'A': CDS_PINID='A';
NODE_NAME     C6106 1
 '@T6G_MB_LIB.T6G(SCH_1):PAGE157_I41@PURE_QUANTA.Q_CAP(CHIPS)':
 'A': CDS_PINID='A';
NODE_NAME     C6111 1
 '@T6G_MB_LIB.T6G(SCH_1):PAGE157_I42@PURE_QUANTA.Q_CAP(CHIPS)':
 'A': CDS_PINID='A';
NODE_NAME     C6110 1
 '@T6G_MB_LIB.T6G(SCH_1):PAGE157_I43@PURE_QUANTA.Q_CAP(CHIPS)':
 'A': CDS_PINID='A';
NODE_NAME     C6109 1
 '@T6G_MB_LIB.T6G(SCH_1):PAGE157_I44@PURE_QUANTA.Q_CAP(CHIPS)':
 'A': CDS_PINID='A';
NODE_NAME     C6114 1
 '@T6G_MB_LIB.T6G(SCH_1):PAGE157_I45@PURE_QUANTA.Q_CAP(CHIPS)':
 'A': CDS_PINID='A';
NODE_NAME     C6113 1
 '@T6G_MB_LIB.T6G(SCH_1):PAGE157_I46@PURE_QUANTA.Q_CAP(CHIPS)':
 'A': CDS_PINID='A';
NODE_NAME     C6112 1
 '@T6G_MB_LIB.T6G(SCH_1):PAGE157_I47@PURE_QUANTA.Q_CAP(CHIPS)':
 'A': CDS_PINID='A';
NODE_NAME     C6117 1
 '@T6G_MB_LIB.T6G(SCH_1):PAGE157_I48@PURE_QUANTA.Q_CAP(CHIPS)':
 'A': CDS_PINID='A';
NODE_NAME     C6116 1
 '@T6G_MB_LIB.T6G(SCH_1):PAGE157_I49@PURE_QUANTA.Q_CAP(CHIPS)':
 'A': CDS_PINID='A';
NODE_NAME     C6115 1
 '@T6G_MB_LIB.T6G(SCH_1):PAGE157_I50@PURE_QUANTA.Q_CAP(CHIPS)':
 'A': CDS_PINID='A';
NODE_NAME     C6121 1
 '@T6G_MB_LIB.T6G(SCH_1):PAGE157_I51@PURE_QUANTA.Q_CAP(CHIPS)':
 'A': CDS_PINID='A';
NODE_NAME     C6120 1
 '@T6G_MB_LIB.T6G(SCH_1):PAGE157_I52@PURE_QUANTA.Q_CAP(CHIPS)':
 'A': CDS_PINID='A';
NODE_NAME     C6119 1
 '@T6G_MB_LIB.T6G(SCH_1):PAGE157_I53@PURE_QUANTA.Q_CAP(CHIPS)':
 'A': CDS_PINID='A';
NODE_NAME     C6118 1
 '@T6G_MB_LIB.T6G(SCH_1):PAGE157_I54@PURE_QUANTA.Q_CAP(CHIPS)':
 'A': CDS_PINID='A';
NODE_NAME     U6002 13
 '@T6G_MB_LIB.T6G(SCH_1):PAGE157_I119@PURE_QUANTA.TUSB8042AIRGCR(CHIPS)':
 'VDD_13': CDS_PINID='VDD_13';
NODE_NAME     U6002 51
 '@T6G_MB_LIB.T6G(SCH_1):PAGE157_I119@PURE_QUANTA.TUSB8042AIRGCR(CHIPS)':
 'VDD_51': CDS_PINID='VDD_51';
NODE_NAME     U6002 57
 '@T6G_MB_LIB.T6G(SCH_1):PAGE157_I119@PURE_QUANTA.TUSB8042AIRGCR(CHIPS)':
 'VDD_57': CDS_PINID='VDD_57';
NODE_NAME     R6267 2
 '@T6G_MB_LIB.T6G(SCH_1):PAGE157_I122@PURE_QUANTA.Q_RES(CHIPS)':
 'B': CDS_PINID='B';
NODE_NAME     R6261 2
 '@T6G_MB_LIB.T6G(SCH_1):PAGE155_I134@PURE_QUANTA.Q_RES(CHIPS)':
 'B': CDS_PINID='B';
NODE_NAME     R6266 2
 '@T6G_MB_LIB.T6G(SCH_1):PAGE155_I136@PURE_QUANTA.Q_RES(CHIPS)':
 'B': CDS_PINID='B';
NODE_NAME     R6262 2
 '@T6G_MB_LIB.T6G(SCH_1):PAGE157_I134@PURE_QUANTA.Q_RES(CHIPS)':
 'B': CDS_PINID='B';
NODE_NAME     R6268 2
 '@T6G_MB_LIB.T6G(SCH_1):PAGE155_I149@PURE_QUANTA.Q_RES(CHIPS)':
 'B': CDS_PINID='B';
NODE_NAME     R6269 2
 '@T6G_MB_LIB.T6G(SCH_1):PAGE157_I136@PURE_QUANTA.Q_RES(CHIPS)':
 'B': CDS_PINID='B';
NODE_NAME     R6263 2
 '@T6G_MB_LIB.T6G(SCH_1):PAGE155_I155@PURE_QUANTA.Q_RES(CHIPS)':
 'B': CDS_PINID='B';
NODE_NAME     R6265 2
 '@T6G_MB_LIB.T6G(SCH_1):PAGE157_I145@PURE_QUANTA.Q_RES(CHIPS)':
 'B': CDS_PINID='B';
NODE_NAME     R6259 1
 '@T6G_MB_LIB.T6G(SCH_1):PAGE155_I166@PURE_QUANTA.Q_RES(CHIPS)':
 'A': CDS_PINID='A';
NODE_NAME     R6260 2
 '@T6G_MB_LIB.T6G(SCH_1):PAGE157_I170@PURE_QUANTA.Q_RES(CHIPS)':
 'B': CDS_PINID='B';
NET_NAME
'P1V2_CPU0_USB_DVDD12'
 '@T6G_MB_LIB.T6G(SCH_1):P1V2_CPU0_USB_DVDD12':
 C_SIGNAL='@t6g_mb_lib.t6g(sch_1):p1v2_cpu0_usb_dvdd12',
 CDS_GLOBAL_NET='TRUE';
NODE_NAME     U6001 1
 '@T6G_MB_LIB.T6G(SCH_1):PAGE154_I1@PURE_QUANTA.CYUSB330468LTXI(CHIPS)':
 'DVDD12_1': CDS_PINID='DVDD12_1';
NODE_NAME     U6001 3
 '@T6G_MB_LIB.T6G(SCH_1):PAGE154_I1@PURE_QUANTA.CYUSB330468LTXI(CHIPS)':
 'DVDD12_2': CDS_PINID='DVDD12_2';
NODE_NAME     U6001 27
 '@T6G_MB_LIB.T6G(SCH_1):PAGE154_I1@PURE_QUANTA.CYUSB330468LTXI(CHIPS)':
 'DVDD12_3': CDS_PINID='DVDD12_3';
NODE_NAME     U6001 19
 '@T6G_MB_LIB.T6G(SCH_1):PAGE154_I1@PURE_QUANTA.CYUSB330468LTXI(CHIPS)':
 'VDD_EFUSE': CDS_PINID='VDD_EFUSE';
NODE_NAME     L6001 2
 '@T6G_MB_LIB.T6G(SCH_1):PAGE154_I26@PURE_QUANTA.Q_INDUCTOR(CHIPS)':
 '2': CDS_PINID='\2\';
NODE_NAME     C6030 1
 '@T6G_MB_LIB.T6G(SCH_1):PAGE154_I27@PURE_QUANTA.Q_CAP(CHIPS)':
 'A': CDS_PINID='A';
NODE_NAME     C6031 1
 '@T6G_MB_LIB.T6G(SCH_1):PAGE154_I29@PURE_QUANTA.Q_CAP(CHIPS)':
 'A': CDS_PINID='A';
NODE_NAME     C6035 1
 '@T6G_MB_LIB.T6G(SCH_1):PAGE154_I31@PURE_QUANTA.Q_CAP(CHIPS)':
 'A': CDS_PINID='A';
NODE_NAME     C6034 1
 '@T6G_MB_LIB.T6G(SCH_1):PAGE154_I32@PURE_QUANTA.Q_CAP(CHIPS)':
 'A': CDS_PINID='A';
NODE_NAME     C6033 1
 '@T6G_MB_LIB.T6G(SCH_1):PAGE154_I34@PURE_QUANTA.Q_CAP(CHIPS)':
 'A': CDS_PINID='A';
NODE_NAME     C6032 1
 '@T6G_MB_LIB.T6G(SCH_1):PAGE154_I35@PURE_QUANTA.Q_CAP(CHIPS)':
 'A': CDS_PINID='A';
NODE_NAME     C6036 1
 '@T6G_MB_LIB.T6G(SCH_1):PAGE154_I37@PURE_QUANTA.Q_CAP(CHIPS)':
 'A': CDS_PINID='A';
NODE_NAME     C6037 1
 '@T6G_MB_LIB.T6G(SCH_1):PAGE154_I38@PURE_QUANTA.Q_CAP(CHIPS)':
 'A': CDS_PINID='A';
NODE_NAME     C6039 1
 '@T6G_MB_LIB.T6G(SCH_1):PAGE154_I40@PURE_QUANTA.Q_CAP(CHIPS)':
 'A': CDS_PINID='A';
NODE_NAME     C6038 1
 '@T6G_MB_LIB.T6G(SCH_1):PAGE154_I41@PURE_QUANTA.Q_CAP(CHIPS)':
 'A': CDS_PINID='A';
NET_NAME
'P1V581_PDB_ADC'
 '@T6G_MB_LIB.T6G(SCH_1):P1V581_PDB_ADC':
 C_SIGNAL='@t6g_mb_lib.t6g(sch_1):p1v581_pdb_adc';
NODE_NAME     R4568 1
 '@T6G_MB_LIB.T6G(SCH_1):PAGE369_I7@PURE_QUANTA.Q_RES(CHIPS)':
 'A': CDS_PINID='A';
NODE_NAME     R4567 2
 '@T6G_MB_LIB.T6G(SCH_1):PAGE369_I8@PURE_QUANTA.Q_RES(CHIPS)':
 'B': CDS_PINID='B';
NODE_NAME     R3688 1
 '@T6G_MB_LIB.T6G(SCH_1):PAGE369_I41@PURE_QUANTA.Q_RES(CHIPS)':
 'A': CDS_PINID='A';
NODE_NAME     R3687 1
 '@T6G_MB_LIB.T6G(SCH_1):PAGE369_I42@PURE_QUANTA.Q_RES(CHIPS)':
 'A': CDS_PINID='A';
NET_NAME
'P1V5_BAT'
 '@T6G_MB_LIB.T6G(SCH_1):P1V5_BAT':
 C_SIGNAL='@t6g_mb_lib.t6g(sch_1):p1v5_bat',
 CDS_GLOBAL_NET='TRUE';
NODE_NAME     U25 BN23
 '@T6G_MB_LIB.T6G(SCH_1):PAGE30_I28@PURE_QUANTA.GENOA_SP5(CHIPS)':
 'VDDBT_RTC_G': CDS_PINID='VDDBT_RTC_G';
NODE_NAME     R373 1
 '@T6G_MB_LIB.T6G(SCH_1):PAGE57_I52@PURE_QUANTA.Q_RES(CHIPS)':
 'A': CDS_PINID='A';
NODE_NAME     R1779 2
 '@T6G_MB_LIB.T6G(SCH_1):PAGE156_I116@PURE_QUANTA.Q_RES(CHIPS)':
 'B': CDS_PINID='B';
NODE_NAME     C1567 1
 '@T6G_MB_LIB.T6G(SCH_1):PAGE156_I125@PURE_QUANTA.Q_CAP(CHIPS)':
 'A': CDS_PINID='A';
NODE_NAME     C5032 1
 '@T6G_MB_LIB.T6G(SCH_1):PAGE156_I126@PURE_QUANTA.Q_CAP(CHIPS)':
 'A': CDS_PINID='A';
NODE_NAME     JP12 2
 '@T6G_MB_LIB.T6G(SCH_1):PAGE156_I128@PURE_QUANTA.CONN3_210HP1030BR1(CHIPS)':
 '2': CDS_PINID='\2\';
NODE_NAME     R5055 1
 '@T6G_MB_LIB.T6G(SCH_1):PAGE27_I427@PURE_QUANTA.Q_RES(CHIPS)':
 'A': CDS_PINID='A';
NET_NAME
'P1V5_BAT_IN'
 '@T6G_MB_LIB.T6G(SCH_1):P1V5_BAT_IN':
 C_SIGNAL='@t6g_mb_lib.t6g(sch_1):p1v5_bat_in';
NODE_NAME     U9 1
 '@T6G_MB_LIB.T6G(SCH_1):PAGE156_I91@PURE_QUANTA.TPS71715DCKR(CHIPS)':
 'IN': CDS_PINID='\in\';
NODE_NAME     R5051 2
 '@T6G_MB_LIB.T6G(SCH_1):PAGE156_I101@PURE_QUANTA.Q_RES(CHIPS)':
 'B': CDS_PINID='B';
NODE_NAME     C45 1
 '@T6G_MB_LIB.T6G(SCH_1):PAGE156_I107@PURE_QUANTA.Q_CAP(CHIPS)':
 'A': CDS_PINID='A';
NODE_NAME     C193 1
 '@T6G_MB_LIB.T6G(SCH_1):PAGE156_I108@PURE_QUANTA.Q_CAP(CHIPS)':
 'A': CDS_PINID='A';
NODE_NAME     R1777 1
 '@T6G_MB_LIB.T6G(SCH_1):PAGE156_I129@PURE_QUANTA.Q_RES(CHIPS)':
 'A': CDS_PINID='A';
NODE_NAME     U167 2
 '@T6G_MB_LIB.T6G(SCH_1):PAGE156_I130@PURE_QUANTA.NCP698SQ15T1G(CHIPS)':
 'VIN': CDS_PINID='VIN';
NET_NAME
'P1V5_BAT_OUT'
 '@T6G_MB_LIB.T6G(SCH_1):P1V5_BAT_OUT':
 C_SIGNAL='@t6g_mb_lib.t6g(sch_1):p1v5_bat_out';
NODE_NAME     U9 5
 '@T6G_MB_LIB.T6G(SCH_1):PAGE156_I91@PURE_QUANTA.TPS71715DCKR(CHIPS)':
 'OUT': CDS_PINID='\out\';
NODE_NAME     C1564 1
 '@T6G_MB_LIB.T6G(SCH_1):PAGE156_I118@PURE_QUANTA.Q_CAP(CHIPS)':
 'A': CDS_PINID='A';
NODE_NAME     R5053 1
 '@T6G_MB_LIB.T6G(SCH_1):PAGE156_I120@PURE_QUANTA.Q_RES(CHIPS)':
 'A': CDS_PINID='A';
NODE_NAME     U167 3
 '@T6G_MB_LIB.T6G(SCH_1):PAGE156_I130@PURE_QUANTA.NCP698SQ15T1G(CHIPS)':
 'VOUT': CDS_PINID='VOUT';
NET_NAME
'P1V5_BAT_OUT_R'
 '@T6G_MB_LIB.T6G(SCH_1):P1V5_BAT_OUT_R':
 C_SIGNAL='@t6g_mb_lib.t6g(sch_1):p1v5_bat_out_r';
NODE_NAME     R5053 2
 '@T6G_MB_LIB.T6G(SCH_1):PAGE156_I120@PURE_QUANTA.Q_RES(CHIPS)':
 'B': CDS_PINID='B';
NODE_NAME     R5054 2
 '@T6G_MB_LIB.T6G(SCH_1):PAGE156_I122@PURE_QUANTA.Q_RES(CHIPS)':
 'B': CDS_PINID='B';
NODE_NAME     JP12 1
 '@T6G_MB_LIB.T6G(SCH_1):PAGE156_I128@PURE_QUANTA.CONN3_210HP1030BR1(CHIPS)':
 '1': CDS_PINID='\1\';
NET_NAME
'P1V8_AUX'
 '@T6G_MB_LIB.T6G(SCH_1):P1V8_AUX':
 C_SIGNAL='@t6g_mb_lib.t6g(sch_1):p1v8_aux',
 CDS_GLOBAL_NET='TRUE';
NODE_NAME     U3 5
 '@T6G_MB_LIB.T6G(SCH_1):PAGE29_I373@PURE_QUANTA.SN74LVC1G07DBVR(CHIPS)':
 'VCC': CDS_PINID='VCC';
NODE_NAME     C30 1
 '@T6G_MB_LIB.T6G(SCH_1):PAGE29_I379@PURE_QUANTA.Q_CAP(CHIPS)':
 'A': CDS_PINID='A';
NODE_NAME     R943 1
 '@T6G_MB_LIB.T6G(SCH_1):PAGE34_I53@PURE_QUANTA.Q_RES(CHIPS)':
 'A': CDS_PINID='A';
NODE_NAME     C223 1
 '@T6G_MB_LIB.T6G(SCH_1):PAGE77_I11@PURE_QUANTA.Q_CAP(CHIPS)':
 'A': CDS_PINID='A';
NODE_NAME     U29 5
 '@T6G_MB_LIB.T6G(SCH_1):PAGE77_I15@PURE_QUANTA.SN74LVC2G07DCKR(CHIPS)':
 'VCC': CDS_PINID='VCC';
NODE_NAME     C224 1
 '@T6G_MB_LIB.T6G(SCH_1):PAGE77_I19@PURE_QUANTA.Q_CAP(CHIPS)':
 'A': CDS_PINID='A';
NODE_NAME     U40 5
 '@T6G_MB_LIB.T6G(SCH_1):PAGE77_I21@PURE_QUANTA.SN74LVC2G07DCKR(CHIPS)':
 'VCC': CDS_PINID='VCC';
NODE_NAME     C218 1
 '@T6G_MB_LIB.T6G(SCH_1):PAGE143_I24@PURE_QUANTA.Q_CAP(CHIPS)':
 'A': CDS_PINID='A';
NODE_NAME     U82 5
 '@T6G_MB_LIB.T6G(SCH_1):PAGE143_I26@PURE_QUANTA.SN74LVC1G07DBVR(CHIPS)':
 'VCC': CDS_PINID='VCC';
NODE_NAME     C219 1
 '@T6G_MB_LIB.T6G(SCH_1):PAGE143_I29@PURE_QUANTA.Q_CAP(CHIPS)':
 'A': CDS_PINID='A';
NODE_NAME     U86 5
 '@T6G_MB_LIB.T6G(SCH_1):PAGE143_I31@PURE_QUANTA.SN74LVC1G07DBVR(CHIPS)':
 'VCC': CDS_PINID='VCC';
NODE_NAME     U98 2
 '@T6G_MB_LIB.T6G(SCH_1):PAGE346_I27@PURE_QUANTA.PCA9306DP1(CHIPS)':
 'VREF1': CDS_PINID='VREF1';
NODE_NAME     C1323 1
 '@T6G_MB_LIB.T6G(SCH_1):PAGE346_I28@PURE_QUANTA.Q_CAP(CHIPS)':
 'A': CDS_PINID='A';
NODE_NAME     R1702 1
 '@T6G_MB_LIB.T6G(SCH_1):PAGE346_I43@PURE_QUANTA.Q_RES(CHIPS)':
 'A': CDS_PINID='A';
NODE_NAME     R1703 1
 '@T6G_MB_LIB.T6G(SCH_1):PAGE346_I45@PURE_QUANTA.Q_RES(CHIPS)':
 'A': CDS_PINID='A';
NODE_NAME     C1134 1
 '@T6G_MB_LIB.T6G(SCH_1):PAGE82_I79@PURE_QUANTA.Q_CAP(CHIPS)':
 'A': CDS_PINID='A';
NODE_NAME     C1132 1
 '@T6G_MB_LIB.T6G(SCH_1):PAGE82_I80@PURE_QUANTA.Q_CAP(CHIPS)':
 'A': CDS_PINID='A';
NODE_NAME     C1131 1
 '@T6G_MB_LIB.T6G(SCH_1):PAGE82_I82@PURE_QUANTA.Q_CAP(CHIPS)':
 'A': CDS_PINID='A';
NODE_NAME     C352 1
 '@T6G_MB_LIB.T6G(SCH_1):PAGE82_I83@PURE_QUANTA.Q_CAP(CHIPS)':
 'A': CDS_PINID='A';
NODE_NAME     C1128 1
 '@T6G_MB_LIB.T6G(SCH_1):PAGE82_I84@PURE_QUANTA.Q_CAP(CHIPS)':
 'A': CDS_PINID='A';
NODE_NAME     C1129 1
 '@T6G_MB_LIB.T6G(SCH_1):PAGE82_I85@PURE_QUANTA.Q_CAP(CHIPS)':
 'A': CDS_PINID='A';
NODE_NAME     C1126 1
 '@T6G_MB_LIB.T6G(SCH_1):PAGE82_I86@PURE_QUANTA.Q_CAP(CHIPS)':
 'A': CDS_PINID='A';
NODE_NAME     C1127 1
 '@T6G_MB_LIB.T6G(SCH_1):PAGE82_I87@PURE_QUANTA.Q_CAP(CHIPS)':
 'A': CDS_PINID='A';
NODE_NAME     R996 1
 '@T6G_MB_LIB.T6G(SCH_1):PAGE83_I22@PURE_QUANTA.Q_RES(CHIPS)':
 'A': CDS_PINID='A';
NODE_NAME     C552 1
 '@T6G_MB_LIB.T6G(SCH_1):PAGE83_I24@PURE_QUANTA.Q_CAP(CHIPS)':
 'A': CDS_PINID='A';
NODE_NAME     U92 5
 '@T6G_MB_LIB.T6G(SCH_1):PAGE83_I26@PURE_QUANTA.SN74LVC1G07DBVR(CHIPS)':
 'VCC': CDS_PINID='VCC';
NODE_NAME     R1261 1
 '@T6G_MB_LIB.T6G(SCH_1):PAGE144_I15@PURE_QUANTA.Q_RES(CHIPS)':
 'A': CDS_PINID='A';
NODE_NAME     R1262 1
 '@T6G_MB_LIB.T6G(SCH_1):PAGE144_I30@PURE_QUANTA.Q_RES(CHIPS)':
 'A': CDS_PINID='A';
NODE_NAME     R5071 1
 '@T6G_MB_LIB.T6G(SCH_1):PAGE144_I34@PURE_QUANTA.Q_RES(CHIPS)':
 'A': CDS_PINID='A';
NODE_NAME     R1264 1
 '@T6G_MB_LIB.T6G(SCH_1):PAGE144_I44@PURE_QUANTA.Q_RES(CHIPS)':
 'A': CDS_PINID='A';
NODE_NAME     R733 1
 '@T6G_MB_LIB.T6G(SCH_1):PAGE144_I50@PURE_QUANTA.Q_RES(CHIPS)':
 'A': CDS_PINID='A';
NODE_NAME     R22 1
 '@T6G_MB_LIB.T6G(SCH_1):PAGE144_I54@PURE_QUANTA.Q_RES(CHIPS)':
 'A': CDS_PINID='A';
NODE_NAME     R6040 1
 '@T6G_MB_LIB.T6G(SCH_1):PAGE144_I70@PURE_QUANTA.Q_RES(CHIPS)':
 'A': CDS_PINID='A';
NODE_NAME     R1358 1
 '@T6G_MB_LIB.T6G(SCH_1):PAGE144_I72@PURE_QUANTA.Q_RES(CHIPS)':
 'A': CDS_PINID='A';
NODE_NAME     U18 F20
 '@T6G_MB_LIB.T6G(SCH_1):PAGE81_I141@PURE_QUANTA.LCMXO3LF9400C5BG484C(CHIPS)':
 'VCCIO1_1': CDS_PINID='VCCIO1_1';
NODE_NAME     U18 J15
 '@T6G_MB_LIB.T6G(SCH_1):PAGE81_I141@PURE_QUANTA.LCMXO3LF9400C5BG484C(CHIPS)':
 'VCCIO1_2': CDS_PINID='VCCIO1_2';
NODE_NAME     U18 K15
 '@T6G_MB_LIB.T6G(SCH_1):PAGE81_I141@PURE_QUANTA.LCMXO3LF9400C5BG484C(CHIPS)':
 'VCCIO1_3': CDS_PINID='VCCIO1_3';
NODE_NAME     U18 L15
 '@T6G_MB_LIB.T6G(SCH_1):PAGE81_I141@PURE_QUANTA.LCMXO3LF9400C5BG484C(CHIPS)':
 'VCCIO1_4': CDS_PINID='VCCIO1_4';
NODE_NAME     U18 M15
 '@T6G_MB_LIB.T6G(SCH_1):PAGE81_I141@PURE_QUANTA.LCMXO3LF9400C5BG484C(CHIPS)':
 'VCCIO1_5': CDS_PINID='VCCIO1_5';
NODE_NAME     U18 M18
 '@T6G_MB_LIB.T6G(SCH_1):PAGE81_I141@PURE_QUANTA.LCMXO3LF9400C5BG484C(CHIPS)':
 'VCCIO1_6': CDS_PINID='VCCIO1_6';
NODE_NAME     U18 N15
 '@T6G_MB_LIB.T6G(SCH_1):PAGE81_I141@PURE_QUANTA.LCMXO3LF9400C5BG484C(CHIPS)':
 'VCCIO1_7': CDS_PINID='VCCIO1_7';
NODE_NAME     U18 P15
 '@T6G_MB_LIB.T6G(SCH_1):PAGE81_I141@PURE_QUANTA.LCMXO3LF9400C5BG484C(CHIPS)':
 'VCCIO1_8': CDS_PINID='VCCIO1_8';
NODE_NAME     U18 V20
 '@T6G_MB_LIB.T6G(SCH_1):PAGE81_I141@PURE_QUANTA.LCMXO3LF9400C5BG484C(CHIPS)':
 'VCCIO1_9': CDS_PINID='VCCIO1_9';
NODE_NAME     U18 F3
 '@T6G_MB_LIB.T6G(SCH_1):PAGE81_I141@PURE_QUANTA.LCMXO3LF9400C5BG484C(CHIPS)':
 'VCCIO5_1': CDS_PINID='VCCIO5_1';
NODE_NAME     U18 J8
 '@T6G_MB_LIB.T6G(SCH_1):PAGE81_I141@PURE_QUANTA.LCMXO3LF9400C5BG484C(CHIPS)':
 'VCCIO5_2': CDS_PINID='VCCIO5_2';
NODE_NAME     U18 K8
 '@T6G_MB_LIB.T6G(SCH_1):PAGE81_I141@PURE_QUANTA.LCMXO3LF9400C5BG484C(CHIPS)':
 'VCCIO5_3': CDS_PINID='VCCIO5_3';
NODE_NAME     R654 2
 '@T6G_MB_LIB.T6G(SCH_1):PAGE82_I64@PURE_QUANTA.Q_RES(CHIPS)':
 'B': CDS_PINID='B';
NODE_NAME     C1133 1
 '@T6G_MB_LIB.T6G(SCH_1):PAGE82_I81@PURE_QUANTA.Q_CAP(CHIPS)':
 'A': CDS_PINID='A';
NODE_NAME     U38 5
 '@T6G_MB_LIB.T6G(SCH_1):PAGE264_I8@PURE_QUANTA.SN74LVC1G11DCKR(CHIPS)':
 'VCC': CDS_PINID='VCC';
NODE_NAME     R1457 1
 '@T6G_MB_LIB.T6G(SCH_1):PAGE264_I41@PURE_QUANTA.Q_RES(CHIPS)':
 'A': CDS_PINID='A';
NODE_NAME     R1452 1
 '@T6G_MB_LIB.T6G(SCH_1):PAGE264_I43@PURE_QUANTA.Q_RES(CHIPS)':
 'A': CDS_PINID='A';
NODE_NAME     C347 1
 '@T6G_MB_LIB.T6G(SCH_1):PAGE264_I47@PURE_QUANTA.Q_CAP(CHIPS)':
 'A': CDS_PINID='A';
NODE_NAME     PL6000 2
 '@T6G_MB_LIB.T6G(SCH_1):PAGE315_I25@PURE_QUANTA.Q_INDUCTOR(CHIPS)':
 '2': CDS_PINID='\2\';
NODE_NAME     PC6019 2
 '@T6G_MB_LIB.T6G(SCH_1):PAGE315_I26@PURE_QUANTA.Q_CAP(CHIPS)':
 'B': CDS_PINID='B';
NODE_NAME     PC6021 1
 '@T6G_MB_LIB.T6G(SCH_1):PAGE315_I27@PURE_QUANTA.Q_CAP(CHIPS)':
 'A': CDS_PINID='A';
NODE_NAME     PR6007 2
 '@T6G_MB_LIB.T6G(SCH_1):PAGE315_I28@PURE_QUANTA.Q_RES(CHIPS)':
 'B': CDS_PINID='B';
NODE_NAME     PC865 1
 '@T6G_MB_LIB.T6G(SCH_1):PAGE315_I29@PURE_QUANTA.Q_CAP(CHIPS)':
 'A': CDS_PINID='A';
NODE_NAME     PC866 1
 '@T6G_MB_LIB.T6G(SCH_1):PAGE315_I34@PURE_QUANTA.Q_CAP(CHIPS)':
 'A': CDS_PINID='A';
NODE_NAME     PC867 1
 '@T6G_MB_LIB.T6G(SCH_1):PAGE315_I36@PURE_QUANTA.Q_CAP(CHIPS)':
 'A': CDS_PINID='A';
NODE_NAME     PC850 1
 '@T6G_MB_LIB.T6G(SCH_1):PAGE315_I37@PURE_QUANTA.Q_CAP(CHIPS)':
 'A': CDS_PINID='A';
NODE_NAME     R1493 1
 '@T6G_MB_LIB.T6G(SCH_1):PAGE273_I125@PURE_QUANTA.Q_RES(CHIPS)':
 'A': CDS_PINID='A';
NODE_NAME     R6504 1
 '@T6G_MB_LIB.T6G(SCH_1):PAGE264_I51@PURE_QUANTA.Q_RES(CHIPS)':
 'A': CDS_PINID='A';
NODE_NAME     R8018 1
 '@T6G_MB_LIB.T6G(SCH_1):PAGE144_I84@PURE_QUANTA.Q_RES(CHIPS)':
 'A': CDS_PINID='A';
NODE_NAME     U8000 5
 '@T6G_MB_LIB.T6G(SCH_1):PAGE130_I1@PURE_QUANTA.NC7SB3157P6X(CHIPS)':
 'VCC': CDS_PINID='VCC';
NODE_NAME     C8007 1
 '@T6G_MB_LIB.T6G(SCH_1):PAGE130_I4@PURE_QUANTA.Q_CAP(CHIPS)':
 'A': CDS_PINID='A';
NODE_NAME     R8035 1
 '@T6G_MB_LIB.T6G(SCH_1):PAGE130_I11@PURE_QUANTA.Q_RES(CHIPS)':
 'A': CDS_PINID='A';
NODE_NAME     U6020 24
 '@T6G_MB_LIB.T6G(SCH_1):PAGE378_I1@PURE_QUANTA.TCA9548APWR(CHIPS)':
 'VCC': CDS_PINID='VCC';
NODE_NAME     R6742 1
 '@T6G_MB_LIB.T6G(SCH_1):PAGE467_I5@PURE_QUANTA.Q_RES(CHIPS)':
 'A': CDS_PINID='A';
NODE_NAME     R6743 1
 '@T6G_MB_LIB.T6G(SCH_1):PAGE467_I6@PURE_QUANTA.Q_RES(CHIPS)':
 'A': CDS_PINID='A';
NODE_NAME     C7500 1
 '@T6G_MB_LIB.T6G(SCH_1):PAGE378_I88@PURE_QUANTA.Q_CAP(CHIPS)':
 'A': CDS_PINID='A';
NODE_NAME     R6770 1
 '@T6G_MB_LIB.T6G(SCH_1):PAGE378_I96@PURE_QUANTA.Q_RES(CHIPS)':
 'A': CDS_PINID='A';
NODE_NAME     R6772 1
 '@T6G_MB_LIB.T6G(SCH_1):PAGE378_I98@PURE_QUANTA.Q_RES(CHIPS)':
 'A': CDS_PINID='A';
NODE_NAME     R6771 1
 '@T6G_MB_LIB.T6G(SCH_1):PAGE378_I100@PURE_QUANTA.Q_RES(CHIPS)':
 'A': CDS_PINID='A';
NODE_NAME     R842 1
 '@T6G_MB_LIB.T6G(SCH_1):PAGE377_I4@PURE_QUANTA.Q_RES(CHIPS)':
 'A': CDS_PINID='A';
NODE_NAME     R843 1
 '@T6G_MB_LIB.T6G(SCH_1):PAGE377_I5@PURE_QUANTA.Q_RES(CHIPS)':
 'A': CDS_PINID='A';
NODE_NAME     R844 1
 '@T6G_MB_LIB.T6G(SCH_1):PAGE377_I9@PURE_QUANTA.Q_RES(CHIPS)':
 'A': CDS_PINID='A';
NODE_NAME     C365 1
 '@T6G_MB_LIB.T6G(SCH_1):PAGE377_I55@PURE_QUANTA.Q_CAP(CHIPS)':
 'A': CDS_PINID='A';
NODE_NAME     U22 24
 '@T6G_MB_LIB.T6G(SCH_1):PAGE377_I94@PURE_QUANTA.TCA9548APWR(CHIPS)':
 'VCC': CDS_PINID='VCC';
NODE_NAME     R6860 1
 '@T6G_MB_LIB.T6G(SCH_1):PAGE475_I213@PURE_QUANTA.Q_RES(CHIPS)':
 'A': CDS_PINID='A';
NODE_NAME     R6861 1
 '@T6G_MB_LIB.T6G(SCH_1):PAGE477_I93@PURE_QUANTA.Q_RES(CHIPS)':
 'A': CDS_PINID='A';
NODE_NAME     R1237 1
 '@T6G_MB_LIB.T6G(SCH_1):PAGE263_I19@PURE_QUANTA.Q_RES(CHIPS)':
 'A': CDS_PINID='A';
NODE_NAME     R6146 1
 '@T6G_MB_LIB.T6G(SCH_1):PAGE83_I138@PURE_QUANTA.Q_RES(CHIPS)':
 'A': CDS_PINID='A';
NODE_NAME     R6147 1
 '@T6G_MB_LIB.T6G(SCH_1):PAGE83_I140@PURE_QUANTA.Q_RES(CHIPS)':
 'A': CDS_PINID='A';
NODE_NAME     R6148 1
 '@T6G_MB_LIB.T6G(SCH_1):PAGE83_I142@PURE_QUANTA.Q_RES(CHIPS)':
 'A': CDS_PINID='A';
NET_NAME
'P1V8_AUX_ADC'
 '@T6G_MB_LIB.T6G(SCH_1):P1V8_AUX_ADC':
 C_SIGNAL='@t6g_mb_lib.t6g(sch_1):p1v8_aux_adc';
NODE_NAME     R1237 2
 '@T6G_MB_LIB.T6G(SCH_1):PAGE263_I19@PURE_QUANTA.Q_RES(CHIPS)':
 'B': CDS_PINID='B';
NODE_NAME     R1259 1
 '@T6G_MB_LIB.T6G(SCH_1):PAGE263_I21@PURE_QUANTA.Q_RES(CHIPS)':
 'A': CDS_PINID='A';
NODE_NAME     R1258 1
 '@T6G_MB_LIB.T6G(SCH_1):PAGE263_I22@PURE_QUANTA.Q_RES(CHIPS)':
 'A': CDS_PINID='A';
NODE_NAME     R1229 1
 '@T6G_MB_LIB.T6G(SCH_1):PAGE263_I242@PURE_QUANTA.Q_RES(CHIPS)':
 'A': CDS_PINID='A';
NET_NAME
'P1V8_AUX_ADC_MAM'
 '@T6G_MB_LIB.T6G(SCH_1):P1V8_AUX_ADC_MAM':
 C_SIGNAL='@t6g_mb_lib.t6g(sch_1):p1v8_aux_adc_mam';
NODE_NAME     R1258 2
 '@T6G_MB_LIB.T6G(SCH_1):PAGE263_I22@PURE_QUANTA.Q_RES(CHIPS)':
 'B': CDS_PINID='B';
NODE_NAME     C1084 1
 '@T6G_MB_LIB.T6G(SCH_1):PAGE263_I77@PURE_QUANTA.Q_CAP(CHIPS)':
 'A': CDS_PINID='A';
NODE_NAME     U50 6
 '@T6G_MB_LIB.T6G(SCH_1):PAGE263_I156@PURE_QUANTA.MAX11617EEET(CHIPS)':
 'AIN1': CDS_PINID='AIN1';
NET_NAME
'P1V8_AUX_ADC_TIC'
 '@T6G_MB_LIB.T6G(SCH_1):P1V8_AUX_ADC_TIC':
 C_SIGNAL='@t6g_mb_lib.t6g(sch_1):p1v8_aux_adc_tic';
NODE_NAME     R1259 2
 '@T6G_MB_LIB.T6G(SCH_1):PAGE263_I21@PURE_QUANTA.Q_RES(CHIPS)':
 'B': CDS_PINID='B';
NODE_NAME     C1092 1
 '@T6G_MB_LIB.T6G(SCH_1):PAGE263_I76@PURE_QUANTA.Q_CAP(CHIPS)':
 'A': CDS_PINID='A';
NODE_NAME     U51 15
 '@T6G_MB_LIB.T6G(SCH_1):PAGE263_I142@PURE_QUANTA.ADC128D818CIMTXNOPB(CHIPS)':
 'IN1': CDS_PINID='IN1';
NET_NAME
'P1V8_AUX_CS'
 '@T6G_MB_LIB.T6G(SCH_1):P1V8_AUX_CS':
 C_SIGNAL='@t6g_mb_lib.t6g(sch_1):p1v8_aux_cs';
NODE_NAME     PR6003 1
 '@T6G_MB_LIB.T6G(SCH_1):PAGE315_I12@PURE_QUANTA.Q_RES(CHIPS)':
 'A': CDS_PINID='A';
NODE_NAME     PU6000 4
 '@T6G_MB_LIB.T6G(SCH_1):PAGE315_I18@PURE_QUANTA.MPQ8626GDZ(CHIPS)':
 'CS': CDS_PINID='CS';
NET_NAME
'P1V8_AUX_ENABLE'
 '@T6G_MB_LIB.T6G(SCH_1):P1V8_AUX_ENABLE':
 C_SIGNAL='@t6g_mb_lib.t6g(sch_1):p1v8_aux_enable';
NODE_NAME     PU6000 5
 '@T6G_MB_LIB.T6G(SCH_1):PAGE315_I18@PURE_QUANTA.MPQ8626GDZ(CHIPS)':
 'EN': CDS_PINID='EN';
NODE_NAME     R6119 2
 '@T6G_MB_LIB.T6G(SCH_1):PAGE315_I40@PURE_QUANTA.Q_RES(CHIPS)':
 'B': CDS_PINID='B';
NODE_NAME     C345 1
 '@T6G_MB_LIB.T6G(SCH_1):PAGE315_I41@PURE_QUANTA.Q_CAP(CHIPS)':
 'A': CDS_PINID='A';
NET_NAME
'P1V8_AUX_FB'
 '@T6G_MB_LIB.T6G(SCH_1):P1V8_AUX_FB':
 C_SIGNAL='@t6g_mb_lib.t6g(sch_1):p1v8_aux_fb';
NODE_NAME     PU6000 6
 '@T6G_MB_LIB.T6G(SCH_1):PAGE315_I18@PURE_QUANTA.MPQ8626GDZ(CHIPS)':
 'FB': CDS_PINID='FB';
NODE_NAME     PR6010 1
 '@T6G_MB_LIB.T6G(SCH_1):PAGE315_I23@PURE_QUANTA.Q_RES(CHIPS)':
 'A': CDS_PINID='A';
NODE_NAME     PC6019 1
 '@T6G_MB_LIB.T6G(SCH_1):PAGE315_I26@PURE_QUANTA.Q_CAP(CHIPS)':
 'A': CDS_PINID='A';
NODE_NAME     PR6007 1
 '@T6G_MB_LIB.T6G(SCH_1):PAGE315_I28@PURE_QUANTA.Q_RES(CHIPS)':
 'A': CDS_PINID='A';
NET_NAME
'P1V8_AUX_MODE'
 '@T6G_MB_LIB.T6G(SCH_1):P1V8_AUX_MODE':
 C_SIGNAL='@t6g_mb_lib.t6g(sch_1):p1v8_aux_mode';
NODE_NAME     PR6006 2
 '@T6G_MB_LIB.T6G(SCH_1):PAGE315_I15@PURE_QUANTA.Q_RES(CHIPS)':
 'B': CDS_PINID='B';
NODE_NAME     PU6000 12
 '@T6G_MB_LIB.T6G(SCH_1):PAGE315_I18@PURE_QUANTA.MPQ8626GDZ(CHIPS)':
 'MODE': CDS_PINID='MODE';
NET_NAME
'P1V8_AUX_REF'
 '@T6G_MB_LIB.T6G(SCH_1):P1V8_AUX_REF':
 C_SIGNAL='@t6g_mb_lib.t6g(sch_1):p1v8_aux_ref';
NODE_NAME     PU6000 8
 '@T6G_MB_LIB.T6G(SCH_1):PAGE315_I18@PURE_QUANTA.MPQ8626GDZ(CHIPS)':
 'TRK_REF': CDS_PINID='TRK_REF';
NODE_NAME     PC384 1
 '@T6G_MB_LIB.T6G(SCH_1):PAGE315_I21@PURE_QUANTA.Q_CAP(CHIPS)':
 'A': CDS_PINID='A';
NET_NAME
'P1V8_AUX_VCC'
 '@T6G_MB_LIB.T6G(SCH_1):P1V8_AUX_VCC':
 C_SIGNAL='@t6g_mb_lib.t6g(sch_1):p1v8_aux_vcc';
NODE_NAME     R6242 2
 '@T6G_MB_LIB.T6G(SCH_1):PAGE315_I2@PURE_QUANTA.Q_RES(CHIPS)':
 'B': CDS_PINID='B';
NODE_NAME     PC6008 1
 '@T6G_MB_LIB.T6G(SCH_1):PAGE315_I13@PURE_QUANTA.Q_CAP(CHIPS)':
 'A': CDS_PINID='A';
NODE_NAME     PU6000 13
 '@T6G_MB_LIB.T6G(SCH_1):PAGE315_I18@PURE_QUANTA.MPQ8626GDZ(CHIPS)':
 'VCC': CDS_PINID='VCC';
NET_NAME
'P1V8_CPU0_RT0_1A'
 '@T6G_MB_LIB.T6G(SCH_1):P1V8_CPU0_RT0_1A':
 C_SIGNAL='@t6g_mb_lib.t6g(sch_1):p1v8_cpu0_rt0_1a',
 CDS_GLOBAL_NET='TRUE';
NODE_NAME     U6010 BV20
 '@T6G_MB_LIB.T6G(SCH_1):PAGE386_I3@PURE_QUANTA.PT5161LRS(CHIPS)':
 'PWR_1A_1': CDS_PINID='PWR_1A_1';
NODE_NAME     U6010 CE17
 '@T6G_MB_LIB.T6G(SCH_1):PAGE386_I3@PURE_QUANTA.PT5161LRS(CHIPS)':
 'PWR_1A_2': CDS_PINID='PWR_1A_2';
NODE_NAME     U6010 CE20
 '@T6G_MB_LIB.T6G(SCH_1):PAGE386_I3@PURE_QUANTA.PT5161LRS(CHIPS)':
 'PWR_1A_3': CDS_PINID='PWR_1A_3';
NODE_NAME     U6010 CM17
 '@T6G_MB_LIB.T6G(SCH_1):PAGE386_I3@PURE_QUANTA.PT5161LRS(CHIPS)':
 'PWR_1A_4': CDS_PINID='PWR_1A_4';
NODE_NAME     U6010 CM20
 '@T6G_MB_LIB.T6G(SCH_1):PAGE386_I3@PURE_QUANTA.PT5161LRS(CHIPS)':
 'PWR_1A_5': CDS_PINID='PWR_1A_5';
NODE_NAME     R952 2
 '@T6G_MB_LIB.T6G(SCH_1):PAGE388_I4@PURE_QUANTA.Q_RES(CHIPS)':
 'B': CDS_PINID='B';
NODE_NAME     R951 2
 '@T6G_MB_LIB.T6G(SCH_1):PAGE388_I5@PURE_QUANTA.Q_RES(CHIPS)':
 'B': CDS_PINID='B';
NODE_NAME     L11 2
 '@T6G_MB_LIB.T6G(SCH_1):PAGE388_I12@PURE_QUANTA.Q_INDUCTOR(CHIPS)':
 '2': CDS_PINID='\2\';
NODE_NAME     C503 1
 '@T6G_MB_LIB.T6G(SCH_1):PAGE388_I13@PURE_QUANTA.Q_CAP(CHIPS)':
 'A': CDS_PINID='A';
NODE_NAME     C505 1
 '@T6G_MB_LIB.T6G(SCH_1):PAGE388_I14@PURE_QUANTA.Q_CAP(CHIPS)':
 'A': CDS_PINID='A';
NODE_NAME     C507 1
 '@T6G_MB_LIB.T6G(SCH_1):PAGE388_I17@PURE_QUANTA.Q_CAP(CHIPS)':
 'A': CDS_PINID='A';
NODE_NAME     C510 1
 '@T6G_MB_LIB.T6G(SCH_1):PAGE388_I18@PURE_QUANTA.Q_CAP(CHIPS)':
 'A': CDS_PINID='A';
NODE_NAME     C512 1
 '@T6G_MB_LIB.T6G(SCH_1):PAGE388_I19@PURE_QUANTA.Q_CAP(CHIPS)':
 'A': CDS_PINID='A';
NODE_NAME     C514 1
 '@T6G_MB_LIB.T6G(SCH_1):PAGE388_I22@PURE_QUANTA.Q_CAP(CHIPS)':
 'A': CDS_PINID='A';
NODE_NAME     C515 1
 '@T6G_MB_LIB.T6G(SCH_1):PAGE388_I23@PURE_QUANTA.Q_CAP(CHIPS)':
 'A': CDS_PINID='A';
NODE_NAME     C517 1
 '@T6G_MB_LIB.T6G(SCH_1):PAGE388_I27@PURE_QUANTA.Q_CAP(CHIPS)':
 'A': CDS_PINID='A';
NODE_NAME     C519 1
 '@T6G_MB_LIB.T6G(SCH_1):PAGE388_I28@PURE_QUANTA.Q_CAP(CHIPS)':
 'A': CDS_PINID='A';
NODE_NAME     C520 1
 '@T6G_MB_LIB.T6G(SCH_1):PAGE388_I29@PURE_QUANTA.Q_CAP(CHIPS)':
 'A': CDS_PINID='A';
NET_NAME
'P1V8_CPU0_RT0_1A_1D'
 '@T6G_MB_LIB.T6G(SCH_1):P1V8_CPU0_RT0_1A_1D':
 C_SIGNAL='@t6g_mb_lib.t6g(sch_1):p1v8_cpu0_rt0_1a_1d',
 CDS_GLOBAL_NET='TRUE';
NODE_NAME     U6010 BV17
 '@T6G_MB_LIB.T6G(SCH_1):PAGE386_I3@PURE_QUANTA.PT5161LRS(CHIPS)':
 'PWR_1D': CDS_PINID='PWR_1D';
NODE_NAME     R952 1
 '@T6G_MB_LIB.T6G(SCH_1):PAGE388_I4@PURE_QUANTA.Q_RES(CHIPS)':
 'A': CDS_PINID='A';
NODE_NAME     R951 1
 '@T6G_MB_LIB.T6G(SCH_1):PAGE388_I5@PURE_QUANTA.Q_RES(CHIPS)':
 'A': CDS_PINID='A';
NODE_NAME     C513 1
 '@T6G_MB_LIB.T6G(SCH_1):PAGE388_I8@PURE_QUANTA.Q_CAP(CHIPS)':
 'A': CDS_PINID='A';
NODE_NAME     C516 1
 '@T6G_MB_LIB.T6G(SCH_1):PAGE388_I9@PURE_QUANTA.Q_CAP(CHIPS)':
 'A': CDS_PINID='A';
NODE_NAME     L26 2
 '@T6G_MB_LIB.T6G(SCH_1):PAGE388_I88@PURE_QUANTA.Q_INDUCTOR(CHIPS)':
 '2': CDS_PINID='\2\';
NODE_NAME     R960 2
 '@T6G_MB_LIB.T6G(SCH_1):PAGE388_I89@PURE_QUANTA.Q_RES(CHIPS)':
 'B': CDS_PINID='B';
NET_NAME
'P1V8_CPU0_RT1_1A'
 '@T6G_MB_LIB.T6G(SCH_1):P1V8_CPU0_RT1_1A':
 C_SIGNAL='@t6g_mb_lib.t6g(sch_1):p1v8_cpu0_rt1_1a',
 CDS_GLOBAL_NET='TRUE';
NODE_NAME     U6011 BV20
 '@T6G_MB_LIB.T6G(SCH_1):PAGE409_I5@PURE_QUANTA.PT5161LRS(CHIPS)':
 'PWR_1A_1': CDS_PINID='PWR_1A_1';
NODE_NAME     U6011 CE17
 '@T6G_MB_LIB.T6G(SCH_1):PAGE409_I5@PURE_QUANTA.PT5161LRS(CHIPS)':
 'PWR_1A_2': CDS_PINID='PWR_1A_2';
NODE_NAME     U6011 CE20
 '@T6G_MB_LIB.T6G(SCH_1):PAGE409_I5@PURE_QUANTA.PT5161LRS(CHIPS)':
 'PWR_1A_3': CDS_PINID='PWR_1A_3';
NODE_NAME     U6011 CM17
 '@T6G_MB_LIB.T6G(SCH_1):PAGE409_I5@PURE_QUANTA.PT5161LRS(CHIPS)':
 'PWR_1A_4': CDS_PINID='PWR_1A_4';
NODE_NAME     U6011 CM20
 '@T6G_MB_LIB.T6G(SCH_1):PAGE409_I5@PURE_QUANTA.PT5161LRS(CHIPS)':
 'PWR_1A_5': CDS_PINID='PWR_1A_5';
NODE_NAME     R1003 2
 '@T6G_MB_LIB.T6G(SCH_1):PAGE411_I2@PURE_QUANTA.Q_RES(CHIPS)':
 'B': CDS_PINID='B';
NODE_NAME     R1002 2
 '@T6G_MB_LIB.T6G(SCH_1):PAGE411_I4@PURE_QUANTA.Q_RES(CHIPS)':
 'B': CDS_PINID='B';
NODE_NAME     L13 2
 '@T6G_MB_LIB.T6G(SCH_1):PAGE411_I11@PURE_QUANTA.Q_INDUCTOR(CHIPS)':
 '2': CDS_PINID='\2\';
NODE_NAME     C588 1
 '@T6G_MB_LIB.T6G(SCH_1):PAGE411_I12@PURE_QUANTA.Q_CAP(CHIPS)':
 'A': CDS_PINID='A';
NODE_NAME     C590 1
 '@T6G_MB_LIB.T6G(SCH_1):PAGE411_I15@PURE_QUANTA.Q_CAP(CHIPS)':
 'A': CDS_PINID='A';
NODE_NAME     C595 1
 '@T6G_MB_LIB.T6G(SCH_1):PAGE411_I16@PURE_QUANTA.Q_CAP(CHIPS)':
 'A': CDS_PINID='A';
NODE_NAME     C594 1
 '@T6G_MB_LIB.T6G(SCH_1):PAGE411_I19@PURE_QUANTA.Q_CAP(CHIPS)':
 'A': CDS_PINID='A';
NODE_NAME     C597 1
 '@T6G_MB_LIB.T6G(SCH_1):PAGE411_I20@PURE_QUANTA.Q_CAP(CHIPS)':
 'A': CDS_PINID='A';
NODE_NAME     C599 1
 '@T6G_MB_LIB.T6G(SCH_1):PAGE411_I21@PURE_QUANTA.Q_CAP(CHIPS)':
 'A': CDS_PINID='A';
NODE_NAME     C600 1
 '@T6G_MB_LIB.T6G(SCH_1):PAGE411_I25@PURE_QUANTA.Q_CAP(CHIPS)':
 'A': CDS_PINID='A';
NODE_NAME     C602 1
 '@T6G_MB_LIB.T6G(SCH_1):PAGE411_I26@PURE_QUANTA.Q_CAP(CHIPS)':
 'A': CDS_PINID='A';
NODE_NAME     C603 1
 '@T6G_MB_LIB.T6G(SCH_1):PAGE411_I27@PURE_QUANTA.Q_CAP(CHIPS)':
 'A': CDS_PINID='A';
NODE_NAME     C606 1
 '@T6G_MB_LIB.T6G(SCH_1):PAGE411_I28@PURE_QUANTA.Q_CAP(CHIPS)':
 'A': CDS_PINID='A';
NET_NAME
'P1V8_CPU0_RT1_1A_1D'
 '@T6G_MB_LIB.T6G(SCH_1):P1V8_CPU0_RT1_1A_1D':
 C_SIGNAL='@t6g_mb_lib.t6g(sch_1):p1v8_cpu0_rt1_1a_1d',
 CDS_GLOBAL_NET='TRUE';
NODE_NAME     U6011 BV17
 '@T6G_MB_LIB.T6G(SCH_1):PAGE409_I5@PURE_QUANTA.PT5161LRS(CHIPS)':
 'PWR_1D': CDS_PINID='PWR_1D';
NODE_NAME     R1003 1
 '@T6G_MB_LIB.T6G(SCH_1):PAGE411_I2@PURE_QUANTA.Q_RES(CHIPS)':
 'A': CDS_PINID='A';
NODE_NAME     R1002 1
 '@T6G_MB_LIB.T6G(SCH_1):PAGE411_I4@PURE_QUANTA.Q_RES(CHIPS)':
 'A': CDS_PINID='A';
NODE_NAME     C598 1
 '@T6G_MB_LIB.T6G(SCH_1):PAGE411_I5@PURE_QUANTA.Q_CAP(CHIPS)':
 'A': CDS_PINID='A';
NODE_NAME     C601 1
 '@T6G_MB_LIB.T6G(SCH_1):PAGE411_I7@PURE_QUANTA.Q_CAP(CHIPS)':
 'A': CDS_PINID='A';
NODE_NAME     L28 2
 '@T6G_MB_LIB.T6G(SCH_1):PAGE411_I88@PURE_QUANTA.Q_INDUCTOR(CHIPS)':
 '2': CDS_PINID='\2\';
NODE_NAME     R1008 2
 '@T6G_MB_LIB.T6G(SCH_1):PAGE411_I89@PURE_QUANTA.Q_RES(CHIPS)':
 'B': CDS_PINID='B';
NET_NAME
'P1V8_CPU0_RT2_1A'
 '@T6G_MB_LIB.T6G(SCH_1):P1V8_CPU0_RT2_1A':
 C_SIGNAL='@t6g_mb_lib.t6g(sch_1):p1v8_cpu0_rt2_1a',
 CDS_GLOBAL_NET='TRUE';
NODE_NAME     U6012 BV20
 '@T6G_MB_LIB.T6G(SCH_1):PAGE420_I6@PURE_QUANTA.PT5161LRS(CHIPS)':
 'PWR_1A_1': CDS_PINID='PWR_1A_1';
NODE_NAME     U6012 CE17
 '@T6G_MB_LIB.T6G(SCH_1):PAGE420_I6@PURE_QUANTA.PT5161LRS(CHIPS)':
 'PWR_1A_2': CDS_PINID='PWR_1A_2';
NODE_NAME     U6012 CE20
 '@T6G_MB_LIB.T6G(SCH_1):PAGE420_I6@PURE_QUANTA.PT5161LRS(CHIPS)':
 'PWR_1A_3': CDS_PINID='PWR_1A_3';
NODE_NAME     U6012 CM17
 '@T6G_MB_LIB.T6G(SCH_1):PAGE420_I6@PURE_QUANTA.PT5161LRS(CHIPS)':
 'PWR_1A_4': CDS_PINID='PWR_1A_4';
NODE_NAME     U6012 CM20
 '@T6G_MB_LIB.T6G(SCH_1):PAGE420_I6@PURE_QUANTA.PT5161LRS(CHIPS)':
 'PWR_1A_5': CDS_PINID='PWR_1A_5';
NODE_NAME     R1046 2
 '@T6G_MB_LIB.T6G(SCH_1):PAGE422_I4@PURE_QUANTA.Q_RES(CHIPS)':
 'B': CDS_PINID='B';
NODE_NAME     R1045 2
 '@T6G_MB_LIB.T6G(SCH_1):PAGE422_I5@PURE_QUANTA.Q_RES(CHIPS)':
 'B': CDS_PINID='B';
NODE_NAME     C666 1
 '@T6G_MB_LIB.T6G(SCH_1):PAGE422_I6@PURE_QUANTA.Q_CAP(CHIPS)':
 'A': CDS_PINID='A';
NODE_NAME     C668 1
 '@T6G_MB_LIB.T6G(SCH_1):PAGE422_I7@PURE_QUANTA.Q_CAP(CHIPS)':
 'A': CDS_PINID='A';
NODE_NAME     C671 1
 '@T6G_MB_LIB.T6G(SCH_1):PAGE422_I12@PURE_QUANTA.Q_CAP(CHIPS)':
 'A': CDS_PINID='A';
NODE_NAME     C670 1
 '@T6G_MB_LIB.T6G(SCH_1):PAGE422_I13@PURE_QUANTA.Q_CAP(CHIPS)':
 'A': CDS_PINID='A';
NODE_NAME     C673 1
 '@T6G_MB_LIB.T6G(SCH_1):PAGE422_I15@PURE_QUANTA.Q_CAP(CHIPS)':
 'A': CDS_PINID='A';
NODE_NAME     C677 1
 '@T6G_MB_LIB.T6G(SCH_1):PAGE422_I16@PURE_QUANTA.Q_CAP(CHIPS)':
 'A': CDS_PINID='A';
NODE_NAME     C774 1
 '@T6G_MB_LIB.T6G(SCH_1):PAGE422_I17@PURE_QUANTA.Q_CAP(CHIPS)':
 'A': CDS_PINID='A';
NODE_NAME     C776 1
 '@T6G_MB_LIB.T6G(SCH_1):PAGE422_I18@PURE_QUANTA.Q_CAP(CHIPS)':
 'A': CDS_PINID='A';
NODE_NAME     C777 1
 '@T6G_MB_LIB.T6G(SCH_1):PAGE422_I19@PURE_QUANTA.Q_CAP(CHIPS)':
 'A': CDS_PINID='A';
NODE_NAME     C778 1
 '@T6G_MB_LIB.T6G(SCH_1):PAGE422_I20@PURE_QUANTA.Q_CAP(CHIPS)':
 'A': CDS_PINID='A';
NODE_NAME     L18 2
 '@T6G_MB_LIB.T6G(SCH_1):PAGE422_I23@PURE_QUANTA.Q_INDUCTOR(CHIPS)':
 '2': CDS_PINID='\2\';
NET_NAME
'P1V8_CPU0_RT2_1A_1D'
 '@T6G_MB_LIB.T6G(SCH_1):P1V8_CPU0_RT2_1A_1D':
 C_SIGNAL='@t6g_mb_lib.t6g(sch_1):p1v8_cpu0_rt2_1a_1d',
 CDS_GLOBAL_NET='TRUE';
NODE_NAME     U6012 BV17
 '@T6G_MB_LIB.T6G(SCH_1):PAGE420_I6@PURE_QUANTA.PT5161LRS(CHIPS)':
 'PWR_1D': CDS_PINID='PWR_1D';
NODE_NAME     R1046 1
 '@T6G_MB_LIB.T6G(SCH_1):PAGE422_I4@PURE_QUANTA.Q_RES(CHIPS)':
 'A': CDS_PINID='A';
NODE_NAME     R1045 1
 '@T6G_MB_LIB.T6G(SCH_1):PAGE422_I5@PURE_QUANTA.Q_RES(CHIPS)':
 'A': CDS_PINID='A';
NODE_NAME     C676 1
 '@T6G_MB_LIB.T6G(SCH_1):PAGE422_I9@PURE_QUANTA.Q_CAP(CHIPS)':
 'A': CDS_PINID='A';
NODE_NAME     C775 1
 '@T6G_MB_LIB.T6G(SCH_1):PAGE422_I10@PURE_QUANTA.Q_CAP(CHIPS)':
 'A': CDS_PINID='A';
NODE_NAME     L29 2
 '@T6G_MB_LIB.T6G(SCH_1):PAGE422_I88@PURE_QUANTA.Q_INDUCTOR(CHIPS)':
 '2': CDS_PINID='\2\';
NODE_NAME     R1050 2
 '@T6G_MB_LIB.T6G(SCH_1):PAGE422_I89@PURE_QUANTA.Q_RES(CHIPS)':
 'B': CDS_PINID='B';
NET_NAME
'P1V8_CPU0_RT3_1A'
 '@T6G_MB_LIB.T6G(SCH_1):P1V8_CPU0_RT3_1A':
 C_SIGNAL='@t6g_mb_lib.t6g(sch_1):p1v8_cpu0_rt3_1a',
 CDS_GLOBAL_NET='TRUE';
NODE_NAME     U6013 BV20
 '@T6G_MB_LIB.T6G(SCH_1):PAGE431_I6@PURE_QUANTA.PT5161LRS(CHIPS)':
 'PWR_1A_1': CDS_PINID='PWR_1A_1';
NODE_NAME     U6013 CE17
 '@T6G_MB_LIB.T6G(SCH_1):PAGE431_I6@PURE_QUANTA.PT5161LRS(CHIPS)':
 'PWR_1A_2': CDS_PINID='PWR_1A_2';
NODE_NAME     U6013 CE20
 '@T6G_MB_LIB.T6G(SCH_1):PAGE431_I6@PURE_QUANTA.PT5161LRS(CHIPS)':
 'PWR_1A_3': CDS_PINID='PWR_1A_3';
NODE_NAME     U6013 CM17
 '@T6G_MB_LIB.T6G(SCH_1):PAGE431_I6@PURE_QUANTA.PT5161LRS(CHIPS)':
 'PWR_1A_4': CDS_PINID='PWR_1A_4';
NODE_NAME     U6013 CM20
 '@T6G_MB_LIB.T6G(SCH_1):PAGE431_I6@PURE_QUANTA.PT5161LRS(CHIPS)':
 'PWR_1A_5': CDS_PINID='PWR_1A_5';
NODE_NAME     R1087 2
 '@T6G_MB_LIB.T6G(SCH_1):PAGE433_I1@PURE_QUANTA.Q_RES(CHIPS)':
 'B': CDS_PINID='B';
NODE_NAME     R1086 2
 '@T6G_MB_LIB.T6G(SCH_1):PAGE433_I2@PURE_QUANTA.Q_RES(CHIPS)':
 'B': CDS_PINID='B';
NODE_NAME     L22 2
 '@T6G_MB_LIB.T6G(SCH_1):PAGE433_I10@PURE_QUANTA.Q_INDUCTOR(CHIPS)':
 '2': CDS_PINID='\2\';
NODE_NAME     C991 1
 '@T6G_MB_LIB.T6G(SCH_1):PAGE433_I12@PURE_QUANTA.Q_CAP(CHIPS)':
 'A': CDS_PINID='A';
NODE_NAME     C993 1
 '@T6G_MB_LIB.T6G(SCH_1):PAGE433_I13@PURE_QUANTA.Q_CAP(CHIPS)':
 'A': CDS_PINID='A';
NODE_NAME     C995 1
 '@T6G_MB_LIB.T6G(SCH_1):PAGE433_I15@PURE_QUANTA.Q_CAP(CHIPS)':
 'A': CDS_PINID='A';
NODE_NAME     C996 1
 '@T6G_MB_LIB.T6G(SCH_1):PAGE433_I16@PURE_QUANTA.Q_CAP(CHIPS)':
 'A': CDS_PINID='A';
NODE_NAME     C998 1
 '@T6G_MB_LIB.T6G(SCH_1):PAGE433_I17@PURE_QUANTA.Q_CAP(CHIPS)':
 'A': CDS_PINID='A';
NODE_NAME     C1000 1
 '@T6G_MB_LIB.T6G(SCH_1):PAGE433_I24@PURE_QUANTA.Q_CAP(CHIPS)':
 'A': CDS_PINID='A';
NODE_NAME     C1001 1
 '@T6G_MB_LIB.T6G(SCH_1):PAGE433_I25@PURE_QUANTA.Q_CAP(CHIPS)':
 'A': CDS_PINID='A';
NODE_NAME     C1003 1
 '@T6G_MB_LIB.T6G(SCH_1):PAGE433_I26@PURE_QUANTA.Q_CAP(CHIPS)':
 'A': CDS_PINID='A';
NODE_NAME     C1004 1
 '@T6G_MB_LIB.T6G(SCH_1):PAGE433_I27@PURE_QUANTA.Q_CAP(CHIPS)':
 'A': CDS_PINID='A';
NODE_NAME     C1005 1
 '@T6G_MB_LIB.T6G(SCH_1):PAGE433_I28@PURE_QUANTA.Q_CAP(CHIPS)':
 'A': CDS_PINID='A';
NET_NAME
'P1V8_CPU0_RT3_1A_1D'
 '@T6G_MB_LIB.T6G(SCH_1):P1V8_CPU0_RT3_1A_1D':
 C_SIGNAL='@t6g_mb_lib.t6g(sch_1):p1v8_cpu0_rt3_1a_1d',
 CDS_GLOBAL_NET='TRUE';
NODE_NAME     U6013 BV17
 '@T6G_MB_LIB.T6G(SCH_1):PAGE431_I6@PURE_QUANTA.PT5161LRS(CHIPS)':
 'PWR_1D': CDS_PINID='PWR_1D';
NODE_NAME     R1087 1
 '@T6G_MB_LIB.T6G(SCH_1):PAGE433_I1@PURE_QUANTA.Q_RES(CHIPS)':
 'A': CDS_PINID='A';
NODE_NAME     R1086 1
 '@T6G_MB_LIB.T6G(SCH_1):PAGE433_I2@PURE_QUANTA.Q_RES(CHIPS)':
 'A': CDS_PINID='A';
NODE_NAME     C999 1
 '@T6G_MB_LIB.T6G(SCH_1):PAGE433_I5@PURE_QUANTA.Q_CAP(CHIPS)':
 'A': CDS_PINID='A';
NODE_NAME     C1002 1
 '@T6G_MB_LIB.T6G(SCH_1):PAGE433_I6@PURE_QUANTA.Q_CAP(CHIPS)':
 'A': CDS_PINID='A';
NODE_NAME     L30 2
 '@T6G_MB_LIB.T6G(SCH_1):PAGE433_I88@PURE_QUANTA.Q_INDUCTOR(CHIPS)':
 '2': CDS_PINID='\2\';
NODE_NAME     R1093 2
 '@T6G_MB_LIB.T6G(SCH_1):PAGE433_I89@PURE_QUANTA.Q_RES(CHIPS)':
 'B': CDS_PINID='B';
NET_NAME
'P1V8_CPU0_RT_1D'
 '@T6G_MB_LIB.T6G(SCH_1):P1V8_CPU0_RT_1D':
 C_SIGNAL='@t6g_mb_lib.t6g(sch_1):p1v8_cpu0_rt_1d',
 CDS_GLOBAL_NET='TRUE';
NODE_NAME     R1105 1
 '@T6G_MB_LIB.T6G(SCH_1):PAGE430_I5@PURE_QUANTA.Q_RES(CHIPS)':
 'A': CDS_PINID='A';
NODE_NAME     U11 8
 '@T6G_MB_LIB.T6G(SCH_1):PAGE387_I3@PURE_QUANTA.M24M02DRMN6TP(CHIPS)':
 'VCC': CDS_PINID='VCC';
NODE_NAME     U15 8
 '@T6G_MB_LIB.T6G(SCH_1):PAGE410_I5@PURE_QUANTA.M24M02DRMN6TP(CHIPS)':
 'VCC': CDS_PINID='VCC';
NODE_NAME     U16 8
 '@T6G_MB_LIB.T6G(SCH_1):PAGE421_I5@PURE_QUANTA.M24M02DRMN6TP(CHIPS)':
 'VCC': CDS_PINID='VCC';
NODE_NAME     U17 8
 '@T6G_MB_LIB.T6G(SCH_1):PAGE432_I5@PURE_QUANTA.M24M02DRMN6TP(CHIPS)':
 'VCC': CDS_PINID='VCC';
NODE_NAME     PC6515 2
 '@T6G_MB_LIB.T6G(SCH_1):PAGE469_I34@PURE_QUANTA.Q_CAP(CHIPS)':
 'B': CDS_PINID='B';
NODE_NAME     PR6505 2
 '@T6G_MB_LIB.T6G(SCH_1):PAGE469_I35@PURE_QUANTA.Q_RES(CHIPS)':
 'B': CDS_PINID='B';
NODE_NAME     PL6501 2
 '@T6G_MB_LIB.T6G(SCH_1):PAGE469_I36@PURE_QUANTA.Q_INDUCTOR(CHIPS)':
 '2': CDS_PINID='\2\';
NODE_NAME     PC6508 1
 '@T6G_MB_LIB.T6G(SCH_1):PAGE469_I38@PURE_QUANTA.Q_CAP(CHIPS)':
 'A': CDS_PINID='A';
NODE_NAME     PC6509 1
 '@T6G_MB_LIB.T6G(SCH_1):PAGE469_I39@PURE_QUANTA.Q_CAP(CHIPS)':
 'A': CDS_PINID='A';
NODE_NAME     PC6510 1
 '@T6G_MB_LIB.T6G(SCH_1):PAGE469_I40@PURE_QUANTA.Q_CAP(CHIPS)':
 'A': CDS_PINID='A';
NODE_NAME     PC6511 1
 '@T6G_MB_LIB.T6G(SCH_1):PAGE469_I44@PURE_QUANTA.Q_CAP(CHIPS)':
 'A': CDS_PINID='A';
NODE_NAME     PC6513 1
 '@T6G_MB_LIB.T6G(SCH_1):PAGE469_I46@PURE_QUANTA.Q_CAPP(CHIPS)':
 'A': CDS_PINID='A';
NODE_NAME     PC6805 1
 '@T6G_MB_LIB.T6G(SCH_1):PAGE469_I48@PURE_QUANTA.Q_CAPP(CHIPS)':
 'A': CDS_PINID='A';
NODE_NAME     PC6514 1
 '@T6G_MB_LIB.T6G(SCH_1):PAGE469_I49@PURE_QUANTA.Q_CAP(CHIPS)':
 'A': CDS_PINID='A';
NODE_NAME     PC6512 1
 '@T6G_MB_LIB.T6G(SCH_1):PAGE469_I52@PURE_QUANTA.Q_CAP(CHIPS)':
 'A': CDS_PINID='A';
NODE_NAME     R6762 1
 '@T6G_MB_LIB.T6G(SCH_1):PAGE378_I77@PURE_QUANTA.Q_RES(CHIPS)':
 'A': CDS_PINID='A';
NODE_NAME     R6763 1
 '@T6G_MB_LIB.T6G(SCH_1):PAGE378_I78@PURE_QUANTA.Q_RES(CHIPS)':
 'A': CDS_PINID='A';
NODE_NAME     R6764 1
 '@T6G_MB_LIB.T6G(SCH_1):PAGE378_I79@PURE_QUANTA.Q_RES(CHIPS)':
 'A': CDS_PINID='A';
NODE_NAME     R6765 1
 '@T6G_MB_LIB.T6G(SCH_1):PAGE378_I80@PURE_QUANTA.Q_RES(CHIPS)':
 'A': CDS_PINID='A';
NODE_NAME     R6767 1
 '@T6G_MB_LIB.T6G(SCH_1):PAGE378_I82@PURE_QUANTA.Q_RES(CHIPS)':
 'A': CDS_PINID='A';
NODE_NAME     R6766 1
 '@T6G_MB_LIB.T6G(SCH_1):PAGE378_I83@PURE_QUANTA.Q_RES(CHIPS)':
 'A': CDS_PINID='A';
NODE_NAME     R6768 1
 '@T6G_MB_LIB.T6G(SCH_1):PAGE378_I84@PURE_QUANTA.Q_RES(CHIPS)':
 'A': CDS_PINID='A';
NODE_NAME     R6769 1
 '@T6G_MB_LIB.T6G(SCH_1):PAGE378_I85@PURE_QUANTA.Q_RES(CHIPS)':
 'A': CDS_PINID='A';
NODE_NAME     R841 1
 '@T6G_MB_LIB.T6G(SCH_1):PAGE377_I17@PURE_QUANTA.Q_RES(CHIPS)':
 'A': CDS_PINID='A';
NODE_NAME     R840 1
 '@T6G_MB_LIB.T6G(SCH_1):PAGE377_I18@PURE_QUANTA.Q_RES(CHIPS)':
 'A': CDS_PINID='A';
NODE_NAME     R838 1
 '@T6G_MB_LIB.T6G(SCH_1):PAGE377_I19@PURE_QUANTA.Q_RES(CHIPS)':
 'A': CDS_PINID='A';
NODE_NAME     R839 1
 '@T6G_MB_LIB.T6G(SCH_1):PAGE377_I20@PURE_QUANTA.Q_RES(CHIPS)':
 'A': CDS_PINID='A';
NODE_NAME     R837 1
 '@T6G_MB_LIB.T6G(SCH_1):PAGE377_I21@PURE_QUANTA.Q_RES(CHIPS)':
 'A': CDS_PINID='A';
NODE_NAME     R836 1
 '@T6G_MB_LIB.T6G(SCH_1):PAGE377_I22@PURE_QUANTA.Q_RES(CHIPS)':
 'A': CDS_PINID='A';
NODE_NAME     R835 1
 '@T6G_MB_LIB.T6G(SCH_1):PAGE377_I23@PURE_QUANTA.Q_RES(CHIPS)':
 'A': CDS_PINID='A';
NODE_NAME     R834 1
 '@T6G_MB_LIB.T6G(SCH_1):PAGE377_I24@PURE_QUANTA.Q_RES(CHIPS)':
 'A': CDS_PINID='A';
NODE_NAME     R972 1
 '@T6G_MB_LIB.T6G(SCH_1):PAGE385_I25@PURE_QUANTA.Q_RES(CHIPS)':
 'A': CDS_PINID='A';
NODE_NAME     R978 1
 '@T6G_MB_LIB.T6G(SCH_1):PAGE385_I30@PURE_QUANTA.Q_RES(CHIPS)':
 'A': CDS_PINID='A';
NODE_NAME     R981 1
 '@T6G_MB_LIB.T6G(SCH_1):PAGE385_I31@PURE_QUANTA.Q_RES(CHIPS)':
 'A': CDS_PINID='A';
NODE_NAME     R983 1
 '@T6G_MB_LIB.T6G(SCH_1):PAGE385_I61@PURE_QUANTA.Q_RES(CHIPS)':
 'A': CDS_PINID='A';
NODE_NAME     R985 1
 '@T6G_MB_LIB.T6G(SCH_1):PAGE385_I62@PURE_QUANTA.Q_RES(CHIPS)':
 'A': CDS_PINID='A';
NODE_NAME     R975 1
 '@T6G_MB_LIB.T6G(SCH_1):PAGE385_I63@PURE_QUANTA.Q_RES(CHIPS)':
 'A': CDS_PINID='A';
NODE_NAME     R998 1
 '@T6G_MB_LIB.T6G(SCH_1):PAGE385_I72@PURE_QUANTA.Q_RES(CHIPS)':
 'A': CDS_PINID='A';
NODE_NAME     R964 1
 '@T6G_MB_LIB.T6G(SCH_1):PAGE385_I88@PURE_QUANTA.Q_RES(CHIPS)':
 'A': CDS_PINID='A';
NODE_NAME     R966 1
 '@T6G_MB_LIB.T6G(SCH_1):PAGE385_I89@PURE_QUANTA.Q_RES(CHIPS)':
 'A': CDS_PINID='A';
NODE_NAME     R968 1
 '@T6G_MB_LIB.T6G(SCH_1):PAGE385_I91@PURE_QUANTA.Q_RES(CHIPS)':
 'A': CDS_PINID='A';
NODE_NAME     R974 1
 '@T6G_MB_LIB.T6G(SCH_1):PAGE385_I98@PURE_QUANTA.Q_RES(CHIPS)':
 'A': CDS_PINID='A';
NODE_NAME     C7510 1
 '@T6G_MB_LIB.T6G(SCH_1):PAGE387_I21@PURE_QUANTA.Q_CAP(CHIPS)':
 'A': CDS_PINID='A';
NODE_NAME     L11 1
 '@T6G_MB_LIB.T6G(SCH_1):PAGE388_I12@PURE_QUANTA.Q_INDUCTOR(CHIPS)':
 '1': CDS_PINID='\1\';
NODE_NAME     C502 1
 '@T6G_MB_LIB.T6G(SCH_1):PAGE388_I16@PURE_QUANTA.Q_CAP(CHIPS)':
 'A': CDS_PINID='A';
NODE_NAME     C504 1
 '@T6G_MB_LIB.T6G(SCH_1):PAGE388_I24@PURE_QUANTA.Q_CAP(CHIPS)':
 'A': CDS_PINID='A';
NODE_NAME     C506 1
 '@T6G_MB_LIB.T6G(SCH_1):PAGE388_I25@PURE_QUANTA.Q_CAP(CHIPS)':
 'A': CDS_PINID='A';
NODE_NAME     C511 1
 '@T6G_MB_LIB.T6G(SCH_1):PAGE388_I26@PURE_QUANTA.Q_CAP(CHIPS)':
 'A': CDS_PINID='A';
NODE_NAME     R1021 1
 '@T6G_MB_LIB.T6G(SCH_1):PAGE408_I5@PURE_QUANTA.Q_RES(CHIPS)':
 'A': CDS_PINID='A';
NODE_NAME     R1027 1
 '@T6G_MB_LIB.T6G(SCH_1):PAGE408_I10@PURE_QUANTA.Q_RES(CHIPS)':
 'A': CDS_PINID='A';
NODE_NAME     R1030 1
 '@T6G_MB_LIB.T6G(SCH_1):PAGE408_I11@PURE_QUANTA.Q_RES(CHIPS)':
 'A': CDS_PINID='A';
NODE_NAME     R1032 1
 '@T6G_MB_LIB.T6G(SCH_1):PAGE408_I40@PURE_QUANTA.Q_RES(CHIPS)':
 'A': CDS_PINID='A';
NODE_NAME     R1034 1
 '@T6G_MB_LIB.T6G(SCH_1):PAGE408_I41@PURE_QUANTA.Q_RES(CHIPS)':
 'A': CDS_PINID='A';
NODE_NAME     R1024 1
 '@T6G_MB_LIB.T6G(SCH_1):PAGE408_I42@PURE_QUANTA.Q_RES(CHIPS)':
 'A': CDS_PINID='A';
NODE_NAME     R1039 1
 '@T6G_MB_LIB.T6G(SCH_1):PAGE408_I51@PURE_QUANTA.Q_RES(CHIPS)':
 'A': CDS_PINID='A';
NODE_NAME     R1013 1
 '@T6G_MB_LIB.T6G(SCH_1):PAGE408_I66@PURE_QUANTA.Q_RES(CHIPS)':
 'A': CDS_PINID='A';
NODE_NAME     R1015 1
 '@T6G_MB_LIB.T6G(SCH_1):PAGE408_I67@PURE_QUANTA.Q_RES(CHIPS)':
 'A': CDS_PINID='A';
NODE_NAME     R1017 1
 '@T6G_MB_LIB.T6G(SCH_1):PAGE408_I69@PURE_QUANTA.Q_RES(CHIPS)':
 'A': CDS_PINID='A';
NODE_NAME     R1023 1
 '@T6G_MB_LIB.T6G(SCH_1):PAGE408_I78@PURE_QUANTA.Q_RES(CHIPS)':
 'A': CDS_PINID='A';
NODE_NAME     C664 1
 '@T6G_MB_LIB.T6G(SCH_1):PAGE410_I24@PURE_QUANTA.Q_CAP(CHIPS)':
 'A': CDS_PINID='A';
NODE_NAME     L13 1
 '@T6G_MB_LIB.T6G(SCH_1):PAGE411_I11@PURE_QUANTA.Q_INDUCTOR(CHIPS)':
 '1': CDS_PINID='\1\';
NODE_NAME     C587 1
 '@T6G_MB_LIB.T6G(SCH_1):PAGE411_I17@PURE_QUANTA.Q_CAP(CHIPS)':
 'A': CDS_PINID='A';
NODE_NAME     C589 1
 '@T6G_MB_LIB.T6G(SCH_1):PAGE411_I18@PURE_QUANTA.Q_CAP(CHIPS)':
 'A': CDS_PINID='A';
NODE_NAME     C591 1
 '@T6G_MB_LIB.T6G(SCH_1):PAGE411_I22@PURE_QUANTA.Q_CAP(CHIPS)':
 'A': CDS_PINID='A';
NODE_NAME     C596 1
 '@T6G_MB_LIB.T6G(SCH_1):PAGE411_I24@PURE_QUANTA.Q_CAP(CHIPS)':
 'A': CDS_PINID='A';
NODE_NAME     R1063 1
 '@T6G_MB_LIB.T6G(SCH_1):PAGE419_I5@PURE_QUANTA.Q_RES(CHIPS)':
 'A': CDS_PINID='A';
NODE_NAME     R1069 1
 '@T6G_MB_LIB.T6G(SCH_1):PAGE419_I10@PURE_QUANTA.Q_RES(CHIPS)':
 'A': CDS_PINID='A';
NODE_NAME     R1073 1
 '@T6G_MB_LIB.T6G(SCH_1):PAGE419_I11@PURE_QUANTA.Q_RES(CHIPS)':
 'A': CDS_PINID='A';
NODE_NAME     R1075 1
 '@T6G_MB_LIB.T6G(SCH_1):PAGE419_I40@PURE_QUANTA.Q_RES(CHIPS)':
 'A': CDS_PINID='A';
NODE_NAME     R1077 1
 '@T6G_MB_LIB.T6G(SCH_1):PAGE419_I41@PURE_QUANTA.Q_RES(CHIPS)':
 'A': CDS_PINID='A';
NODE_NAME     R1066 1
 '@T6G_MB_LIB.T6G(SCH_1):PAGE419_I42@PURE_QUANTA.Q_RES(CHIPS)':
 'A': CDS_PINID='A';
NODE_NAME     R1080 1
 '@T6G_MB_LIB.T6G(SCH_1):PAGE419_I51@PURE_QUANTA.Q_RES(CHIPS)':
 'A': CDS_PINID='A';
NODE_NAME     R1055 1
 '@T6G_MB_LIB.T6G(SCH_1):PAGE419_I67@PURE_QUANTA.Q_RES(CHIPS)':
 'A': CDS_PINID='A';
NODE_NAME     R1057 1
 '@T6G_MB_LIB.T6G(SCH_1):PAGE419_I68@PURE_QUANTA.Q_RES(CHIPS)':
 'A': CDS_PINID='A';
NODE_NAME     R1059 1
 '@T6G_MB_LIB.T6G(SCH_1):PAGE419_I70@PURE_QUANTA.Q_RES(CHIPS)':
 'A': CDS_PINID='A';
NODE_NAME     R1065 1
 '@T6G_MB_LIB.T6G(SCH_1):PAGE419_I78@PURE_QUANTA.Q_RES(CHIPS)':
 'A': CDS_PINID='A';
NODE_NAME     C989 1
 '@T6G_MB_LIB.T6G(SCH_1):PAGE421_I23@PURE_QUANTA.Q_CAP(CHIPS)':
 'A': CDS_PINID='A';
NODE_NAME     L18 1
 '@T6G_MB_LIB.T6G(SCH_1):PAGE422_I23@PURE_QUANTA.Q_INDUCTOR(CHIPS)':
 '1': CDS_PINID='\1\';
NODE_NAME     C665 1
 '@T6G_MB_LIB.T6G(SCH_1):PAGE422_I25@PURE_QUANTA.Q_CAP(CHIPS)':
 'A': CDS_PINID='A';
NODE_NAME     C669 1
 '@T6G_MB_LIB.T6G(SCH_1):PAGE422_I26@PURE_QUANTA.Q_CAP(CHIPS)':
 'A': CDS_PINID='A';
NODE_NAME     C667 1
 '@T6G_MB_LIB.T6G(SCH_1):PAGE422_I27@PURE_QUANTA.Q_CAP(CHIPS)':
 'A': CDS_PINID='A';
NODE_NAME     C672 1
 '@T6G_MB_LIB.T6G(SCH_1):PAGE422_I29@PURE_QUANTA.Q_CAP(CHIPS)':
 'A': CDS_PINID='A';
NODE_NAME     R1111 1
 '@T6G_MB_LIB.T6G(SCH_1):PAGE430_I10@PURE_QUANTA.Q_RES(CHIPS)':
 'A': CDS_PINID='A';
NODE_NAME     R1114 1
 '@T6G_MB_LIB.T6G(SCH_1):PAGE430_I11@PURE_QUANTA.Q_RES(CHIPS)':
 'A': CDS_PINID='A';
NODE_NAME     R1116 1
 '@T6G_MB_LIB.T6G(SCH_1):PAGE430_I40@PURE_QUANTA.Q_RES(CHIPS)':
 'A': CDS_PINID='A';
NODE_NAME     R1119 1
 '@T6G_MB_LIB.T6G(SCH_1):PAGE430_I41@PURE_QUANTA.Q_RES(CHIPS)':
 'A': CDS_PINID='A';
NODE_NAME     R1108 1
 '@T6G_MB_LIB.T6G(SCH_1):PAGE430_I42@PURE_QUANTA.Q_RES(CHIPS)':
 'A': CDS_PINID='A';
NODE_NAME     R1122 1
 '@T6G_MB_LIB.T6G(SCH_1):PAGE430_I51@PURE_QUANTA.Q_RES(CHIPS)':
 'A': CDS_PINID='A';
NODE_NAME     R1097 1
 '@T6G_MB_LIB.T6G(SCH_1):PAGE430_I67@PURE_QUANTA.Q_RES(CHIPS)':
 'A': CDS_PINID='A';
NODE_NAME     R1099 1
 '@T6G_MB_LIB.T6G(SCH_1):PAGE430_I68@PURE_QUANTA.Q_RES(CHIPS)':
 'A': CDS_PINID='A';
NODE_NAME     R1101 1
 '@T6G_MB_LIB.T6G(SCH_1):PAGE430_I70@PURE_QUANTA.Q_RES(CHIPS)':
 'A': CDS_PINID='A';
NODE_NAME     R1107 1
 '@T6G_MB_LIB.T6G(SCH_1):PAGE430_I79@PURE_QUANTA.Q_RES(CHIPS)':
 'A': CDS_PINID='A';
NODE_NAME     C1057 1
 '@T6G_MB_LIB.T6G(SCH_1):PAGE432_I23@PURE_QUANTA.Q_CAP(CHIPS)':
 'A': CDS_PINID='A';
NODE_NAME     L22 1
 '@T6G_MB_LIB.T6G(SCH_1):PAGE433_I10@PURE_QUANTA.Q_INDUCTOR(CHIPS)':
 '1': CDS_PINID='\1\';
NODE_NAME     C990 1
 '@T6G_MB_LIB.T6G(SCH_1):PAGE433_I19@PURE_QUANTA.Q_CAP(CHIPS)':
 'A': CDS_PINID='A';
NODE_NAME     C992 1
 '@T6G_MB_LIB.T6G(SCH_1):PAGE433_I20@PURE_QUANTA.Q_CAP(CHIPS)':
 'A': CDS_PINID='A';
NODE_NAME     C994 1
 '@T6G_MB_LIB.T6G(SCH_1):PAGE433_I21@PURE_QUANTA.Q_CAP(CHIPS)':
 'A': CDS_PINID='A';
NODE_NAME     C997 1
 '@T6G_MB_LIB.T6G(SCH_1):PAGE433_I22@PURE_QUANTA.Q_CAP(CHIPS)':
 'A': CDS_PINID='A';
NODE_NAME     R1231 1
 '@T6G_MB_LIB.T6G(SCH_1):PAGE263_I191@PURE_QUANTA.Q_RES(CHIPS)':
 'A': CDS_PINID='A';
NODE_NAME     R1369 1
 '@T6G_MB_LIB.T6G(SCH_1):PAGE385_I116@PURE_QUANTA.Q_RES(CHIPS)':
 'A': CDS_PINID='A';
NODE_NAME     R1397 1
 '@T6G_MB_LIB.T6G(SCH_1):PAGE408_I99@PURE_QUANTA.Q_RES(CHIPS)':
 'A': CDS_PINID='A';
NODE_NAME     R1405 1
 '@T6G_MB_LIB.T6G(SCH_1):PAGE419_I96@PURE_QUANTA.Q_RES(CHIPS)':
 'A': CDS_PINID='A';
NODE_NAME     R1413 1
 '@T6G_MB_LIB.T6G(SCH_1):PAGE430_I97@PURE_QUANTA.Q_RES(CHIPS)':
 'A': CDS_PINID='A';
NODE_NAME     R6808 1
 '@T6G_MB_LIB.T6G(SCH_1):PAGE386_I19@PURE_QUANTA.Q_RES(CHIPS)':
 'A': CDS_PINID='A';
NODE_NAME     R1040 1
 '@T6G_MB_LIB.T6G(SCH_1):PAGE409_I19@PURE_QUANTA.Q_RES(CHIPS)':
 'A': CDS_PINID='A';
NODE_NAME     R1081 1
 '@T6G_MB_LIB.T6G(SCH_1):PAGE420_I19@PURE_QUANTA.Q_RES(CHIPS)':
 'A': CDS_PINID='A';
NODE_NAME     R1123 1
 '@T6G_MB_LIB.T6G(SCH_1):PAGE431_I19@PURE_QUANTA.Q_RES(CHIPS)':
 'A': CDS_PINID='A';
NODE_NAME     R1446 1
 '@T6G_MB_LIB.T6G(SCH_1):PAGE385_I143@PURE_QUANTA.Q_RES(CHIPS)':
 'A': CDS_PINID='A';
NODE_NAME     R1445 1
 '@T6G_MB_LIB.T6G(SCH_1):PAGE385_I145@PURE_QUANTA.Q_RES(CHIPS)':
 'A': CDS_PINID='A';
NODE_NAME     R1439 1
 '@T6G_MB_LIB.T6G(SCH_1):PAGE385_I146@PURE_QUANTA.Q_RES(CHIPS)':
 'A': CDS_PINID='A';
NODE_NAME     R1438 1
 '@T6G_MB_LIB.T6G(SCH_1):PAGE385_I147@PURE_QUANTA.Q_RES(CHIPS)':
 'A': CDS_PINID='A';
NODE_NAME     R1470 1
 '@T6G_MB_LIB.T6G(SCH_1):PAGE408_I115@PURE_QUANTA.Q_RES(CHIPS)':
 'A': CDS_PINID='A';
NODE_NAME     R1471 1
 '@T6G_MB_LIB.T6G(SCH_1):PAGE408_I116@PURE_QUANTA.Q_RES(CHIPS)':
 'A': CDS_PINID='A';
NODE_NAME     R1472 1
 '@T6G_MB_LIB.T6G(SCH_1):PAGE408_I121@PURE_QUANTA.Q_RES(CHIPS)':
 'A': CDS_PINID='A';
NODE_NAME     R1473 1
 '@T6G_MB_LIB.T6G(SCH_1):PAGE408_I122@PURE_QUANTA.Q_RES(CHIPS)':
 'A': CDS_PINID='A';
NODE_NAME     R1476 1
 '@T6G_MB_LIB.T6G(SCH_1):PAGE419_I116@PURE_QUANTA.Q_RES(CHIPS)':
 'A': CDS_PINID='A';
NODE_NAME     R1477 1
 '@T6G_MB_LIB.T6G(SCH_1):PAGE419_I117@PURE_QUANTA.Q_RES(CHIPS)':
 'A': CDS_PINID='A';
NODE_NAME     R1478 1
 '@T6G_MB_LIB.T6G(SCH_1):PAGE419_I118@PURE_QUANTA.Q_RES(CHIPS)':
 'A': CDS_PINID='A';
NODE_NAME     R1479 1
 '@T6G_MB_LIB.T6G(SCH_1):PAGE419_I121@PURE_QUANTA.Q_RES(CHIPS)':
 'A': CDS_PINID='A';
NODE_NAME     R1482 1
 '@T6G_MB_LIB.T6G(SCH_1):PAGE430_I112@PURE_QUANTA.Q_RES(CHIPS)':
 'A': CDS_PINID='A';
NODE_NAME     R1483 1
 '@T6G_MB_LIB.T6G(SCH_1):PAGE430_I113@PURE_QUANTA.Q_RES(CHIPS)':
 'A': CDS_PINID='A';
NODE_NAME     R1484 1
 '@T6G_MB_LIB.T6G(SCH_1):PAGE430_I118@PURE_QUANTA.Q_RES(CHIPS)':
 'A': CDS_PINID='A';
NODE_NAME     R1485 1
 '@T6G_MB_LIB.T6G(SCH_1):PAGE430_I119@PURE_QUANTA.Q_RES(CHIPS)':
 'A': CDS_PINID='A';
NODE_NAME     R1367 1
 '@T6G_MB_LIB.T6G(SCH_1):PAGE377_I121@PURE_QUANTA.Q_RES(CHIPS)':
 'A': CDS_PINID='A';
NODE_NAME     R1366 1
 '@T6G_MB_LIB.T6G(SCH_1):PAGE377_I122@PURE_QUANTA.Q_RES(CHIPS)':
 'A': CDS_PINID='A';
NODE_NAME     R1374 1
 '@T6G_MB_LIB.T6G(SCH_1):PAGE377_I123@PURE_QUANTA.Q_RES(CHIPS)':
 'A': CDS_PINID='A';
NODE_NAME     R1371 1
 '@T6G_MB_LIB.T6G(SCH_1):PAGE377_I124@PURE_QUANTA.Q_RES(CHIPS)':
 'A': CDS_PINID='A';
NODE_NAME     R1375 1
 '@T6G_MB_LIB.T6G(SCH_1):PAGE377_I125@PURE_QUANTA.Q_RES(CHIPS)':
 'A': CDS_PINID='A';
NODE_NAME     R1379 1
 '@T6G_MB_LIB.T6G(SCH_1):PAGE377_I126@PURE_QUANTA.Q_RES(CHIPS)':
 'A': CDS_PINID='A';
NODE_NAME     R1382 1
 '@T6G_MB_LIB.T6G(SCH_1):PAGE377_I127@PURE_QUANTA.Q_RES(CHIPS)':
 'A': CDS_PINID='A';
NODE_NAME     R1383 1
 '@T6G_MB_LIB.T6G(SCH_1):PAGE377_I128@PURE_QUANTA.Q_RES(CHIPS)':
 'A': CDS_PINID='A';
NODE_NAME     R1410 1
 '@T6G_MB_LIB.T6G(SCH_1):PAGE377_I164@PURE_QUANTA.Q_RES(CHIPS)':
 'A': CDS_PINID='A';
NODE_NAME     R1411 1
 '@T6G_MB_LIB.T6G(SCH_1):PAGE377_I165@PURE_QUANTA.Q_RES(CHIPS)':
 'A': CDS_PINID='A';
NODE_NAME     R1415 1
 '@T6G_MB_LIB.T6G(SCH_1):PAGE377_I166@PURE_QUANTA.Q_RES(CHIPS)':
 'A': CDS_PINID='A';
NODE_NAME     R1418 1
 '@T6G_MB_LIB.T6G(SCH_1):PAGE377_I167@PURE_QUANTA.Q_RES(CHIPS)':
 'A': CDS_PINID='A';
NODE_NAME     R1420 1
 '@T6G_MB_LIB.T6G(SCH_1):PAGE377_I168@PURE_QUANTA.Q_RES(CHIPS)':
 'A': CDS_PINID='A';
NODE_NAME     R1428 1
 '@T6G_MB_LIB.T6G(SCH_1):PAGE377_I169@PURE_QUANTA.Q_RES(CHIPS)':
 'A': CDS_PINID='A';
NODE_NAME     R1431 1
 '@T6G_MB_LIB.T6G(SCH_1):PAGE377_I170@PURE_QUANTA.Q_RES(CHIPS)':
 'A': CDS_PINID='A';
NODE_NAME     R1432 1
 '@T6G_MB_LIB.T6G(SCH_1):PAGE377_I171@PURE_QUANTA.Q_RES(CHIPS)':
 'A': CDS_PINID='A';
NODE_NAME     L26 1
 '@T6G_MB_LIB.T6G(SCH_1):PAGE388_I88@PURE_QUANTA.Q_INDUCTOR(CHIPS)':
 '1': CDS_PINID='\1\';
NODE_NAME     R960 1
 '@T6G_MB_LIB.T6G(SCH_1):PAGE388_I89@PURE_QUANTA.Q_RES(CHIPS)':
 'A': CDS_PINID='A';
NODE_NAME     L28 1
 '@T6G_MB_LIB.T6G(SCH_1):PAGE411_I88@PURE_QUANTA.Q_INDUCTOR(CHIPS)':
 '1': CDS_PINID='\1\';
NODE_NAME     R1008 1
 '@T6G_MB_LIB.T6G(SCH_1):PAGE411_I89@PURE_QUANTA.Q_RES(CHIPS)':
 'A': CDS_PINID='A';
NODE_NAME     L29 1
 '@T6G_MB_LIB.T6G(SCH_1):PAGE422_I88@PURE_QUANTA.Q_INDUCTOR(CHIPS)':
 '1': CDS_PINID='\1\';
NODE_NAME     R1050 1
 '@T6G_MB_LIB.T6G(SCH_1):PAGE422_I89@PURE_QUANTA.Q_RES(CHIPS)':
 'A': CDS_PINID='A';
NODE_NAME     L30 1
 '@T6G_MB_LIB.T6G(SCH_1):PAGE433_I88@PURE_QUANTA.Q_INDUCTOR(CHIPS)':
 '1': CDS_PINID='\1\';
NODE_NAME     R1093 1
 '@T6G_MB_LIB.T6G(SCH_1):PAGE433_I89@PURE_QUANTA.Q_RES(CHIPS)':
 'A': CDS_PINID='A';
NET_NAME
'P1V8_CPU0_RT_1D_ADC'
 '@T6G_MB_LIB.T6G(SCH_1):P1V8_CPU0_RT_1D_ADC':
 C_SIGNAL='@t6g_mb_lib.t6g(sch_1):p1v8_cpu0_rt_1d_adc';
NODE_NAME     R1246 1
 '@T6G_MB_LIB.T6G(SCH_1):PAGE263_I189@PURE_QUANTA.Q_RES(CHIPS)':
 'A': CDS_PINID='A';
NODE_NAME     R1252 1
 '@T6G_MB_LIB.T6G(SCH_1):PAGE263_I190@PURE_QUANTA.Q_RES(CHIPS)':
 'A': CDS_PINID='A';
NODE_NAME     R1231 2
 '@T6G_MB_LIB.T6G(SCH_1):PAGE263_I191@PURE_QUANTA.Q_RES(CHIPS)':
 'B': CDS_PINID='B';
NODE_NAME     R1220 1
 '@T6G_MB_LIB.T6G(SCH_1):PAGE263_I244@PURE_QUANTA.Q_RES(CHIPS)':
 'A': CDS_PINID='A';
NET_NAME
'P1V8_CPU0_RT_1D_ADC_MAM'
 '@T6G_MB_LIB.T6G(SCH_1):P1V8_CPU0_RT_1D_ADC_MAM':
 C_SIGNAL='@t6g_mb_lib.t6g(sch_1):p1v8_cpu0_rt_1d_adc_mam';
NODE_NAME     U50 8
 '@T6G_MB_LIB.T6G(SCH_1):PAGE263_I156@PURE_QUANTA.MAX11617EEET(CHIPS)':
 'AIN3': CDS_PINID='AIN3';
NODE_NAME     C1079 1
 '@T6G_MB_LIB.T6G(SCH_1):PAGE263_I185@PURE_QUANTA.Q_CAP(CHIPS)':
 'A': CDS_PINID='A';
NODE_NAME     R1246 2
 '@T6G_MB_LIB.T6G(SCH_1):PAGE263_I189@PURE_QUANTA.Q_RES(CHIPS)':
 'B': CDS_PINID='B';
NET_NAME
'P1V8_CPU0_RT_1D_ADC_TIC'
 '@T6G_MB_LIB.T6G(SCH_1):P1V8_CPU0_RT_1D_ADC_TIC':
 C_SIGNAL='@t6g_mb_lib.t6g(sch_1):p1v8_cpu0_rt_1d_adc_tic';
NODE_NAME     U51 13
 '@T6G_MB_LIB.T6G(SCH_1):PAGE263_I142@PURE_QUANTA.ADC128D818CIMTXNOPB(CHIPS)':
 'IN3': CDS_PINID='IN3';
NODE_NAME     C1087 1
 '@T6G_MB_LIB.T6G(SCH_1):PAGE263_I187@PURE_QUANTA.Q_CAP(CHIPS)':
 'A': CDS_PINID='A';
NODE_NAME     R1252 2
 '@T6G_MB_LIB.T6G(SCH_1):PAGE263_I190@PURE_QUANTA.Q_RES(CHIPS)':
 'B': CDS_PINID='B';
NET_NAME
'P1V8_CPU1_RT0_1A'
 '@T6G_MB_LIB.T6G(SCH_1):P1V8_CPU1_RT0_1A':
 C_SIGNAL='@t6g_mb_lib.t6g(sch_1):p1v8_cpu1_rt0_1a',
 CDS_GLOBAL_NET='TRUE';
NODE_NAME     U6014 BV20
 '@T6G_MB_LIB.T6G(SCH_1):PAGE400_I1@PURE_QUANTA.PT5161LRS(CHIPS)':
 'PWR_1A_1': CDS_PINID='PWR_1A_1';
NODE_NAME     U6014 CE17
 '@T6G_MB_LIB.T6G(SCH_1):PAGE400_I1@PURE_QUANTA.PT5161LRS(CHIPS)':
 'PWR_1A_2': CDS_PINID='PWR_1A_2';
NODE_NAME     U6014 CE20
 '@T6G_MB_LIB.T6G(SCH_1):PAGE400_I1@PURE_QUANTA.PT5161LRS(CHIPS)':
 'PWR_1A_3': CDS_PINID='PWR_1A_3';
NODE_NAME     U6014 CM17
 '@T6G_MB_LIB.T6G(SCH_1):PAGE400_I1@PURE_QUANTA.PT5161LRS(CHIPS)':
 'PWR_1A_4': CDS_PINID='PWR_1A_4';
NODE_NAME     U6014 CM20
 '@T6G_MB_LIB.T6G(SCH_1):PAGE400_I1@PURE_QUANTA.PT5161LRS(CHIPS)':
 'PWR_1A_5': CDS_PINID='PWR_1A_5';
NODE_NAME     C114 1
 '@T6G_MB_LIB.T6G(SCH_1):PAGE398_I4@PURE_QUANTA.Q_CAP(CHIPS)':
 'A': CDS_PINID='A';
NODE_NAME     C117 1
 '@T6G_MB_LIB.T6G(SCH_1):PAGE398_I5@PURE_QUANTA.Q_CAP(CHIPS)':
 'A': CDS_PINID='A';
NODE_NAME     C121 1
 '@T6G_MB_LIB.T6G(SCH_1):PAGE398_I7@PURE_QUANTA.Q_CAP(CHIPS)':
 'A': CDS_PINID='A';
NODE_NAME     C126 1
 '@T6G_MB_LIB.T6G(SCH_1):PAGE398_I9@PURE_QUANTA.Q_CAP(CHIPS)':
 'A': CDS_PINID='A';
NODE_NAME     C123 1
 '@T6G_MB_LIB.T6G(SCH_1):PAGE398_I18@PURE_QUANTA.Q_CAP(CHIPS)':
 'A': CDS_PINID='A';
NODE_NAME     C119 1
 '@T6G_MB_LIB.T6G(SCH_1):PAGE398_I20@PURE_QUANTA.Q_CAP(CHIPS)':
 'A': CDS_PINID='A';
NODE_NAME     L3 2
 '@T6G_MB_LIB.T6G(SCH_1):PAGE398_I22@PURE_QUANTA.Q_INDUCTOR(CHIPS)':
 '2': CDS_PINID='\2\';
NODE_NAME     C129 1
 '@T6G_MB_LIB.T6G(SCH_1):PAGE398_I23@PURE_QUANTA.Q_CAP(CHIPS)':
 'A': CDS_PINID='A';
NODE_NAME     C131 1
 '@T6G_MB_LIB.T6G(SCH_1):PAGE398_I24@PURE_QUANTA.Q_CAP(CHIPS)':
 'A': CDS_PINID='A';
NODE_NAME     C133 1
 '@T6G_MB_LIB.T6G(SCH_1):PAGE398_I25@PURE_QUANTA.Q_CAP(CHIPS)':
 'A': CDS_PINID='A';
NODE_NAME     C134 1
 '@T6G_MB_LIB.T6G(SCH_1):PAGE398_I26@PURE_QUANTA.Q_CAP(CHIPS)':
 'A': CDS_PINID='A';
NODE_NAME     R6702 2
 '@T6G_MB_LIB.T6G(SCH_1):PAGE398_I32@PURE_QUANTA.Q_RES(CHIPS)':
 'B': CDS_PINID='B';
NODE_NAME     R6703 2
 '@T6G_MB_LIB.T6G(SCH_1):PAGE398_I33@PURE_QUANTA.Q_RES(CHIPS)':
 'B': CDS_PINID='B';
NET_NAME
'P1V8_CPU1_RT0_1A_1D'
 '@T6G_MB_LIB.T6G(SCH_1):P1V8_CPU1_RT0_1A_1D':
 C_SIGNAL='@t6g_mb_lib.t6g(sch_1):p1v8_cpu1_rt0_1a_1d',
 CDS_GLOBAL_NET='TRUE';
NODE_NAME     U6014 BV17
 '@T6G_MB_LIB.T6G(SCH_1):PAGE400_I1@PURE_QUANTA.PT5161LRS(CHIPS)':
 'PWR_1D': CDS_PINID='PWR_1D';
NODE_NAME     C125 1
 '@T6G_MB_LIB.T6G(SCH_1):PAGE398_I19@PURE_QUANTA.Q_CAP(CHIPS)':
 'A': CDS_PINID='A';
NODE_NAME     C130 1
 '@T6G_MB_LIB.T6G(SCH_1):PAGE398_I27@PURE_QUANTA.Q_CAP(CHIPS)':
 'A': CDS_PINID='A';
NODE_NAME     R6702 1
 '@T6G_MB_LIB.T6G(SCH_1):PAGE398_I32@PURE_QUANTA.Q_RES(CHIPS)':
 'A': CDS_PINID='A';
NODE_NAME     R6703 1
 '@T6G_MB_LIB.T6G(SCH_1):PAGE398_I33@PURE_QUANTA.Q_RES(CHIPS)':
 'A': CDS_PINID='A';
NODE_NAME     L27 2
 '@T6G_MB_LIB.T6G(SCH_1):PAGE398_I97@PURE_QUANTA.Q_INDUCTOR(CHIPS)':
 '2': CDS_PINID='\2\';
NODE_NAME     R6701 2
 '@T6G_MB_LIB.T6G(SCH_1):PAGE398_I98@PURE_QUANTA.Q_RES(CHIPS)':
 'B': CDS_PINID='B';
NET_NAME
'P1V8_CPU1_RT1_1A'
 '@T6G_MB_LIB.T6G(SCH_1):P1V8_CPU1_RT1_1A':
 C_SIGNAL='@t6g_mb_lib.t6g(sch_1):p1v8_cpu1_rt1_1a',
 CDS_GLOBAL_NET='TRUE';
NODE_NAME     U6015 BV20
 '@T6G_MB_LIB.T6G(SCH_1):PAGE391_I5@PURE_QUANTA.PT5161LRS(CHIPS)':
 'PWR_1A_1': CDS_PINID='PWR_1A_1';
NODE_NAME     U6015 CE17
 '@T6G_MB_LIB.T6G(SCH_1):PAGE391_I5@PURE_QUANTA.PT5161LRS(CHIPS)':
 'PWR_1A_2': CDS_PINID='PWR_1A_2';
NODE_NAME     U6015 CE20
 '@T6G_MB_LIB.T6G(SCH_1):PAGE391_I5@PURE_QUANTA.PT5161LRS(CHIPS)':
 'PWR_1A_3': CDS_PINID='PWR_1A_3';
NODE_NAME     U6015 CM17
 '@T6G_MB_LIB.T6G(SCH_1):PAGE391_I5@PURE_QUANTA.PT5161LRS(CHIPS)':
 'PWR_1A_4': CDS_PINID='PWR_1A_4';
NODE_NAME     U6015 CM20
 '@T6G_MB_LIB.T6G(SCH_1):PAGE391_I5@PURE_QUANTA.PT5161LRS(CHIPS)':
 'PWR_1A_5': CDS_PINID='PWR_1A_5';
NODE_NAME     R664 2
 '@T6G_MB_LIB.T6G(SCH_1):PAGE443_I4@PURE_QUANTA.Q_RES(CHIPS)':
 'B': CDS_PINID='B';
NODE_NAME     R653 2
 '@T6G_MB_LIB.T6G(SCH_1):PAGE443_I5@PURE_QUANTA.Q_RES(CHIPS)':
 'B': CDS_PINID='B';
NODE_NAME     L5 2
 '@T6G_MB_LIB.T6G(SCH_1):PAGE443_I12@PURE_QUANTA.Q_INDUCTOR(CHIPS)':
 '2': CDS_PINID='\2\';
NODE_NAME     C103 1
 '@T6G_MB_LIB.T6G(SCH_1):PAGE443_I13@PURE_QUANTA.Q_CAP(CHIPS)':
 'A': CDS_PINID='A';
NODE_NAME     C111 1
 '@T6G_MB_LIB.T6G(SCH_1):PAGE443_I14@PURE_QUANTA.Q_CAP(CHIPS)':
 'A': CDS_PINID='A';
NODE_NAME     C199 1
 '@T6G_MB_LIB.T6G(SCH_1):PAGE443_I17@PURE_QUANTA.Q_CAP(CHIPS)':
 'A': CDS_PINID='A';
NODE_NAME     C195 1
 '@T6G_MB_LIB.T6G(SCH_1):PAGE443_I18@PURE_QUANTA.Q_CAP(CHIPS)':
 'A': CDS_PINID='A';
NODE_NAME     C202 1
 '@T6G_MB_LIB.T6G(SCH_1):PAGE443_I20@PURE_QUANTA.Q_CAP(CHIPS)':
 'A': CDS_PINID='A';
NODE_NAME     C204 1
 '@T6G_MB_LIB.T6G(SCH_1):PAGE443_I22@PURE_QUANTA.Q_CAP(CHIPS)':
 'A': CDS_PINID='A';
NODE_NAME     C205 1
 '@T6G_MB_LIB.T6G(SCH_1):PAGE443_I23@PURE_QUANTA.Q_CAP(CHIPS)':
 'A': CDS_PINID='A';
NODE_NAME     C217 1
 '@T6G_MB_LIB.T6G(SCH_1):PAGE443_I27@PURE_QUANTA.Q_CAP(CHIPS)':
 'A': CDS_PINID='A';
NODE_NAME     C287 1
 '@T6G_MB_LIB.T6G(SCH_1):PAGE443_I28@PURE_QUANTA.Q_CAP(CHIPS)':
 'A': CDS_PINID='A';
NODE_NAME     C288 1
 '@T6G_MB_LIB.T6G(SCH_1):PAGE443_I29@PURE_QUANTA.Q_CAP(CHIPS)':
 'A': CDS_PINID='A';
NET_NAME
'P1V8_CPU1_RT1_1A_1D'
 '@T6G_MB_LIB.T6G(SCH_1):P1V8_CPU1_RT1_1A_1D':
 C_SIGNAL='@t6g_mb_lib.t6g(sch_1):p1v8_cpu1_rt1_1a_1d',
 CDS_GLOBAL_NET='TRUE';
NODE_NAME     U6015 BV17
 '@T6G_MB_LIB.T6G(SCH_1):PAGE391_I5@PURE_QUANTA.PT5161LRS(CHIPS)':
 'PWR_1D': CDS_PINID='PWR_1D';
NODE_NAME     R664 1
 '@T6G_MB_LIB.T6G(SCH_1):PAGE443_I4@PURE_QUANTA.Q_RES(CHIPS)':
 'A': CDS_PINID='A';
NODE_NAME     R653 1
 '@T6G_MB_LIB.T6G(SCH_1):PAGE443_I5@PURE_QUANTA.Q_RES(CHIPS)':
 'A': CDS_PINID='A';
NODE_NAME     C203 1
 '@T6G_MB_LIB.T6G(SCH_1):PAGE443_I8@PURE_QUANTA.Q_CAP(CHIPS)':
 'A': CDS_PINID='A';
NODE_NAME     C206 1
 '@T6G_MB_LIB.T6G(SCH_1):PAGE443_I9@PURE_QUANTA.Q_CAP(CHIPS)':
 'A': CDS_PINID='A';
NODE_NAME     L31 2
 '@T6G_MB_LIB.T6G(SCH_1):PAGE443_I88@PURE_QUANTA.Q_INDUCTOR(CHIPS)':
 '2': CDS_PINID='\2\';
NODE_NAME     R704 2
 '@T6G_MB_LIB.T6G(SCH_1):PAGE443_I89@PURE_QUANTA.Q_RES(CHIPS)':
 'B': CDS_PINID='B';
NET_NAME
'P1V8_CPU1_RT2_1A'
 '@T6G_MB_LIB.T6G(SCH_1):P1V8_CPU1_RT2_1A':
 C_SIGNAL='@t6g_mb_lib.t6g(sch_1):p1v8_cpu1_rt2_1a',
 CDS_GLOBAL_NET='TRUE';
NODE_NAME     U6016 BV20
 '@T6G_MB_LIB.T6G(SCH_1):PAGE452_I7@PURE_QUANTA.PT5161LRS(CHIPS)':
 'PWR_1A_1': CDS_PINID='PWR_1A_1';
NODE_NAME     U6016 CE17
 '@T6G_MB_LIB.T6G(SCH_1):PAGE452_I7@PURE_QUANTA.PT5161LRS(CHIPS)':
 'PWR_1A_2': CDS_PINID='PWR_1A_2';
NODE_NAME     U6016 CE20
 '@T6G_MB_LIB.T6G(SCH_1):PAGE452_I7@PURE_QUANTA.PT5161LRS(CHIPS)':
 'PWR_1A_3': CDS_PINID='PWR_1A_3';
NODE_NAME     U6016 CM17
 '@T6G_MB_LIB.T6G(SCH_1):PAGE452_I7@PURE_QUANTA.PT5161LRS(CHIPS)':
 'PWR_1A_4': CDS_PINID='PWR_1A_4';
NODE_NAME     U6016 CM20
 '@T6G_MB_LIB.T6G(SCH_1):PAGE452_I7@PURE_QUANTA.PT5161LRS(CHIPS)':
 'PWR_1A_5': CDS_PINID='PWR_1A_5';
NODE_NAME     R852 2
 '@T6G_MB_LIB.T6G(SCH_1):PAGE454_I2@PURE_QUANTA.Q_RES(CHIPS)':
 'B': CDS_PINID='B';
NODE_NAME     R853 2
 '@T6G_MB_LIB.T6G(SCH_1):PAGE454_I3@PURE_QUANTA.Q_RES(CHIPS)':
 'B': CDS_PINID='B';
NODE_NAME     C367 1
 '@T6G_MB_LIB.T6G(SCH_1):PAGE454_I5@PURE_QUANTA.Q_CAP(CHIPS)':
 'A': CDS_PINID='A';
NODE_NAME     C369 1
 '@T6G_MB_LIB.T6G(SCH_1):PAGE454_I10@PURE_QUANTA.Q_CAP(CHIPS)':
 'A': CDS_PINID='A';
NODE_NAME     C372 1
 '@T6G_MB_LIB.T6G(SCH_1):PAGE454_I11@PURE_QUANTA.Q_CAP(CHIPS)':
 'A': CDS_PINID='A';
NODE_NAME     C371 1
 '@T6G_MB_LIB.T6G(SCH_1):PAGE454_I12@PURE_QUANTA.Q_CAP(CHIPS)':
 'A': CDS_PINID='A';
NODE_NAME     C374 1
 '@T6G_MB_LIB.T6G(SCH_1):PAGE454_I13@PURE_QUANTA.Q_CAP(CHIPS)':
 'A': CDS_PINID='A';
NODE_NAME     C376 1
 '@T6G_MB_LIB.T6G(SCH_1):PAGE454_I15@PURE_QUANTA.Q_CAP(CHIPS)':
 'A': CDS_PINID='A';
NODE_NAME     C377 1
 '@T6G_MB_LIB.T6G(SCH_1):PAGE454_I16@PURE_QUANTA.Q_CAP(CHIPS)':
 'A': CDS_PINID='A';
NODE_NAME     C379 1
 '@T6G_MB_LIB.T6G(SCH_1):PAGE454_I17@PURE_QUANTA.Q_CAP(CHIPS)':
 'A': CDS_PINID='A';
NODE_NAME     C380 1
 '@T6G_MB_LIB.T6G(SCH_1):PAGE454_I18@PURE_QUANTA.Q_CAP(CHIPS)':
 'A': CDS_PINID='A';
NODE_NAME     C381 1
 '@T6G_MB_LIB.T6G(SCH_1):PAGE454_I19@PURE_QUANTA.Q_CAP(CHIPS)':
 'A': CDS_PINID='A';
NODE_NAME     L7 2
 '@T6G_MB_LIB.T6G(SCH_1):PAGE454_I21@PURE_QUANTA.Q_INDUCTOR(CHIPS)':
 '2': CDS_PINID='\2\';
NET_NAME
'P1V8_CPU1_RT2_1A_1D'
 '@T6G_MB_LIB.T6G(SCH_1):P1V8_CPU1_RT2_1A_1D':
 C_SIGNAL='@t6g_mb_lib.t6g(sch_1):p1v8_cpu1_rt2_1a_1d',
 CDS_GLOBAL_NET='TRUE';
NODE_NAME     U6016 BV17
 '@T6G_MB_LIB.T6G(SCH_1):PAGE452_I7@PURE_QUANTA.PT5161LRS(CHIPS)':
 'PWR_1D': CDS_PINID='PWR_1D';
NODE_NAME     R852 1
 '@T6G_MB_LIB.T6G(SCH_1):PAGE454_I2@PURE_QUANTA.Q_RES(CHIPS)':
 'A': CDS_PINID='A';
NODE_NAME     R853 1
 '@T6G_MB_LIB.T6G(SCH_1):PAGE454_I3@PURE_QUANTA.Q_RES(CHIPS)':
 'A': CDS_PINID='A';
NODE_NAME     C375 1
 '@T6G_MB_LIB.T6G(SCH_1):PAGE454_I6@PURE_QUANTA.Q_CAP(CHIPS)':
 'A': CDS_PINID='A';
NODE_NAME     C378 1
 '@T6G_MB_LIB.T6G(SCH_1):PAGE454_I8@PURE_QUANTA.Q_CAP(CHIPS)':
 'A': CDS_PINID='A';
NODE_NAME     L32 2
 '@T6G_MB_LIB.T6G(SCH_1):PAGE454_I88@PURE_QUANTA.Q_INDUCTOR(CHIPS)':
 '2': CDS_PINID='\2\';
NODE_NAME     R857 2
 '@T6G_MB_LIB.T6G(SCH_1):PAGE454_I89@PURE_QUANTA.Q_RES(CHIPS)':
 'B': CDS_PINID='B';
NET_NAME
'P1V8_CPU1_RT3_1A'
 '@T6G_MB_LIB.T6G(SCH_1):P1V8_CPU1_RT3_1A':
 C_SIGNAL='@t6g_mb_lib.t6g(sch_1):p1v8_cpu1_rt3_1a',
 CDS_GLOBAL_NET='TRUE';
NODE_NAME     U6017 BV20
 '@T6G_MB_LIB.T6G(SCH_1):PAGE463_I5@PURE_QUANTA.PT5161LRS(CHIPS)':
 'PWR_1A_1': CDS_PINID='PWR_1A_1';
NODE_NAME     U6017 CE17
 '@T6G_MB_LIB.T6G(SCH_1):PAGE463_I5@PURE_QUANTA.PT5161LRS(CHIPS)':
 'PWR_1A_2': CDS_PINID='PWR_1A_2';
NODE_NAME     U6017 CE20
 '@T6G_MB_LIB.T6G(SCH_1):PAGE463_I5@PURE_QUANTA.PT5161LRS(CHIPS)':
 'PWR_1A_3': CDS_PINID='PWR_1A_3';
NODE_NAME     U6017 CM17
 '@T6G_MB_LIB.T6G(SCH_1):PAGE463_I5@PURE_QUANTA.PT5161LRS(CHIPS)':
 'PWR_1A_4': CDS_PINID='PWR_1A_4';
NODE_NAME     U6017 CM20
 '@T6G_MB_LIB.T6G(SCH_1):PAGE463_I5@PURE_QUANTA.PT5161LRS(CHIPS)':
 'PWR_1A_5': CDS_PINID='PWR_1A_5';
NODE_NAME     R894 2
 '@T6G_MB_LIB.T6G(SCH_1):PAGE465_I1@PURE_QUANTA.Q_RES(CHIPS)':
 'B': CDS_PINID='B';
NODE_NAME     R893 2
 '@T6G_MB_LIB.T6G(SCH_1):PAGE465_I2@PURE_QUANTA.Q_RES(CHIPS)':
 'B': CDS_PINID='B';
NODE_NAME     L9 2
 '@T6G_MB_LIB.T6G(SCH_1):PAGE465_I11@PURE_QUANTA.Q_INDUCTOR(CHIPS)':
 '2': CDS_PINID='\2\';
NODE_NAME     C433 1
 '@T6G_MB_LIB.T6G(SCH_1):PAGE465_I14@PURE_QUANTA.Q_CAP(CHIPS)':
 'A': CDS_PINID='A';
NODE_NAME     C435 1
 '@T6G_MB_LIB.T6G(SCH_1):PAGE465_I15@PURE_QUANTA.Q_CAP(CHIPS)':
 'A': CDS_PINID='A';
NODE_NAME     C437 1
 '@T6G_MB_LIB.T6G(SCH_1):PAGE465_I16@PURE_QUANTA.Q_CAP(CHIPS)':
 'A': CDS_PINID='A';
NODE_NAME     C438 1
 '@T6G_MB_LIB.T6G(SCH_1):PAGE465_I19@PURE_QUANTA.Q_CAP(CHIPS)':
 'A': CDS_PINID='A';
NODE_NAME     C440 1
 '@T6G_MB_LIB.T6G(SCH_1):PAGE465_I20@PURE_QUANTA.Q_CAP(CHIPS)':
 'A': CDS_PINID='A';
NODE_NAME     C442 1
 '@T6G_MB_LIB.T6G(SCH_1):PAGE465_I24@PURE_QUANTA.Q_CAP(CHIPS)':
 'A': CDS_PINID='A';
NODE_NAME     C443 1
 '@T6G_MB_LIB.T6G(SCH_1):PAGE465_I25@PURE_QUANTA.Q_CAP(CHIPS)':
 'A': CDS_PINID='A';
NODE_NAME     C445 1
 '@T6G_MB_LIB.T6G(SCH_1):PAGE465_I26@PURE_QUANTA.Q_CAP(CHIPS)':
 'A': CDS_PINID='A';
NODE_NAME     C446 1
 '@T6G_MB_LIB.T6G(SCH_1):PAGE465_I27@PURE_QUANTA.Q_CAP(CHIPS)':
 'A': CDS_PINID='A';
NODE_NAME     C447 1
 '@T6G_MB_LIB.T6G(SCH_1):PAGE465_I28@PURE_QUANTA.Q_CAP(CHIPS)':
 'A': CDS_PINID='A';
NET_NAME
'P1V8_CPU1_RT3_1A_1D'
 '@T6G_MB_LIB.T6G(SCH_1):P1V8_CPU1_RT3_1A_1D':
 C_SIGNAL='@t6g_mb_lib.t6g(sch_1):p1v8_cpu1_rt3_1a_1d',
 CDS_GLOBAL_NET='TRUE';
NODE_NAME     U6017 BV17
 '@T6G_MB_LIB.T6G(SCH_1):PAGE463_I5@PURE_QUANTA.PT5161LRS(CHIPS)':
 'PWR_1D': CDS_PINID='PWR_1D';
NODE_NAME     R894 1
 '@T6G_MB_LIB.T6G(SCH_1):PAGE465_I1@PURE_QUANTA.Q_RES(CHIPS)':
 'A': CDS_PINID='A';
NODE_NAME     R893 1
 '@T6G_MB_LIB.T6G(SCH_1):PAGE465_I2@PURE_QUANTA.Q_RES(CHIPS)':
 'A': CDS_PINID='A';
NODE_NAME     C441 1
 '@T6G_MB_LIB.T6G(SCH_1):PAGE465_I4@PURE_QUANTA.Q_CAP(CHIPS)':
 'A': CDS_PINID='A';
NODE_NAME     C444 1
 '@T6G_MB_LIB.T6G(SCH_1):PAGE465_I6@PURE_QUANTA.Q_CAP(CHIPS)':
 'A': CDS_PINID='A';
NODE_NAME     L33 2
 '@T6G_MB_LIB.T6G(SCH_1):PAGE465_I88@PURE_QUANTA.Q_INDUCTOR(CHIPS)':
 '2': CDS_PINID='\2\';
NODE_NAME     R897 2
 '@T6G_MB_LIB.T6G(SCH_1):PAGE465_I89@PURE_QUANTA.Q_RES(CHIPS)':
 'B': CDS_PINID='B';
NET_NAME
'P1V8_CPU1_RT_1D'
 '@T6G_MB_LIB.T6G(SCH_1):P1V8_CPU1_RT_1D':
 C_SIGNAL='@t6g_mb_lib.t6g(sch_1):p1v8_cpu1_rt_1d',
 CDS_GLOBAL_NET='TRUE';
NODE_NAME     U12 8
 '@T6G_MB_LIB.T6G(SCH_1):PAGE399_I5@PURE_QUANTA.M24M02DRMN6TP(CHIPS)':
 'VCC': CDS_PINID='VCC';
NODE_NAME     U19 8
 '@T6G_MB_LIB.T6G(SCH_1):PAGE442_I5@PURE_QUANTA.M24M02DRMN6TP(CHIPS)':
 'VCC': CDS_PINID='VCC';
NODE_NAME     U20 8
 '@T6G_MB_LIB.T6G(SCH_1):PAGE453_I5@PURE_QUANTA.M24M02DRMN6TP(CHIPS)':
 'VCC': CDS_PINID='VCC';
NODE_NAME     U21 8
 '@T6G_MB_LIB.T6G(SCH_1):PAGE464_I5@PURE_QUANTA.M24M02DRMN6TP(CHIPS)':
 'VCC': CDS_PINID='VCC';
NODE_NAME     C113 1
 '@T6G_MB_LIB.T6G(SCH_1):PAGE398_I12@PURE_QUANTA.Q_CAP(CHIPS)':
 'A': CDS_PINID='A';
NODE_NAME     C118 1
 '@T6G_MB_LIB.T6G(SCH_1):PAGE398_I14@PURE_QUANTA.Q_CAP(CHIPS)':
 'A': CDS_PINID='A';
NODE_NAME     C122 1
 '@T6G_MB_LIB.T6G(SCH_1):PAGE398_I15@PURE_QUANTA.Q_CAP(CHIPS)':
 'A': CDS_PINID='A';
NODE_NAME     PC6534 2
 '@T6G_MB_LIB.T6G(SCH_1):PAGE470_I33@PURE_QUANTA.Q_CAP(CHIPS)':
 'B': CDS_PINID='B';
NODE_NAME     PR6524 2
 '@T6G_MB_LIB.T6G(SCH_1):PAGE470_I34@PURE_QUANTA.Q_RES(CHIPS)':
 'B': CDS_PINID='B';
NODE_NAME     PL6502 2
 '@T6G_MB_LIB.T6G(SCH_1):PAGE470_I37@PURE_QUANTA.Q_INDUCTOR(CHIPS)':
 '2': CDS_PINID='\2\';
NODE_NAME     PC6527 1
 '@T6G_MB_LIB.T6G(SCH_1):PAGE470_I38@PURE_QUANTA.Q_CAP(CHIPS)':
 'A': CDS_PINID='A';
NODE_NAME     PC6528 1
 '@T6G_MB_LIB.T6G(SCH_1):PAGE470_I41@PURE_QUANTA.Q_CAP(CHIPS)':
 'A': CDS_PINID='A';
NODE_NAME     PC6529 1
 '@T6G_MB_LIB.T6G(SCH_1):PAGE470_I42@PURE_QUANTA.Q_CAP(CHIPS)':
 'A': CDS_PINID='A';
NODE_NAME     PC6530 1
 '@T6G_MB_LIB.T6G(SCH_1):PAGE470_I44@PURE_QUANTA.Q_CAP(CHIPS)':
 'A': CDS_PINID='A';
NODE_NAME     PC6531 1
 '@T6G_MB_LIB.T6G(SCH_1):PAGE470_I45@PURE_QUANTA.Q_CAP(CHIPS)':
 'A': CDS_PINID='A';
NODE_NAME     PC6532 1
 '@T6G_MB_LIB.T6G(SCH_1):PAGE470_I46@PURE_QUANTA.Q_CAPP(CHIPS)':
 'A': CDS_PINID='A';
NODE_NAME     PC6804 1
 '@T6G_MB_LIB.T6G(SCH_1):PAGE470_I47@PURE_QUANTA.Q_CAPP(CHIPS)':
 'A': CDS_PINID='A';
NODE_NAME     PC6533 1
 '@T6G_MB_LIB.T6G(SCH_1):PAGE470_I49@PURE_QUANTA.Q_CAP(CHIPS)':
 'A': CDS_PINID='A';
NODE_NAME     C115 1
 '@T6G_MB_LIB.T6G(SCH_1):PAGE398_I21@PURE_QUANTA.Q_CAP(CHIPS)':
 'A': CDS_PINID='A';
NODE_NAME     L3 1
 '@T6G_MB_LIB.T6G(SCH_1):PAGE398_I22@PURE_QUANTA.Q_INDUCTOR(CHIPS)':
 '1': CDS_PINID='\1\';
NODE_NAME     R724 1
 '@T6G_MB_LIB.T6G(SCH_1):PAGE401_I25@PURE_QUANTA.Q_RES(CHIPS)':
 'A': CDS_PINID='A';
NODE_NAME     R720 1
 '@T6G_MB_LIB.T6G(SCH_1):PAGE401_I26@PURE_QUANTA.Q_RES(CHIPS)':
 'A': CDS_PINID='A';
NODE_NAME     R716 1
 '@T6G_MB_LIB.T6G(SCH_1):PAGE401_I27@PURE_QUANTA.Q_RES(CHIPS)':
 'A': CDS_PINID='A';
NODE_NAME     R706 1
 '@T6G_MB_LIB.T6G(SCH_1):PAGE401_I29@PURE_QUANTA.Q_RES(CHIPS)':
 'A': CDS_PINID='A';
NODE_NAME     R727 1
 '@T6G_MB_LIB.T6G(SCH_1):PAGE401_I54@PURE_QUANTA.Q_RES(CHIPS)':
 'A': CDS_PINID='A';
NODE_NAME     R6718 1
 '@T6G_MB_LIB.T6G(SCH_1):PAGE378_I9@PURE_QUANTA.Q_RES(CHIPS)':
 'A': CDS_PINID='A';
NODE_NAME     R6719 1
 '@T6G_MB_LIB.T6G(SCH_1):PAGE378_I11@PURE_QUANTA.Q_RES(CHIPS)':
 'A': CDS_PINID='A';
NODE_NAME     R6722 1
 '@T6G_MB_LIB.T6G(SCH_1):PAGE401_I85@PURE_QUANTA.Q_RES(CHIPS)':
 'A': CDS_PINID='A';
NODE_NAME     R6725 1
 '@T6G_MB_LIB.T6G(SCH_1):PAGE401_I91@PURE_QUANTA.Q_RES(CHIPS)':
 'A': CDS_PINID='A';
NODE_NAME     R6724 1
 '@T6G_MB_LIB.T6G(SCH_1):PAGE401_I101@PURE_QUANTA.Q_RES(CHIPS)':
 'A': CDS_PINID='A';
NODE_NAME     L5 1
 '@T6G_MB_LIB.T6G(SCH_1):PAGE443_I12@PURE_QUANTA.Q_INDUCTOR(CHIPS)':
 '1': CDS_PINID='\1\';
NODE_NAME     C102 1
 '@T6G_MB_LIB.T6G(SCH_1):PAGE443_I16@PURE_QUANTA.Q_CAP(CHIPS)':
 'A': CDS_PINID='A';
NODE_NAME     C110 1
 '@T6G_MB_LIB.T6G(SCH_1):PAGE443_I24@PURE_QUANTA.Q_CAP(CHIPS)':
 'A': CDS_PINID='A';
NODE_NAME     C127 1
 '@T6G_MB_LIB.T6G(SCH_1):PAGE443_I25@PURE_QUANTA.Q_CAP(CHIPS)':
 'A': CDS_PINID='A';
NODE_NAME     C200 1
 '@T6G_MB_LIB.T6G(SCH_1):PAGE443_I26@PURE_QUANTA.Q_CAP(CHIPS)':
 'A': CDS_PINID='A';
NODE_NAME     R755 1
 '@T6G_MB_LIB.T6G(SCH_1):PAGE392_I19@PURE_QUANTA.Q_RES(CHIPS)':
 'A': CDS_PINID='A';
NODE_NAME     R781 1
 '@T6G_MB_LIB.T6G(SCH_1):PAGE392_I24@PURE_QUANTA.Q_RES(CHIPS)':
 'A': CDS_PINID='A';
NODE_NAME     R784 1
 '@T6G_MB_LIB.T6G(SCH_1):PAGE392_I25@PURE_QUANTA.Q_RES(CHIPS)':
 'A': CDS_PINID='A';
NODE_NAME     R786 1
 '@T6G_MB_LIB.T6G(SCH_1):PAGE392_I55@PURE_QUANTA.Q_RES(CHIPS)':
 'A': CDS_PINID='A';
NODE_NAME     R788 1
 '@T6G_MB_LIB.T6G(SCH_1):PAGE392_I56@PURE_QUANTA.Q_RES(CHIPS)':
 'A': CDS_PINID='A';
NODE_NAME     R759 1
 '@T6G_MB_LIB.T6G(SCH_1):PAGE392_I57@PURE_QUANTA.Q_RES(CHIPS)':
 'A': CDS_PINID='A';
NODE_NAME     R793 1
 '@T6G_MB_LIB.T6G(SCH_1):PAGE392_I66@PURE_QUANTA.Q_RES(CHIPS)':
 'A': CDS_PINID='A';
NODE_NAME     R758 1
 '@T6G_MB_LIB.T6G(SCH_1):PAGE392_I94@PURE_QUANTA.Q_RES(CHIPS)':
 'A': CDS_PINID='A';
NODE_NAME     R6738 1
 '@T6G_MB_LIB.T6G(SCH_1):PAGE378_I17@PURE_QUANTA.Q_RES(CHIPS)':
 'A': CDS_PINID='A';
NODE_NAME     R6739 1
 '@T6G_MB_LIB.T6G(SCH_1):PAGE378_I18@PURE_QUANTA.Q_RES(CHIPS)':
 'A': CDS_PINID='A';
NODE_NAME     R6750 1
 '@T6G_MB_LIB.T6G(SCH_1):PAGE378_I31@PURE_QUANTA.Q_RES(CHIPS)':
 'A': CDS_PINID='A';
NODE_NAME     R6751 1
 '@T6G_MB_LIB.T6G(SCH_1):PAGE378_I32@PURE_QUANTA.Q_RES(CHIPS)':
 'A': CDS_PINID='A';
NODE_NAME     R6752 1
 '@T6G_MB_LIB.T6G(SCH_1):PAGE378_I35@PURE_QUANTA.Q_RES(CHIPS)':
 'A': CDS_PINID='A';
NODE_NAME     R6753 1
 '@T6G_MB_LIB.T6G(SCH_1):PAGE378_I36@PURE_QUANTA.Q_RES(CHIPS)':
 'A': CDS_PINID='A';
NODE_NAME     R827 1
 '@T6G_MB_LIB.T6G(SCH_1):PAGE377_I58@PURE_QUANTA.Q_RES(CHIPS)':
 'A': CDS_PINID='A';
NODE_NAME     R826 1
 '@T6G_MB_LIB.T6G(SCH_1):PAGE377_I59@PURE_QUANTA.Q_RES(CHIPS)':
 'A': CDS_PINID='A';
NODE_NAME     R812 1
 '@T6G_MB_LIB.T6G(SCH_1):PAGE377_I60@PURE_QUANTA.Q_RES(CHIPS)':
 'A': CDS_PINID='A';
NODE_NAME     R810 1
 '@T6G_MB_LIB.T6G(SCH_1):PAGE377_I61@PURE_QUANTA.Q_RES(CHIPS)':
 'A': CDS_PINID='A';
NODE_NAME     R6734 1
 '@T6G_MB_LIB.T6G(SCH_1):PAGE377_I62@PURE_QUANTA.Q_RES(CHIPS)':
 'A': CDS_PINID='A';
NODE_NAME     R6735 1
 '@T6G_MB_LIB.T6G(SCH_1):PAGE377_I63@PURE_QUANTA.Q_RES(CHIPS)':
 'A': CDS_PINID='A';
NODE_NAME     R6707 1
 '@T6G_MB_LIB.T6G(SCH_1):PAGE377_I64@PURE_QUANTA.Q_RES(CHIPS)':
 'A': CDS_PINID='A';
NODE_NAME     R6706 1
 '@T6G_MB_LIB.T6G(SCH_1):PAGE377_I65@PURE_QUANTA.Q_RES(CHIPS)':
 'A': CDS_PINID='A';
NODE_NAME     R6712 1
 '@T6G_MB_LIB.T6G(SCH_1):PAGE401_I102@PURE_QUANTA.Q_RES(CHIPS)':
 'A': CDS_PINID='A';
NODE_NAME     R6714 1
 '@T6G_MB_LIB.T6G(SCH_1):PAGE401_I104@PURE_QUANTA.Q_RES(CHIPS)':
 'A': CDS_PINID='A';
NODE_NAME     R6716 1
 '@T6G_MB_LIB.T6G(SCH_1):PAGE401_I107@PURE_QUANTA.Q_RES(CHIPS)':
 'A': CDS_PINID='A';
NODE_NAME     R735 1
 '@T6G_MB_LIB.T6G(SCH_1):PAGE392_I103@PURE_QUANTA.Q_RES(CHIPS)':
 'A': CDS_PINID='A';
NODE_NAME     R745 1
 '@T6G_MB_LIB.T6G(SCH_1):PAGE392_I104@PURE_QUANTA.Q_RES(CHIPS)':
 'A': CDS_PINID='A';
NODE_NAME     R795 1
 '@T6G_MB_LIB.T6G(SCH_1):PAGE392_I110@PURE_QUANTA.Q_RES(CHIPS)':
 'A': CDS_PINID='A';
NODE_NAME     C7501 1
 '@T6G_MB_LIB.T6G(SCH_1):PAGE399_I11@PURE_QUANTA.Q_CAP(CHIPS)':
 'A': CDS_PINID='A';
NODE_NAME     C7502 1
 '@T6G_MB_LIB.T6G(SCH_1):PAGE442_I22@PURE_QUANTA.Q_CAP(CHIPS)':
 'A': CDS_PINID='A';
NODE_NAME     C7503 1
 '@T6G_MB_LIB.T6G(SCH_1):PAGE453_I23@PURE_QUANTA.Q_CAP(CHIPS)':
 'A': CDS_PINID='A';
NODE_NAME     C7504 1
 '@T6G_MB_LIB.T6G(SCH_1):PAGE464_I19@PURE_QUANTA.Q_CAP(CHIPS)':
 'A': CDS_PINID='A';
NODE_NAME     R868 1
 '@T6G_MB_LIB.T6G(SCH_1):PAGE451_I17@PURE_QUANTA.Q_RES(CHIPS)':
 'A': CDS_PINID='A';
NODE_NAME     R874 1
 '@T6G_MB_LIB.T6G(SCH_1):PAGE451_I21@PURE_QUANTA.Q_RES(CHIPS)':
 'A': CDS_PINID='A';
NODE_NAME     R878 1
 '@T6G_MB_LIB.T6G(SCH_1):PAGE451_I47@PURE_QUANTA.Q_RES(CHIPS)':
 'A': CDS_PINID='A';
NODE_NAME     R880 1
 '@T6G_MB_LIB.T6G(SCH_1):PAGE451_I48@PURE_QUANTA.Q_RES(CHIPS)':
 'A': CDS_PINID='A';
NODE_NAME     R882 1
 '@T6G_MB_LIB.T6G(SCH_1):PAGE451_I49@PURE_QUANTA.Q_RES(CHIPS)':
 'A': CDS_PINID='A';
NODE_NAME     R871 1
 '@T6G_MB_LIB.T6G(SCH_1):PAGE451_I50@PURE_QUANTA.Q_RES(CHIPS)':
 'A': CDS_PINID='A';
NODE_NAME     R885 1
 '@T6G_MB_LIB.T6G(SCH_1):PAGE451_I59@PURE_QUANTA.Q_RES(CHIPS)':
 'A': CDS_PINID='A';
NODE_NAME     R861 1
 '@T6G_MB_LIB.T6G(SCH_1):PAGE451_I74@PURE_QUANTA.Q_RES(CHIPS)':
 'A': CDS_PINID='A';
NODE_NAME     R864 1
 '@T6G_MB_LIB.T6G(SCH_1):PAGE451_I75@PURE_QUANTA.Q_RES(CHIPS)':
 'A': CDS_PINID='A';
NODE_NAME     R887 1
 '@T6G_MB_LIB.T6G(SCH_1):PAGE451_I77@PURE_QUANTA.Q_RES(CHIPS)':
 'A': CDS_PINID='A';
NODE_NAME     R870 1
 '@T6G_MB_LIB.T6G(SCH_1):PAGE451_I86@PURE_QUANTA.Q_RES(CHIPS)':
 'A': CDS_PINID='A';
NODE_NAME     L7 1
 '@T6G_MB_LIB.T6G(SCH_1):PAGE454_I21@PURE_QUANTA.Q_INDUCTOR(CHIPS)':
 '1': CDS_PINID='\1\';
NODE_NAME     C366 1
 '@T6G_MB_LIB.T6G(SCH_1):PAGE454_I24@PURE_QUANTA.Q_CAP(CHIPS)':
 'A': CDS_PINID='A';
NODE_NAME     C368 1
 '@T6G_MB_LIB.T6G(SCH_1):PAGE454_I25@PURE_QUANTA.Q_CAP(CHIPS)':
 'A': CDS_PINID='A';
NODE_NAME     C370 1
 '@T6G_MB_LIB.T6G(SCH_1):PAGE454_I27@PURE_QUANTA.Q_CAP(CHIPS)':
 'A': CDS_PINID='A';
NODE_NAME     C373 1
 '@T6G_MB_LIB.T6G(SCH_1):PAGE454_I28@PURE_QUANTA.Q_CAP(CHIPS)':
 'A': CDS_PINID='A';
NODE_NAME     R909 1
 '@T6G_MB_LIB.T6G(SCH_1):PAGE462_I17@PURE_QUANTA.Q_RES(CHIPS)':
 'A': CDS_PINID='A';
NODE_NAME     R915 1
 '@T6G_MB_LIB.T6G(SCH_1):PAGE462_I22@PURE_QUANTA.Q_RES(CHIPS)':
 'A': CDS_PINID='A';
NODE_NAME     R918 1
 '@T6G_MB_LIB.T6G(SCH_1):PAGE462_I23@PURE_QUANTA.Q_RES(CHIPS)':
 'A': CDS_PINID='A';
NODE_NAME     R920 1
 '@T6G_MB_LIB.T6G(SCH_1):PAGE462_I54@PURE_QUANTA.Q_RES(CHIPS)':
 'A': CDS_PINID='A';
NODE_NAME     R922 1
 '@T6G_MB_LIB.T6G(SCH_1):PAGE462_I55@PURE_QUANTA.Q_RES(CHIPS)':
 'A': CDS_PINID='A';
NODE_NAME     R912 1
 '@T6G_MB_LIB.T6G(SCH_1):PAGE462_I56@PURE_QUANTA.Q_RES(CHIPS)':
 'A': CDS_PINID='A';
NODE_NAME     R925 1
 '@T6G_MB_LIB.T6G(SCH_1):PAGE462_I65@PURE_QUANTA.Q_RES(CHIPS)':
 'A': CDS_PINID='A';
NODE_NAME     R902 1
 '@T6G_MB_LIB.T6G(SCH_1):PAGE462_I80@PURE_QUANTA.Q_RES(CHIPS)':
 'A': CDS_PINID='A';
NODE_NAME     R904 1
 '@T6G_MB_LIB.T6G(SCH_1):PAGE462_I82@PURE_QUANTA.Q_RES(CHIPS)':
 'A': CDS_PINID='A';
NODE_NAME     R927 1
 '@T6G_MB_LIB.T6G(SCH_1):PAGE462_I84@PURE_QUANTA.Q_RES(CHIPS)':
 'A': CDS_PINID='A';
NODE_NAME     R911 1
 '@T6G_MB_LIB.T6G(SCH_1):PAGE462_I93@PURE_QUANTA.Q_RES(CHIPS)':
 'A': CDS_PINID='A';
NODE_NAME     L9 1
 '@T6G_MB_LIB.T6G(SCH_1):PAGE465_I11@PURE_QUANTA.Q_INDUCTOR(CHIPS)':
 '1': CDS_PINID='\1\';
NODE_NAME     C432 1
 '@T6G_MB_LIB.T6G(SCH_1):PAGE465_I17@PURE_QUANTA.Q_CAP(CHIPS)':
 'A': CDS_PINID='A';
NODE_NAME     C434 1
 '@T6G_MB_LIB.T6G(SCH_1):PAGE465_I18@PURE_QUANTA.Q_CAP(CHIPS)':
 'A': CDS_PINID='A';
NODE_NAME     C436 1
 '@T6G_MB_LIB.T6G(SCH_1):PAGE465_I21@PURE_QUANTA.Q_CAP(CHIPS)':
 'A': CDS_PINID='A';
NODE_NAME     C439 1
 '@T6G_MB_LIB.T6G(SCH_1):PAGE465_I23@PURE_QUANTA.Q_CAP(CHIPS)':
 'A': CDS_PINID='A';
NODE_NAME     R1234 1
 '@T6G_MB_LIB.T6G(SCH_1):PAGE263_I194@PURE_QUANTA.Q_RES(CHIPS)':
 'A': CDS_PINID='A';
NODE_NAME     R1388 1
 '@T6G_MB_LIB.T6G(SCH_1):PAGE401_I125@PURE_QUANTA.Q_RES(CHIPS)':
 'A': CDS_PINID='A';
NODE_NAME     R1377 1
 '@T6G_MB_LIB.T6G(SCH_1):PAGE392_I125@PURE_QUANTA.Q_RES(CHIPS)':
 'A': CDS_PINID='A';
NODE_NAME     R1426 1
 '@T6G_MB_LIB.T6G(SCH_1):PAGE451_I114@PURE_QUANTA.Q_RES(CHIPS)':
 'A': CDS_PINID='A';
NODE_NAME     R1434 1
 '@T6G_MB_LIB.T6G(SCH_1):PAGE462_I115@PURE_QUANTA.Q_RES(CHIPS)':
 'A': CDS_PINID='A';
NODE_NAME     R699 1
 '@T6G_MB_LIB.T6G(SCH_1):PAGE400_I106@PURE_QUANTA.Q_RES(CHIPS)':
 'A': CDS_PINID='A';
NODE_NAME     R6730 1
 '@T6G_MB_LIB.T6G(SCH_1):PAGE391_I21@PURE_QUANTA.Q_RES(CHIPS)':
 'A': CDS_PINID='A';
NODE_NAME     R6794 1
 '@T6G_MB_LIB.T6G(SCH_1):PAGE452_I21@PURE_QUANTA.Q_RES(CHIPS)':
 'A': CDS_PINID='A';
NODE_NAME     R6900 1
 '@T6G_MB_LIB.T6G(SCH_1):PAGE463_I19@PURE_QUANTA.Q_RES(CHIPS)':
 'A': CDS_PINID='A';
NODE_NAME     R1465 1
 '@T6G_MB_LIB.T6G(SCH_1):PAGE401_I145@PURE_QUANTA.Q_RES(CHIPS)':
 'A': CDS_PINID='A';
NODE_NAME     R1466 1
 '@T6G_MB_LIB.T6G(SCH_1):PAGE401_I146@PURE_QUANTA.Q_RES(CHIPS)':
 'A': CDS_PINID='A';
NODE_NAME     R1467 1
 '@T6G_MB_LIB.T6G(SCH_1):PAGE401_I147@PURE_QUANTA.Q_RES(CHIPS)':
 'A': CDS_PINID='A';
NODE_NAME     R1464 1
 '@T6G_MB_LIB.T6G(SCH_1):PAGE401_I149@PURE_QUANTA.Q_RES(CHIPS)':
 'A': CDS_PINID='A';
NODE_NAME     R1454 1
 '@T6G_MB_LIB.T6G(SCH_1):PAGE392_I145@PURE_QUANTA.Q_RES(CHIPS)':
 'A': CDS_PINID='A';
NODE_NAME     R1455 1
 '@T6G_MB_LIB.T6G(SCH_1):PAGE392_I146@PURE_QUANTA.Q_RES(CHIPS)':
 'A': CDS_PINID='A';
NODE_NAME     R1461 1
 '@T6G_MB_LIB.T6G(SCH_1):PAGE392_I151@PURE_QUANTA.Q_RES(CHIPS)':
 'A': CDS_PINID='A';
NODE_NAME     R1456 1
 '@T6G_MB_LIB.T6G(SCH_1):PAGE392_I153@PURE_QUANTA.Q_RES(CHIPS)':
 'A': CDS_PINID='A';
NODE_NAME     R1488 1
 '@T6G_MB_LIB.T6G(SCH_1):PAGE451_I132@PURE_QUANTA.Q_RES(CHIPS)':
 'A': CDS_PINID='A';
NODE_NAME     R1499 1
 '@T6G_MB_LIB.T6G(SCH_1):PAGE451_I137@PURE_QUANTA.Q_RES(CHIPS)':
 'A': CDS_PINID='A';
NODE_NAME     R1490 1
 '@T6G_MB_LIB.T6G(SCH_1):PAGE451_I139@PURE_QUANTA.Q_RES(CHIPS)':
 'A': CDS_PINID='A';
NODE_NAME     R1489 1
 '@T6G_MB_LIB.T6G(SCH_1):PAGE451_I140@PURE_QUANTA.Q_RES(CHIPS)':
 'A': CDS_PINID='A';
NODE_NAME     R1511 1
 '@T6G_MB_LIB.T6G(SCH_1):PAGE462_I132@PURE_QUANTA.Q_RES(CHIPS)':
 'A': CDS_PINID='A';
NODE_NAME     R1513 1
 '@T6G_MB_LIB.T6G(SCH_1):PAGE462_I137@PURE_QUANTA.Q_RES(CHIPS)':
 'A': CDS_PINID='A';
NODE_NAME     R1510 1
 '@T6G_MB_LIB.T6G(SCH_1):PAGE462_I139@PURE_QUANTA.Q_RES(CHIPS)':
 'A': CDS_PINID='A';
NODE_NAME     R1512 1
 '@T6G_MB_LIB.T6G(SCH_1):PAGE462_I140@PURE_QUANTA.Q_RES(CHIPS)':
 'A': CDS_PINID='A';
NODE_NAME     R1361 1
 '@T6G_MB_LIB.T6G(SCH_1):PAGE377_I104@PURE_QUANTA.Q_RES(CHIPS)':
 'A': CDS_PINID='A';
NODE_NAME     R1390 1
 '@T6G_MB_LIB.T6G(SCH_1):PAGE377_I105@PURE_QUANTA.Q_RES(CHIPS)':
 'A': CDS_PINID='A';
NODE_NAME     R1393 1
 '@T6G_MB_LIB.T6G(SCH_1):PAGE377_I106@PURE_QUANTA.Q_RES(CHIPS)':
 'A': CDS_PINID='A';
NODE_NAME     R1394 1
 '@T6G_MB_LIB.T6G(SCH_1):PAGE377_I107@PURE_QUANTA.Q_RES(CHIPS)':
 'A': CDS_PINID='A';
NODE_NAME     R1399 1
 '@T6G_MB_LIB.T6G(SCH_1):PAGE377_I108@PURE_QUANTA.Q_RES(CHIPS)':
 'A': CDS_PINID='A';
NODE_NAME     R1402 1
 '@T6G_MB_LIB.T6G(SCH_1):PAGE377_I109@PURE_QUANTA.Q_RES(CHIPS)':
 'A': CDS_PINID='A';
NODE_NAME     R1403 1
 '@T6G_MB_LIB.T6G(SCH_1):PAGE377_I110@PURE_QUANTA.Q_RES(CHIPS)':
 'A': CDS_PINID='A';
NODE_NAME     R1407 1
 '@T6G_MB_LIB.T6G(SCH_1):PAGE377_I111@PURE_QUANTA.Q_RES(CHIPS)':
 'A': CDS_PINID='A';
NODE_NAME     R1437 1
 '@T6G_MB_LIB.T6G(SCH_1):PAGE377_I172@PURE_QUANTA.Q_RES(CHIPS)':
 'A': CDS_PINID='A';
NODE_NAME     R1436 1
 '@T6G_MB_LIB.T6G(SCH_1):PAGE377_I173@PURE_QUANTA.Q_RES(CHIPS)':
 'A': CDS_PINID='A';
NODE_NAME     R1448 1
 '@T6G_MB_LIB.T6G(SCH_1):PAGE377_I174@PURE_QUANTA.Q_RES(CHIPS)':
 'A': CDS_PINID='A';
NODE_NAME     R1451 1
 '@T6G_MB_LIB.T6G(SCH_1):PAGE377_I175@PURE_QUANTA.Q_RES(CHIPS)':
 'A': CDS_PINID='A';
NODE_NAME     R1462 1
 '@T6G_MB_LIB.T6G(SCH_1):PAGE377_I176@PURE_QUANTA.Q_RES(CHIPS)':
 'A': CDS_PINID='A';
NODE_NAME     R1463 1
 '@T6G_MB_LIB.T6G(SCH_1):PAGE377_I177@PURE_QUANTA.Q_RES(CHIPS)':
 'A': CDS_PINID='A';
NODE_NAME     R1468 1
 '@T6G_MB_LIB.T6G(SCH_1):PAGE377_I178@PURE_QUANTA.Q_RES(CHIPS)':
 'A': CDS_PINID='A';
NODE_NAME     R1469 1
 '@T6G_MB_LIB.T6G(SCH_1):PAGE377_I179@PURE_QUANTA.Q_RES(CHIPS)':
 'A': CDS_PINID='A';
NODE_NAME     L27 1
 '@T6G_MB_LIB.T6G(SCH_1):PAGE398_I97@PURE_QUANTA.Q_INDUCTOR(CHIPS)':
 '1': CDS_PINID='\1\';
NODE_NAME     R6701 1
 '@T6G_MB_LIB.T6G(SCH_1):PAGE398_I98@PURE_QUANTA.Q_RES(CHIPS)':
 'A': CDS_PINID='A';
NODE_NAME     L31 1
 '@T6G_MB_LIB.T6G(SCH_1):PAGE443_I88@PURE_QUANTA.Q_INDUCTOR(CHIPS)':
 '1': CDS_PINID='\1\';
NODE_NAME     R704 1
 '@T6G_MB_LIB.T6G(SCH_1):PAGE443_I89@PURE_QUANTA.Q_RES(CHIPS)':
 'A': CDS_PINID='A';
NODE_NAME     L32 1
 '@T6G_MB_LIB.T6G(SCH_1):PAGE454_I88@PURE_QUANTA.Q_INDUCTOR(CHIPS)':
 '1': CDS_PINID='\1\';
NODE_NAME     R857 1
 '@T6G_MB_LIB.T6G(SCH_1):PAGE454_I89@PURE_QUANTA.Q_RES(CHIPS)':
 'A': CDS_PINID='A';
NODE_NAME     L33 1
 '@T6G_MB_LIB.T6G(SCH_1):PAGE465_I88@PURE_QUANTA.Q_INDUCTOR(CHIPS)':
 '1': CDS_PINID='\1\';
NODE_NAME     R897 1
 '@T6G_MB_LIB.T6G(SCH_1):PAGE465_I89@PURE_QUANTA.Q_RES(CHIPS)':
 'A': CDS_PINID='A';
NET_NAME
'P1V8_CPU1_RT_1D_ADC'
 '@T6G_MB_LIB.T6G(SCH_1):P1V8_CPU1_RT_1D_ADC':
 C_SIGNAL='@t6g_mb_lib.t6g(sch_1):p1v8_cpu1_rt_1d_adc';
NODE_NAME     R1234 2
 '@T6G_MB_LIB.T6G(SCH_1):PAGE263_I194@PURE_QUANTA.Q_RES(CHIPS)':
 'B': CDS_PINID='B';
NODE_NAME     R1250 1
 '@T6G_MB_LIB.T6G(SCH_1):PAGE263_I202@PURE_QUANTA.Q_RES(CHIPS)':
 'A': CDS_PINID='A';
NODE_NAME     R1257 1
 '@T6G_MB_LIB.T6G(SCH_1):PAGE263_I203@PURE_QUANTA.Q_RES(CHIPS)':
 'A': CDS_PINID='A';
NODE_NAME     R1223 1
 '@T6G_MB_LIB.T6G(SCH_1):PAGE263_I245@PURE_QUANTA.Q_RES(CHIPS)':
 'A': CDS_PINID='A';
NET_NAME
'P1V8_CPU1_RT_1D_ADC_MAM'
 '@T6G_MB_LIB.T6G(SCH_1):P1V8_CPU1_RT_1D_ADC_MAM':
 C_SIGNAL='@t6g_mb_lib.t6g(sch_1):p1v8_cpu1_rt_1d_adc_mam';
NODE_NAME     U50 9
 '@T6G_MB_LIB.T6G(SCH_1):PAGE263_I156@PURE_QUANTA.MAX11617EEET(CHIPS)':
 'AIN4': CDS_PINID='AIN4';
NODE_NAME     C1083 1
 '@T6G_MB_LIB.T6G(SCH_1):PAGE263_I198@PURE_QUANTA.Q_CAP(CHIPS)':
 'A': CDS_PINID='A';
NODE_NAME     R1250 2
 '@T6G_MB_LIB.T6G(SCH_1):PAGE263_I202@PURE_QUANTA.Q_RES(CHIPS)':
 'B': CDS_PINID='B';
NET_NAME
'P1V8_CPU1_RT_1D_ADC_TIC'
 '@T6G_MB_LIB.T6G(SCH_1):P1V8_CPU1_RT_1D_ADC_TIC':
 C_SIGNAL='@t6g_mb_lib.t6g(sch_1):p1v8_cpu1_rt_1d_adc_tic';
NODE_NAME     U51 12
 '@T6G_MB_LIB.T6G(SCH_1):PAGE263_I142@PURE_QUANTA.ADC128D818CIMTXNOPB(CHIPS)':
 'IN4': CDS_PINID='IN4';
NODE_NAME     C1091 1
 '@T6G_MB_LIB.T6G(SCH_1):PAGE263_I200@PURE_QUANTA.Q_CAP(CHIPS)':
 'A': CDS_PINID='A';
NODE_NAME     R1257 2
 '@T6G_MB_LIB.T6G(SCH_1):PAGE263_I203@PURE_QUANTA.Q_RES(CHIPS)':
 'B': CDS_PINID='B';
NET_NAME
'P1V8_RETIMER_CPU0_CS'
 '@T6G_MB_LIB.T6G(SCH_1):P1V8_RETIMER_CPU0_CS':
 C_SIGNAL='@t6g_mb_lib.t6g(sch_1):p1v8_retimer_cpu0_cs';
NODE_NAME     PR6502 1
 '@T6G_MB_LIB.T6G(SCH_1):PAGE469_I20@PURE_QUANTA.Q_RES(CHIPS)':
 'A': CDS_PINID='A';
NODE_NAME     PU6500 3
 '@T6G_MB_LIB.T6G(SCH_1):PAGE469_I51@PURE_QUANTA.MPQ8633BGLEC838Z(CHIPS)':
 'CS': CDS_PINID='CS';
NET_NAME
'P1V8_RETIMER_CPU0_EN'
 '@T6G_MB_LIB.T6G(SCH_1):P1V8_RETIMER_CPU0_EN':
 C_SIGNAL='@t6g_mb_lib.t6g(sch_1):p1v8_retimer_cpu0_en';
NODE_NAME     C6757 1
 '@T6G_MB_LIB.T6G(SCH_1):PAGE469_I5@PURE_QUANTA.Q_CAP(CHIPS)':
 'A': CDS_PINID='A';
NODE_NAME     PU6500 8
 '@T6G_MB_LIB.T6G(SCH_1):PAGE469_I51@PURE_QUANTA.MPQ8633BGLEC838Z(CHIPS)':
 'EN': CDS_PINID='EN';
NODE_NAME     R6850 1
 '@T6G_MB_LIB.T6G(SCH_1):PAGE79_I146@PURE_QUANTA.Q_RES(CHIPS)':
 'A': CDS_PINID='A';
NET_NAME
'P1V8_RETIMER_CPU0_FB'
 '@T6G_MB_LIB.T6G(SCH_1):P1V8_RETIMER_CPU0_FB':
 C_SIGNAL='@t6g_mb_lib.t6g(sch_1):p1v8_retimer_cpu0_fb';
NODE_NAME     PR6507 1
 '@T6G_MB_LIB.T6G(SCH_1):PAGE469_I33@PURE_QUANTA.Q_RES(CHIPS)':
 'A': CDS_PINID='A';
NODE_NAME     PC6515 1
 '@T6G_MB_LIB.T6G(SCH_1):PAGE469_I34@PURE_QUANTA.Q_CAP(CHIPS)':
 'A': CDS_PINID='A';
NODE_NAME     PR6505 1
 '@T6G_MB_LIB.T6G(SCH_1):PAGE469_I35@PURE_QUANTA.Q_RES(CHIPS)':
 'A': CDS_PINID='A';
NODE_NAME     PU6500 7
 '@T6G_MB_LIB.T6G(SCH_1):PAGE469_I51@PURE_QUANTA.MPQ8633BGLEC838Z(CHIPS)':
 'FB': CDS_PINID='FB';
NET_NAME
'P1V8_RETIMER_CPU0_MODE'
 '@T6G_MB_LIB.T6G(SCH_1):P1V8_RETIMER_CPU0_MODE':
 C_SIGNAL='@t6g_mb_lib.t6g(sch_1):p1v8_retimer_cpu0_mode';
NODE_NAME     PR6500 2
 '@T6G_MB_LIB.T6G(SCH_1):PAGE469_I21@PURE_QUANTA.Q_RES(CHIPS)':
 'B': CDS_PINID='B';
NODE_NAME     PU6500 4
 '@T6G_MB_LIB.T6G(SCH_1):PAGE469_I51@PURE_QUANTA.MPQ8633BGLEC838Z(CHIPS)':
 'MODE': CDS_PINID='MODE';
NET_NAME
'P1V8_RETIMER_CPU0_REF'
 '@T6G_MB_LIB.T6G(SCH_1):P1V8_RETIMER_CPU0_REF':
 C_SIGNAL='@t6g_mb_lib.t6g(sch_1):p1v8_retimer_cpu0_ref';
NODE_NAME     PC6518 1
 '@T6G_MB_LIB.T6G(SCH_1):PAGE469_I26@PURE_QUANTA.Q_CAP(CHIPS)':
 'A': CDS_PINID='A';
NODE_NAME     PU6500 5
 '@T6G_MB_LIB.T6G(SCH_1):PAGE469_I51@PURE_QUANTA.MPQ8633BGLEC838Z(CHIPS)':
 'TRK_REF': CDS_PINID='TRK_REF';
NET_NAME
'P1V8_RETIMER_CPU0_R_EN'
 '@T6G_MB_LIB.T6G(SCH_1):P1V8_RETIMER_CPU0_R_EN':
 C_SIGNAL='@t6g_mb_lib.t6g(sch_1):p1v8_retimer_cpu0_r_en';
NODE_NAME     U18 B15
 '@T6G_MB_LIB.T6G(SCH_1):PAGE79_I94@PURE_QUANTA.LCMXO3LF9400C5BG484C(CHIPS)':
 'PT38B': CDS_PINID='PT38B';
NODE_NAME     R6850 2
 '@T6G_MB_LIB.T6G(SCH_1):PAGE79_I146@PURE_QUANTA.Q_RES(CHIPS)':
 'B': CDS_PINID='B';
NET_NAME
'P1V8_RETIMER_CPU0_VCC'
 '@T6G_MB_LIB.T6G(SCH_1):P1V8_RETIMER_CPU0_VCC':
 C_SIGNAL='@t6g_mb_lib.t6g(sch_1):p1v8_retimer_cpu0_vcc';
NODE_NAME     PC6506 1
 '@T6G_MB_LIB.T6G(SCH_1):PAGE469_I12@PURE_QUANTA.Q_CAP(CHIPS)':
 'A': CDS_PINID='A';
NODE_NAME     PR6501 2
 '@T6G_MB_LIB.T6G(SCH_1):PAGE469_I13@PURE_QUANTA.Q_RES(CHIPS)':
 'B': CDS_PINID='B';
NODE_NAME     PU6500 19
 '@T6G_MB_LIB.T6G(SCH_1):PAGE469_I51@PURE_QUANTA.MPQ8633BGLEC838Z(CHIPS)':
 'VCC': CDS_PINID='VCC';
NET_NAME
'P1V8_RETIMER_CPU1_CS'
 '@T6G_MB_LIB.T6G(SCH_1):P1V8_RETIMER_CPU1_CS':
 C_SIGNAL='@t6g_mb_lib.t6g(sch_1):p1v8_retimer_cpu1_cs';
NODE_NAME     PR6522 1
 '@T6G_MB_LIB.T6G(SCH_1):PAGE470_I20@PURE_QUANTA.Q_RES(CHIPS)':
 'A': CDS_PINID='A';
NODE_NAME     PU6501 3
 '@T6G_MB_LIB.T6G(SCH_1):PAGE470_I51@PURE_QUANTA.MPQ8633BGLEC838Z(CHIPS)':
 'CS': CDS_PINID='CS';
NET_NAME
'P1V8_RETIMER_CPU1_EN'
 '@T6G_MB_LIB.T6G(SCH_1):P1V8_RETIMER_CPU1_EN':
 C_SIGNAL='@t6g_mb_lib.t6g(sch_1):p1v8_retimer_cpu1_en';
NODE_NAME     C105 1
 '@T6G_MB_LIB.T6G(SCH_1):PAGE470_I5@PURE_QUANTA.Q_CAP(CHIPS)':
 'A': CDS_PINID='A';
NODE_NAME     PU6501 8
 '@T6G_MB_LIB.T6G(SCH_1):PAGE470_I51@PURE_QUANTA.MPQ8633BGLEC838Z(CHIPS)':
 'EN': CDS_PINID='EN';
NODE_NAME     R6851 1
 '@T6G_MB_LIB.T6G(SCH_1):PAGE79_I147@PURE_QUANTA.Q_RES(CHIPS)':
 'A': CDS_PINID='A';
NET_NAME
'P1V8_RETIMER_CPU1_FB'
 '@T6G_MB_LIB.T6G(SCH_1):P1V8_RETIMER_CPU1_FB':
 C_SIGNAL='@t6g_mb_lib.t6g(sch_1):p1v8_retimer_cpu1_fb';
NODE_NAME     PR6526 1
 '@T6G_MB_LIB.T6G(SCH_1):PAGE470_I32@PURE_QUANTA.Q_RES(CHIPS)':
 'A': CDS_PINID='A';
NODE_NAME     PC6534 1
 '@T6G_MB_LIB.T6G(SCH_1):PAGE470_I33@PURE_QUANTA.Q_CAP(CHIPS)':
 'A': CDS_PINID='A';
NODE_NAME     PR6524 1
 '@T6G_MB_LIB.T6G(SCH_1):PAGE470_I34@PURE_QUANTA.Q_RES(CHIPS)':
 'A': CDS_PINID='A';
NODE_NAME     PU6501 7
 '@T6G_MB_LIB.T6G(SCH_1):PAGE470_I51@PURE_QUANTA.MPQ8633BGLEC838Z(CHIPS)':
 'FB': CDS_PINID='FB';
NET_NAME
'P1V8_RETIMER_CPU1_MODE'
 '@T6G_MB_LIB.T6G(SCH_1):P1V8_RETIMER_CPU1_MODE':
 C_SIGNAL='@t6g_mb_lib.t6g(sch_1):p1v8_retimer_cpu1_mode';
NODE_NAME     PR6520 2
 '@T6G_MB_LIB.T6G(SCH_1):PAGE470_I21@PURE_QUANTA.Q_RES(CHIPS)':
 'B': CDS_PINID='B';
NODE_NAME     PU6501 4
 '@T6G_MB_LIB.T6G(SCH_1):PAGE470_I51@PURE_QUANTA.MPQ8633BGLEC838Z(CHIPS)':
 'MODE': CDS_PINID='MODE';
NET_NAME
'P1V8_RETIMER_CPU1_REF'
 '@T6G_MB_LIB.T6G(SCH_1):P1V8_RETIMER_CPU1_REF':
 C_SIGNAL='@t6g_mb_lib.t6g(sch_1):p1v8_retimer_cpu1_ref';
NODE_NAME     PC6537 1
 '@T6G_MB_LIB.T6G(SCH_1):PAGE470_I25@PURE_QUANTA.Q_CAP(CHIPS)':
 'A': CDS_PINID='A';
NODE_NAME     PU6501 5
 '@T6G_MB_LIB.T6G(SCH_1):PAGE470_I51@PURE_QUANTA.MPQ8633BGLEC838Z(CHIPS)':
 'TRK_REF': CDS_PINID='TRK_REF';
NET_NAME
'P1V8_RETIMER_CPU1_R_EN'
 '@T6G_MB_LIB.T6G(SCH_1):P1V8_RETIMER_CPU1_R_EN':
 C_SIGNAL='@t6g_mb_lib.t6g(sch_1):p1v8_retimer_cpu1_r_en';
NODE_NAME     U18 A20
 '@T6G_MB_LIB.T6G(SCH_1):PAGE79_I94@PURE_QUANTA.LCMXO3LF9400C5BG484C(CHIPS)':
 'PT43A||R_GPLLT': CDS_PINID='\pt43a||r_gpllt\';
NODE_NAME     R6851 2
 '@T6G_MB_LIB.T6G(SCH_1):PAGE79_I147@PURE_QUANTA.Q_RES(CHIPS)':
 'B': CDS_PINID='B';
NET_NAME
'P1V8_RETIMER_CPU1_VCC'
 '@T6G_MB_LIB.T6G(SCH_1):P1V8_RETIMER_CPU1_VCC':
 C_SIGNAL='@t6g_mb_lib.t6g(sch_1):p1v8_retimer_cpu1_vcc';
NODE_NAME     PC6525 1
 '@T6G_MB_LIB.T6G(SCH_1):PAGE470_I12@PURE_QUANTA.Q_CAP(CHIPS)':
 'A': CDS_PINID='A';
NODE_NAME     PR6521 2
 '@T6G_MB_LIB.T6G(SCH_1):PAGE470_I13@PURE_QUANTA.Q_RES(CHIPS)':
 'B': CDS_PINID='B';
NODE_NAME     PU6501 19
 '@T6G_MB_LIB.T6G(SCH_1):PAGE470_I51@PURE_QUANTA.MPQ8633BGLEC838Z(CHIPS)':
 'VCC': CDS_PINID='VCC';
NET_NAME
'P2E_CPU0_P5_RX_DN'
 '@T6G_MB_LIB.T6G(SCH_1):P2E_CPU0_P5_RX_DN':
 C_SIGNAL='@t6g_mb_lib.t6g(sch_1):p2e_cpu0_p5_rx_dn';
NODE_NAME     U25 E44
 '@T6G_MB_LIB.T6G(SCH_1):PAGE26_I59@PURE_QUANTA.GENOA_SP5(CHIPS)':
 'P5_RXN2': CDS_PINID='P5_RXN2';
NODE_NAME     J41 A21
 '@T6G_MB_LIB.T6G(SCH_1):PAGE348_I176@PURE_QUANTA.SCONN168_ME1016810202011(CHIPS)':
 'PERP1': CDS_PINID='PERP1';
NET_NAME
'P2E_CPU0_P5_RX_DP'
 '@T6G_MB_LIB.T6G(SCH_1):P2E_CPU0_P5_RX_DP':
 C_SIGNAL='@t6g_mb_lib.t6g(sch_1):p2e_cpu0_p5_rx_dp';
NODE_NAME     U25 E43
 '@T6G_MB_LIB.T6G(SCH_1):PAGE26_I59@PURE_QUANTA.GENOA_SP5(CHIPS)':
 'P5_RXP2': CDS_PINID='P5_RXP2';
NODE_NAME     J41 A20
 '@T6G_MB_LIB.T6G(SCH_1):PAGE348_I176@PURE_QUANTA.SCONN168_ME1016810202011(CHIPS)':
 'PERN1': CDS_PINID='PERN1';
NET_NAME
'P2E_CPU0_P5_TX_C_DN'
 '@T6G_MB_LIB.T6G(SCH_1):P2E_CPU0_P5_TX_C_DN':
 C_SIGNAL='@t6g_mb_lib.t6g(sch_1):p2e_cpu0_p5_tx_c_dn';
NODE_NAME     J41 A18
 '@T6G_MB_LIB.T6G(SCH_1):PAGE348_I176@PURE_QUANTA.SCONN168_ME1016810202011(CHIPS)':
 'PERP0': CDS_PINID='PERP0';
NODE_NAME     C2078 2
 '@T6G_MB_LIB.T6G(SCH_1):PAGE26_I157@PURE_QUANTA.Q_CAP_DIFFBUS(CHIPS)':
 '2': CDS_PINID='\2\';
NET_NAME
'P2E_CPU0_P5_TX_C_DP'
 '@T6G_MB_LIB.T6G(SCH_1):P2E_CPU0_P5_TX_C_DP':
 C_SIGNAL='@t6g_mb_lib.t6g(sch_1):p2e_cpu0_p5_tx_c_dp';
NODE_NAME     J41 A17
 '@T6G_MB_LIB.T6G(SCH_1):PAGE348_I176@PURE_QUANTA.SCONN168_ME1016810202011(CHIPS)':
 'PERN0': CDS_PINID='PERN0';
NODE_NAME     C2077 2
 '@T6G_MB_LIB.T6G(SCH_1):PAGE26_I156@PURE_QUANTA.Q_CAP_DIFFBUS(CHIPS)':
 '2': CDS_PINID='\2\';
NET_NAME
'P2E_CPU0_P5_TX_DN'
 '@T6G_MB_LIB.T6G(SCH_1):P2E_CPU0_P5_TX_DN':
 C_SIGNAL='@t6g_mb_lib.t6g(sch_1):p2e_cpu0_p5_tx_dn';
NODE_NAME     U25 C45
 '@T6G_MB_LIB.T6G(SCH_1):PAGE26_I59@PURE_QUANTA.GENOA_SP5(CHIPS)':
 'P5_TXN2': CDS_PINID='P5_TXN2';
NODE_NAME     C2078 1
 '@T6G_MB_LIB.T6G(SCH_1):PAGE26_I157@PURE_QUANTA.Q_CAP_DIFFBUS(CHIPS)':
 '1': CDS_PINID='\1\';
NET_NAME
'P2E_CPU0_P5_TX_DP'
 '@T6G_MB_LIB.T6G(SCH_1):P2E_CPU0_P5_TX_DP':
 C_SIGNAL='@t6g_mb_lib.t6g(sch_1):p2e_cpu0_p5_tx_dp';
NODE_NAME     U25 C44
 '@T6G_MB_LIB.T6G(SCH_1):PAGE26_I59@PURE_QUANTA.GENOA_SP5(CHIPS)':
 'P5_TXP2': CDS_PINID='P5_TXP2';
NODE_NAME     C2077 1
 '@T6G_MB_LIB.T6G(SCH_1):PAGE26_I156@PURE_QUANTA.Q_CAP_DIFFBUS(CHIPS)':
 '1': CDS_PINID='\1\';
NET_NAME
'P2E_MB_BMC_RX_BUF2_C_DN<0>'
 '@T6G_MB_LIB.T6G(SCH_1):P2E_MB_BMC_RX_BUF2_C_DN'<0>:
 C_SIGNAL='@t6g_mb_lib.t6g(sch_1):p2e_mb_bmc_rx_buf2_c_dn(0)';
NODE_NAME     U6000 19
 '@T6G_MB_LIB.T6G(SCH_1):PAGE111_I1@PURE_QUANTA.DS125BR111RTWR(CHIPS)':
 'OUTB-': CDS_PINID='\outb-\';
NODE_NAME     C6008 1
 '@T6G_MB_LIB.T6G(SCH_1):PAGE112_I44@PURE_QUANTA.Q_CAP(CHIPS)':
 'A': CDS_PINID='A';
NET_NAME
'P2E_MB_BMC_RX_BUF2_C_DP<0>'
 '@T6G_MB_LIB.T6G(SCH_1):P2E_MB_BMC_RX_BUF2_C_DP'<0>:
 C_SIGNAL='@t6g_mb_lib.t6g(sch_1):p2e_mb_bmc_rx_buf2_c_dp(0)';
NODE_NAME     U6000 20
 '@T6G_MB_LIB.T6G(SCH_1):PAGE111_I1@PURE_QUANTA.DS125BR111RTWR(CHIPS)':
 'OUTB+': CDS_PINID='\outb+\';
NODE_NAME     C6007 1
 '@T6G_MB_LIB.T6G(SCH_1):PAGE112_I43@PURE_QUANTA.Q_CAP(CHIPS)':
 'A': CDS_PINID='A';
NET_NAME
'P2E_MB_BMC_RX_BUF_C_DN<0>'
 '@T6G_MB_LIB.T6G(SCH_1):P2E_MB_BMC_RX_BUF_C_DN'<0>:
 C_SIGNAL='@t6g_mb_lib.t6g(sch_1):p2e_mb_bmc_rx_buf_c_dn(0)';
NODE_NAME     U237 8
 '@T6G_MB_LIB.T6G(SCH_1):PAGE110_I63@PURE_QUANTA.PI3EQX12902AZLEX(CHIPS)':
 'BON': CDS_PINID='BON';
NODE_NAME     C1869 1
 '@T6G_MB_LIB.T6G(SCH_1):PAGE112_I12@PURE_QUANTA.Q_CAP(CHIPS)':
 'A': CDS_PINID='A';
NET_NAME
'P2E_MB_BMC_RX_BUF_C_DP<0>'
 '@T6G_MB_LIB.T6G(SCH_1):P2E_MB_BMC_RX_BUF_C_DP'<0>:
 C_SIGNAL='@t6g_mb_lib.t6g(sch_1):p2e_mb_bmc_rx_buf_c_dp(0)';
NODE_NAME     U237 9
 '@T6G_MB_LIB.T6G(SCH_1):PAGE110_I63@PURE_QUANTA.PI3EQX12902AZLEX(CHIPS)':
 'BOP': CDS_PINID='BOP';
NODE_NAME     C1868 1
 '@T6G_MB_LIB.T6G(SCH_1):PAGE112_I11@PURE_QUANTA.Q_CAP(CHIPS)':
 'A': CDS_PINID='A';
NET_NAME
'P2E_MB_BMC_RX_BUF_DN<0>'
 '@T6G_MB_LIB.T6G(SCH_1):P2E_MB_BMC_RX_BUF_DN'<0>:
 C_SIGNAL='@t6g_mb_lib.t6g(sch_1):p2e_mb_bmc_rx_buf_dn(0)';
NODE_NAME     J41 A66
 '@T6G_MB_LIB.T6G(SCH_1):PAGE348_I176@PURE_QUANTA.SCONN168_ME1016810202011(CHIPS)':
 'PERP15': CDS_PINID='PERP15';
NODE_NAME     C1869 2
 '@T6G_MB_LIB.T6G(SCH_1):PAGE112_I12@PURE_QUANTA.Q_CAP(CHIPS)':
 'B': CDS_PINID='B';
NODE_NAME     C6008 2
 '@T6G_MB_LIB.T6G(SCH_1):PAGE112_I44@PURE_QUANTA.Q_CAP(CHIPS)':
 'B': CDS_PINID='B';
NET_NAME
'P2E_MB_BMC_RX_BUF_DP<0>'
 '@T6G_MB_LIB.T6G(SCH_1):P2E_MB_BMC_RX_BUF_DP'<0>:
 C_SIGNAL='@t6g_mb_lib.t6g(sch_1):p2e_mb_bmc_rx_buf_dp(0)';
NODE_NAME     J41 A65
 '@T6G_MB_LIB.T6G(SCH_1):PAGE348_I176@PURE_QUANTA.SCONN168_ME1016810202011(CHIPS)':
 'PERN15': CDS_PINID='PERN15';
NODE_NAME     C1868 2
 '@T6G_MB_LIB.T6G(SCH_1):PAGE112_I11@PURE_QUANTA.Q_CAP(CHIPS)':
 'B': CDS_PINID='B';
NODE_NAME     C6007 2
 '@T6G_MB_LIB.T6G(SCH_1):PAGE112_I43@PURE_QUANTA.Q_CAP(CHIPS)':
 'B': CDS_PINID='B';
NET_NAME
'P2E_MB_BMC_RX_DN<0>'
 '@T6G_MB_LIB.T6G(SCH_1):P2E_MB_BMC_RX_DN'<0>:
 C_SIGNAL='@t6g_mb_lib.t6g(sch_1):p2e_mb_bmc_rx_dn(0)';
NODE_NAME     R6157 1
 '@T6G_MB_LIB.T6G(SCH_1):PAGE112_I22@PURE_QUANTA.Q_RES(CHIPS)':
 'A': CDS_PINID='A';
NODE_NAME     R6159 1
 '@T6G_MB_LIB.T6G(SCH_1):PAGE112_I23@PURE_QUANTA.Q_RES(CHIPS)':
 'A': CDS_PINID='A';
NODE_NAME     J112 O6
 '@T6G_MB_LIB.T6G(SCH_1):PAGE329_I7@PURE_QUANTA.CONN160_10131762101LF(CHIPS)':
 'O6': CDS_PINID='O6';
NET_NAME
'P2E_MB_BMC_RX_DP<0>'
 '@T6G_MB_LIB.T6G(SCH_1):P2E_MB_BMC_RX_DP'<0>:
 C_SIGNAL='@t6g_mb_lib.t6g(sch_1):p2e_mb_bmc_rx_dp(0)';
NODE_NAME     R6156 1
 '@T6G_MB_LIB.T6G(SCH_1):PAGE112_I21@PURE_QUANTA.Q_RES(CHIPS)':
 'A': CDS_PINID='A';
NODE_NAME     R6158 1
 '@T6G_MB_LIB.T6G(SCH_1):PAGE112_I24@PURE_QUANTA.Q_RES(CHIPS)':
 'A': CDS_PINID='A';
NODE_NAME     J112 N6
 '@T6G_MB_LIB.T6G(SCH_1):PAGE329_I7@PURE_QUANTA.CONN160_10131762101LF(CHIPS)':
 'N6': CDS_PINID='N6';
NET_NAME
'P2E_MB_BMC_RX_R1_DN<0>'
 '@T6G_MB_LIB.T6G(SCH_1):P2E_MB_BMC_RX_R1_DN'<0>:
 C_SIGNAL='@t6g_mb_lib.t6g(sch_1):p2e_mb_bmc_rx_r1_dn(0)';
NODE_NAME     U237 18
 '@T6G_MB_LIB.T6G(SCH_1):PAGE110_I63@PURE_QUANTA.PI3EQX12902AZLEX(CHIPS)':
 'BIN': CDS_PINID='BIN';
NODE_NAME     R6157 2
 '@T6G_MB_LIB.T6G(SCH_1):PAGE112_I22@PURE_QUANTA.Q_RES(CHIPS)':
 'B': CDS_PINID='B';
NET_NAME
'P2E_MB_BMC_RX_R1_DP<0>'
 '@T6G_MB_LIB.T6G(SCH_1):P2E_MB_BMC_RX_R1_DP'<0>:
 C_SIGNAL='@t6g_mb_lib.t6g(sch_1):p2e_mb_bmc_rx_r1_dp(0)';
NODE_NAME     U237 17
 '@T6G_MB_LIB.T6G(SCH_1):PAGE110_I63@PURE_QUANTA.PI3EQX12902AZLEX(CHIPS)':
 'BIP': CDS_PINID='BIP';
NODE_NAME     R6156 2
 '@T6G_MB_LIB.T6G(SCH_1):PAGE112_I21@PURE_QUANTA.Q_RES(CHIPS)':
 'B': CDS_PINID='B';
NET_NAME
'P2E_MB_BMC_RX_R2_DN<0>'
 '@T6G_MB_LIB.T6G(SCH_1):P2E_MB_BMC_RX_R2_DN'<0>:
 C_SIGNAL='@t6g_mb_lib.t6g(sch_1):p2e_mb_bmc_rx_r2_dn(0)';
NODE_NAME     U6000 12
 '@T6G_MB_LIB.T6G(SCH_1):PAGE111_I1@PURE_QUANTA.DS125BR111RTWR(CHIPS)':
 'INB-': CDS_PINID='\inb-\';
NODE_NAME     R6159 2
 '@T6G_MB_LIB.T6G(SCH_1):PAGE112_I23@PURE_QUANTA.Q_RES(CHIPS)':
 'B': CDS_PINID='B';
NET_NAME
'P2E_MB_BMC_RX_R2_DP<0>'
 '@T6G_MB_LIB.T6G(SCH_1):P2E_MB_BMC_RX_R2_DP'<0>:
 C_SIGNAL='@t6g_mb_lib.t6g(sch_1):p2e_mb_bmc_rx_r2_dp(0)';
NODE_NAME     U6000 11
 '@T6G_MB_LIB.T6G(SCH_1):PAGE111_I1@PURE_QUANTA.DS125BR111RTWR(CHIPS)':
 'INB+': CDS_PINID='\inb+\';
NODE_NAME     R6158 2
 '@T6G_MB_LIB.T6G(SCH_1):PAGE112_I24@PURE_QUANTA.Q_RES(CHIPS)':
 'B': CDS_PINID='B';
NET_NAME
'P2E_MB_BMC_TX_BUF2_DN<0>'
 '@T6G_MB_LIB.T6G(SCH_1):P2E_MB_BMC_TX_BUF2_DN'<0>:
 C_SIGNAL='@t6g_mb_lib.t6g(sch_1):p2e_mb_bmc_tx_buf2_dn(0)';
NODE_NAME     U6000 8
 '@T6G_MB_LIB.T6G(SCH_1):PAGE111_I1@PURE_QUANTA.DS125BR111RTWR(CHIPS)':
 'OUTA-': CDS_PINID='\outa-\';
NODE_NAME     C6006 1
 '@T6G_MB_LIB.T6G(SCH_1):PAGE112_I35@PURE_QUANTA.Q_CAP(CHIPS)':
 'A': CDS_PINID='A';
NET_NAME
'P2E_MB_BMC_TX_BUF2_DP<0>'
 '@T6G_MB_LIB.T6G(SCH_1):P2E_MB_BMC_TX_BUF2_DP'<0>:
 C_SIGNAL='@t6g_mb_lib.t6g(sch_1):p2e_mb_bmc_tx_buf2_dp(0)';
NODE_NAME     U6000 7
 '@T6G_MB_LIB.T6G(SCH_1):PAGE111_I1@PURE_QUANTA.DS125BR111RTWR(CHIPS)':
 'OUTA+': CDS_PINID='\outa+\';
NODE_NAME     C6005 1
 '@T6G_MB_LIB.T6G(SCH_1):PAGE112_I36@PURE_QUANTA.Q_CAP(CHIPS)':
 'A': CDS_PINID='A';
NET_NAME
'P2E_MB_BMC_TX_BUF_C_DN<0>'
 '@T6G_MB_LIB.T6G(SCH_1):P2E_MB_BMC_TX_BUF_C_DN'<0>:
 C_SIGNAL='@t6g_mb_lib.t6g(sch_1):p2e_mb_bmc_tx_buf_c_dn(0)';
NODE_NAME     C1871 2
 '@T6G_MB_LIB.T6G(SCH_1):PAGE112_I14@PURE_QUANTA.Q_CAP(CHIPS)':
 'B': CDS_PINID='B';
NODE_NAME     C6006 2
 '@T6G_MB_LIB.T6G(SCH_1):PAGE112_I35@PURE_QUANTA.Q_CAP(CHIPS)':
 'B': CDS_PINID='B';
NODE_NAME     J112 R6
 '@T6G_MB_LIB.T6G(SCH_1):PAGE329_I7@PURE_QUANTA.CONN160_10131762101LF(CHIPS)':
 'R6': CDS_PINID='R6';
NET_NAME
'P2E_MB_BMC_TX_BUF_C_DP<0>'
 '@T6G_MB_LIB.T6G(SCH_1):P2E_MB_BMC_TX_BUF_C_DP'<0>:
 C_SIGNAL='@t6g_mb_lib.t6g(sch_1):p2e_mb_bmc_tx_buf_c_dp(0)';
NODE_NAME     C1870 2
 '@T6G_MB_LIB.T6G(SCH_1):PAGE112_I13@PURE_QUANTA.Q_CAP(CHIPS)':
 'B': CDS_PINID='B';
NODE_NAME     C6005 2
 '@T6G_MB_LIB.T6G(SCH_1):PAGE112_I36@PURE_QUANTA.Q_CAP(CHIPS)':
 'B': CDS_PINID='B';
NODE_NAME     J112 Q6
 '@T6G_MB_LIB.T6G(SCH_1):PAGE329_I7@PURE_QUANTA.CONN160_10131762101LF(CHIPS)':
 'Q6': CDS_PINID='Q6';
NET_NAME
'P2E_MB_BMC_TX_BUF_DN<0>'
 '@T6G_MB_LIB.T6G(SCH_1):P2E_MB_BMC_TX_BUF_DN'<0>:
 C_SIGNAL='@t6g_mb_lib.t6g(sch_1):p2e_mb_bmc_tx_buf_dn(0)';
NODE_NAME     U237 23
 '@T6G_MB_LIB.T6G(SCH_1):PAGE110_I63@PURE_QUANTA.PI3EQX12902AZLEX(CHIPS)':
 'AON': CDS_PINID='AON';
NODE_NAME     C1871 1
 '@T6G_MB_LIB.T6G(SCH_1):PAGE112_I14@PURE_QUANTA.Q_CAP(CHIPS)':
 'A': CDS_PINID='A';
NET_NAME
'P2E_MB_BMC_TX_BUF_DP<0>'
 '@T6G_MB_LIB.T6G(SCH_1):P2E_MB_BMC_TX_BUF_DP'<0>:
 C_SIGNAL='@t6g_mb_lib.t6g(sch_1):p2e_mb_bmc_tx_buf_dp(0)';
NODE_NAME     U237 24
 '@T6G_MB_LIB.T6G(SCH_1):PAGE110_I63@PURE_QUANTA.PI3EQX12902AZLEX(CHIPS)':
 'AOP': CDS_PINID='AOP';
NODE_NAME     C1870 1
 '@T6G_MB_LIB.T6G(SCH_1):PAGE112_I13@PURE_QUANTA.Q_CAP(CHIPS)':
 'A': CDS_PINID='A';
NET_NAME
'P2E_MB_BMC_TX_C_DN<0>'
 '@T6G_MB_LIB.T6G(SCH_1):P2E_MB_BMC_TX_C_DN'<0>:
 C_SIGNAL='@t6g_mb_lib.t6g(sch_1):p2e_mb_bmc_tx_c_dn(0)';
NODE_NAME     J41 B66
 '@T6G_MB_LIB.T6G(SCH_1):PAGE348_I176@PURE_QUANTA.SCONN168_ME1016810202011(CHIPS)':
 'PETP15': CDS_PINID='PETP15';
NODE_NAME     R6155 1
 '@T6G_MB_LIB.T6G(SCH_1):PAGE112_I2@PURE_QUANTA.Q_RES(CHIPS)':
 'A': CDS_PINID='A';
NODE_NAME     R6153 1
 '@T6G_MB_LIB.T6G(SCH_1):PAGE112_I3@PURE_QUANTA.Q_RES(CHIPS)':
 'A': CDS_PINID='A';
NET_NAME
'P2E_MB_BMC_TX_C_DP<0>'
 '@T6G_MB_LIB.T6G(SCH_1):P2E_MB_BMC_TX_C_DP'<0>:
 C_SIGNAL='@t6g_mb_lib.t6g(sch_1):p2e_mb_bmc_tx_c_dp(0)';
NODE_NAME     J41 B65
 '@T6G_MB_LIB.T6G(SCH_1):PAGE348_I176@PURE_QUANTA.SCONN168_ME1016810202011(CHIPS)':
 'PETN15': CDS_PINID='PETN15';
NODE_NAME     R6154 1
 '@T6G_MB_LIB.T6G(SCH_1):PAGE112_I1@PURE_QUANTA.Q_RES(CHIPS)':
 'A': CDS_PINID='A';
NODE_NAME     R6152 1
 '@T6G_MB_LIB.T6G(SCH_1):PAGE112_I8@PURE_QUANTA.Q_RES(CHIPS)':
 'A': CDS_PINID='A';
NET_NAME
'P2E_MB_BMC_TX_C_R1_DN<0>'
 '@T6G_MB_LIB.T6G(SCH_1):P2E_MB_BMC_TX_C_R1_DN'<0>:
 C_SIGNAL='@t6g_mb_lib.t6g(sch_1):p2e_mb_bmc_tx_c_r1_dn(0)';
NODE_NAME     U237 3
 '@T6G_MB_LIB.T6G(SCH_1):PAGE110_I63@PURE_QUANTA.PI3EQX12902AZLEX(CHIPS)':
 'AIN': CDS_PINID='AIN';
NODE_NAME     R6153 2
 '@T6G_MB_LIB.T6G(SCH_1):PAGE112_I3@PURE_QUANTA.Q_RES(CHIPS)':
 'B': CDS_PINID='B';
NET_NAME
'P2E_MB_BMC_TX_C_R1_DP<0>'
 '@T6G_MB_LIB.T6G(SCH_1):P2E_MB_BMC_TX_C_R1_DP'<0>:
 C_SIGNAL='@t6g_mb_lib.t6g(sch_1):p2e_mb_bmc_tx_c_r1_dp(0)';
NODE_NAME     U237 2
 '@T6G_MB_LIB.T6G(SCH_1):PAGE110_I63@PURE_QUANTA.PI3EQX12902AZLEX(CHIPS)':
 'AIP': CDS_PINID='AIP';
NODE_NAME     R6152 2
 '@T6G_MB_LIB.T6G(SCH_1):PAGE112_I8@PURE_QUANTA.Q_RES(CHIPS)':
 'B': CDS_PINID='B';
NET_NAME
'P2E_MB_BMC_TX_C_R2_DN<0>'
 '@T6G_MB_LIB.T6G(SCH_1):P2E_MB_BMC_TX_C_R2_DN'<0>:
 C_SIGNAL='@t6g_mb_lib.t6g(sch_1):p2e_mb_bmc_tx_c_r2_dn(0)';
NODE_NAME     U6000 23
 '@T6G_MB_LIB.T6G(SCH_1):PAGE111_I1@PURE_QUANTA.DS125BR111RTWR(CHIPS)':
 'INA-': CDS_PINID='\ina-\';
NODE_NAME     R6155 2
 '@T6G_MB_LIB.T6G(SCH_1):PAGE112_I2@PURE_QUANTA.Q_RES(CHIPS)':
 'B': CDS_PINID='B';
NET_NAME
'P2E_MB_BMC_TX_C_R2_DP<0>'
 '@T6G_MB_LIB.T6G(SCH_1):P2E_MB_BMC_TX_C_R2_DP'<0>:
 C_SIGNAL='@t6g_mb_lib.t6g(sch_1):p2e_mb_bmc_tx_c_r2_dp(0)';
NODE_NAME     U6000 24
 '@T6G_MB_LIB.T6G(SCH_1):PAGE111_I1@PURE_QUANTA.DS125BR111RTWR(CHIPS)':
 'INA+': CDS_PINID='\ina+\';
NODE_NAME     R6154 2
 '@T6G_MB_LIB.T6G(SCH_1):PAGE112_I1@PURE_QUANTA.Q_RES(CHIPS)':
 'B': CDS_PINID='B';
NET_NAME
'P3E_CPU0_P4_RX_DN<0>'
 '@T6G_MB_LIB.T6G(SCH_1):P3E_CPU0_P4_RX_DN'<0>:
 C_SIGNAL='@t6g_mb_lib.t6g(sch_1):p3e_cpu0_p4_rx_dn(0)';
NODE_NAME     U25 DG53
 '@T6G_MB_LIB.T6G(SCH_1):PAGE26_I59@PURE_QUANTA.GENOA_SP5(CHIPS)':
 'P4_RXN0': CDS_PINID='P4_RXN0';
NODE_NAME     J90 A18
 '@T6G_MB_LIB.T6G(SCH_1):PAGE297_I90@PURE_QUANTA.SCONN56_123276793(CHIPS)':
 'PER_P0': CDS_PINID='PER_P0';
NET_NAME
'P3E_CPU0_P4_RX_DN<1>'
 '@T6G_MB_LIB.T6G(SCH_1):P3E_CPU0_P4_RX_DN'<1>:
 C_SIGNAL='@t6g_mb_lib.t6g(sch_1):p3e_cpu0_p4_rx_dn(1)';
NODE_NAME     U25 DG50
 '@T6G_MB_LIB.T6G(SCH_1):PAGE26_I59@PURE_QUANTA.GENOA_SP5(CHIPS)':
 'P4_RXN1': CDS_PINID='P4_RXN1';
NODE_NAME     J90 A21
 '@T6G_MB_LIB.T6G(SCH_1):PAGE297_I90@PURE_QUANTA.SCONN56_123276793(CHIPS)':
 'PER_P1': CDS_PINID='PER_P1';
NET_NAME
'P3E_CPU0_P4_RX_DN<2>'
 '@T6G_MB_LIB.T6G(SCH_1):P3E_CPU0_P4_RX_DN'<2>:
 C_SIGNAL='@t6g_mb_lib.t6g(sch_1):p3e_cpu0_p4_rx_dn(2)';
NODE_NAME     U25 DG47
 '@T6G_MB_LIB.T6G(SCH_1):PAGE26_I59@PURE_QUANTA.GENOA_SP5(CHIPS)':
 'P4_RXN2': CDS_PINID='P4_RXN2';
NODE_NAME     J90 A24
 '@T6G_MB_LIB.T6G(SCH_1):PAGE297_I90@PURE_QUANTA.SCONN56_123276793(CHIPS)':
 'PER_P2': CDS_PINID='PER_P2';
NET_NAME
'P3E_CPU0_P4_RX_DN<3>'
 '@T6G_MB_LIB.T6G(SCH_1):P3E_CPU0_P4_RX_DN'<3>:
 C_SIGNAL='@t6g_mb_lib.t6g(sch_1):p3e_cpu0_p4_rx_dn(3)';
NODE_NAME     U25 DG44
 '@T6G_MB_LIB.T6G(SCH_1):PAGE26_I59@PURE_QUANTA.GENOA_SP5(CHIPS)':
 'P4_RXN3': CDS_PINID='P4_RXN3';
NODE_NAME     J90 A27
 '@T6G_MB_LIB.T6G(SCH_1):PAGE297_I90@PURE_QUANTA.SCONN56_123276793(CHIPS)':
 'PER_P3': CDS_PINID='PER_P3';
NET_NAME
'P3E_CPU0_P4_RX_DP<0>'
 '@T6G_MB_LIB.T6G(SCH_1):P3E_CPU0_P4_RX_DP'<0>:
 C_SIGNAL='@t6g_mb_lib.t6g(sch_1):p3e_cpu0_p4_rx_dp(0)';
NODE_NAME     U25 DG54
 '@T6G_MB_LIB.T6G(SCH_1):PAGE26_I59@PURE_QUANTA.GENOA_SP5(CHIPS)':
 'P4_RXP0': CDS_PINID='P4_RXP0';
NODE_NAME     J90 A17
 '@T6G_MB_LIB.T6G(SCH_1):PAGE297_I90@PURE_QUANTA.SCONN56_123276793(CHIPS)':
 'PER_N0': CDS_PINID='PER_N0';
NET_NAME
'P3E_CPU0_P4_RX_DP<1>'
 '@T6G_MB_LIB.T6G(SCH_1):P3E_CPU0_P4_RX_DP'<1>:
 C_SIGNAL='@t6g_mb_lib.t6g(sch_1):p3e_cpu0_p4_rx_dp(1)';
NODE_NAME     U25 DG51
 '@T6G_MB_LIB.T6G(SCH_1):PAGE26_I59@PURE_QUANTA.GENOA_SP5(CHIPS)':
 'P4_RXP1': CDS_PINID='P4_RXP1';
NODE_NAME     J90 A20
 '@T6G_MB_LIB.T6G(SCH_1):PAGE297_I90@PURE_QUANTA.SCONN56_123276793(CHIPS)':
 'PER_N1': CDS_PINID='PER_N1';
NET_NAME
'P3E_CPU0_P4_RX_DP<2>'
 '@T6G_MB_LIB.T6G(SCH_1):P3E_CPU0_P4_RX_DP'<2>:
 C_SIGNAL='@t6g_mb_lib.t6g(sch_1):p3e_cpu0_p4_rx_dp(2)';
NODE_NAME     U25 DG48
 '@T6G_MB_LIB.T6G(SCH_1):PAGE26_I59@PURE_QUANTA.GENOA_SP5(CHIPS)':
 'P4_RXP2': CDS_PINID='P4_RXP2';
NODE_NAME     J90 A23
 '@T6G_MB_LIB.T6G(SCH_1):PAGE297_I90@PURE_QUANTA.SCONN56_123276793(CHIPS)':
 'PER_N2': CDS_PINID='PER_N2';
NET_NAME
'P3E_CPU0_P4_RX_DP<3>'
 '@T6G_MB_LIB.T6G(SCH_1):P3E_CPU0_P4_RX_DP'<3>:
 C_SIGNAL='@t6g_mb_lib.t6g(sch_1):p3e_cpu0_p4_rx_dp(3)';
NODE_NAME     U25 DG45
 '@T6G_MB_LIB.T6G(SCH_1):PAGE26_I59@PURE_QUANTA.GENOA_SP5(CHIPS)':
 'P4_RXP3': CDS_PINID='P4_RXP3';
NODE_NAME     J90 A26
 '@T6G_MB_LIB.T6G(SCH_1):PAGE297_I90@PURE_QUANTA.SCONN56_123276793(CHIPS)':
 'PER_N3': CDS_PINID='PER_N3';
NET_NAME
'P3E_CPU0_P4_TX_C_DN<0>'
 '@T6G_MB_LIB.T6G(SCH_1):P3E_CPU0_P4_TX_C_DN'<0>:
 C_SIGNAL='@t6g_mb_lib.t6g(sch_1):p3e_cpu0_p4_tx_c_dn(0)';
NODE_NAME     C1996 1
 '@T6G_MB_LIB.T6G(SCH_1):PAGE355_I51@PURE_QUANTA.Q_CAP_DIFFBUS(CHIPS)':
 '1': CDS_PINID='\1\';
NODE_NAME     J90 B18
 '@T6G_MB_LIB.T6G(SCH_1):PAGE297_I90@PURE_QUANTA.SCONN56_123276793(CHIPS)':
 'PET_P0': CDS_PINID='PET_P0';
NET_NAME
'P3E_CPU0_P4_TX_C_DN<1>'
 '@T6G_MB_LIB.T6G(SCH_1):P3E_CPU0_P4_TX_C_DN'<1>:
 C_SIGNAL='@t6g_mb_lib.t6g(sch_1):p3e_cpu0_p4_tx_c_dn(1)';
NODE_NAME     C1994 1
 '@T6G_MB_LIB.T6G(SCH_1):PAGE355_I11@PURE_QUANTA.Q_CAP_DIFFBUS(CHIPS)':
 '1': CDS_PINID='\1\';
NODE_NAME     J90 B21
 '@T6G_MB_LIB.T6G(SCH_1):PAGE297_I90@PURE_QUANTA.SCONN56_123276793(CHIPS)':
 'PET_P1': CDS_PINID='PET_P1';
NET_NAME
'P3E_CPU0_P4_TX_C_DN<2>'
 '@T6G_MB_LIB.T6G(SCH_1):P3E_CPU0_P4_TX_C_DN'<2>:
 C_SIGNAL='@t6g_mb_lib.t6g(sch_1):p3e_cpu0_p4_tx_c_dn(2)';
NODE_NAME     C1992 1
 '@T6G_MB_LIB.T6G(SCH_1):PAGE355_I9@PURE_QUANTA.Q_CAP_DIFFBUS(CHIPS)':
 '1': CDS_PINID='\1\';
NODE_NAME     J90 B24
 '@T6G_MB_LIB.T6G(SCH_1):PAGE297_I90@PURE_QUANTA.SCONN56_123276793(CHIPS)':
 'PET_P2': CDS_PINID='PET_P2';
NET_NAME
'P3E_CPU0_P4_TX_C_DN<3>'
 '@T6G_MB_LIB.T6G(SCH_1):P3E_CPU0_P4_TX_C_DN'<3>:
 C_SIGNAL='@t6g_mb_lib.t6g(sch_1):p3e_cpu0_p4_tx_c_dn(3)';
NODE_NAME     C1990 1
 '@T6G_MB_LIB.T6G(SCH_1):PAGE355_I7@PURE_QUANTA.Q_CAP_DIFFBUS(CHIPS)':
 '1': CDS_PINID='\1\';
NODE_NAME     J90 B26
 '@T6G_MB_LIB.T6G(SCH_1):PAGE297_I90@PURE_QUANTA.SCONN56_123276793(CHIPS)':
 'PET_N3': CDS_PINID='PET_N3';
NET_NAME
'P3E_CPU0_P4_TX_C_DP<0>'
 '@T6G_MB_LIB.T6G(SCH_1):P3E_CPU0_P4_TX_C_DP'<0>:
 C_SIGNAL='@t6g_mb_lib.t6g(sch_1):p3e_cpu0_p4_tx_c_dp(0)';
NODE_NAME     C1995 1
 '@T6G_MB_LIB.T6G(SCH_1):PAGE355_I52@PURE_QUANTA.Q_CAP_DIFFBUS(CHIPS)':
 '1': CDS_PINID='\1\';
NODE_NAME     J90 B17
 '@T6G_MB_LIB.T6G(SCH_1):PAGE297_I90@PURE_QUANTA.SCONN56_123276793(CHIPS)':
 'PET_N0': CDS_PINID='PET_N0';
NET_NAME
'P3E_CPU0_P4_TX_C_DP<1>'
 '@T6G_MB_LIB.T6G(SCH_1):P3E_CPU0_P4_TX_C_DP'<1>:
 C_SIGNAL='@t6g_mb_lib.t6g(sch_1):p3e_cpu0_p4_tx_c_dp(1)';
NODE_NAME     C1993 1
 '@T6G_MB_LIB.T6G(SCH_1):PAGE355_I12@PURE_QUANTA.Q_CAP_DIFFBUS(CHIPS)':
 '1': CDS_PINID='\1\';
NODE_NAME     J90 B20
 '@T6G_MB_LIB.T6G(SCH_1):PAGE297_I90@PURE_QUANTA.SCONN56_123276793(CHIPS)':
 'PET_N1': CDS_PINID='PET_N1';
NET_NAME
'P3E_CPU0_P4_TX_C_DP<2>'
 '@T6G_MB_LIB.T6G(SCH_1):P3E_CPU0_P4_TX_C_DP'<2>:
 C_SIGNAL='@t6g_mb_lib.t6g(sch_1):p3e_cpu0_p4_tx_c_dp(2)';
NODE_NAME     C1991 1
 '@T6G_MB_LIB.T6G(SCH_1):PAGE355_I10@PURE_QUANTA.Q_CAP_DIFFBUS(CHIPS)':
 '1': CDS_PINID='\1\';
NODE_NAME     J90 B23
 '@T6G_MB_LIB.T6G(SCH_1):PAGE297_I90@PURE_QUANTA.SCONN56_123276793(CHIPS)':
 'PET_N2': CDS_PINID='PET_N2';
NET_NAME
'P3E_CPU0_P4_TX_C_DP<3>'
 '@T6G_MB_LIB.T6G(SCH_1):P3E_CPU0_P4_TX_C_DP'<3>:
 C_SIGNAL='@t6g_mb_lib.t6g(sch_1):p3e_cpu0_p4_tx_c_dp(3)';
NODE_NAME     C1989 1
 '@T6G_MB_LIB.T6G(SCH_1):PAGE355_I8@PURE_QUANTA.Q_CAP_DIFFBUS(CHIPS)':
 '1': CDS_PINID='\1\';
NODE_NAME     J90 B27
 '@T6G_MB_LIB.T6G(SCH_1):PAGE297_I90@PURE_QUANTA.SCONN56_123276793(CHIPS)':
 'PET_P3': CDS_PINID='PET_P3';
NET_NAME
'P3E_CPU0_P4_TX_DN<0>'
 '@T6G_MB_LIB.T6G(SCH_1):P3E_CPU0_P4_TX_DN'<0>:
 C_SIGNAL='@t6g_mb_lib.t6g(sch_1):p3e_cpu0_p4_tx_dn(0)';
NODE_NAME     U25 DE52
 '@T6G_MB_LIB.T6G(SCH_1):PAGE26_I59@PURE_QUANTA.GENOA_SP5(CHIPS)':
 'P4_TXN0': CDS_PINID='P4_TXN0';
NODE_NAME     C1996 2
 '@T6G_MB_LIB.T6G(SCH_1):PAGE355_I51@PURE_QUANTA.Q_CAP_DIFFBUS(CHIPS)':
 '2': CDS_PINID='\2\';
NET_NAME
'P3E_CPU0_P4_TX_DN<1>'
 '@T6G_MB_LIB.T6G(SCH_1):P3E_CPU0_P4_TX_DN'<1>:
 C_SIGNAL='@t6g_mb_lib.t6g(sch_1):p3e_cpu0_p4_tx_dn(1)';
NODE_NAME     U25 DE49
 '@T6G_MB_LIB.T6G(SCH_1):PAGE26_I59@PURE_QUANTA.GENOA_SP5(CHIPS)':
 'P4_TXN1': CDS_PINID='P4_TXN1';
NODE_NAME     C1994 2
 '@T6G_MB_LIB.T6G(SCH_1):PAGE355_I11@PURE_QUANTA.Q_CAP_DIFFBUS(CHIPS)':
 '2': CDS_PINID='\2\';
NET_NAME
'P3E_CPU0_P4_TX_DN<2>'
 '@T6G_MB_LIB.T6G(SCH_1):P3E_CPU0_P4_TX_DN'<2>:
 C_SIGNAL='@t6g_mb_lib.t6g(sch_1):p3e_cpu0_p4_tx_dn(2)';
NODE_NAME     U25 DE46
 '@T6G_MB_LIB.T6G(SCH_1):PAGE26_I59@PURE_QUANTA.GENOA_SP5(CHIPS)':
 'P4_TXN2': CDS_PINID='P4_TXN2';
NODE_NAME     C1992 2
 '@T6G_MB_LIB.T6G(SCH_1):PAGE355_I9@PURE_QUANTA.Q_CAP_DIFFBUS(CHIPS)':
 '2': CDS_PINID='\2\';
NET_NAME
'P3E_CPU0_P4_TX_DN<3>'
 '@T6G_MB_LIB.T6G(SCH_1):P3E_CPU0_P4_TX_DN'<3>:
 C_SIGNAL='@t6g_mb_lib.t6g(sch_1):p3e_cpu0_p4_tx_dn(3)';
NODE_NAME     U25 DE43
 '@T6G_MB_LIB.T6G(SCH_1):PAGE26_I59@PURE_QUANTA.GENOA_SP5(CHIPS)':
 'P4_TXN3': CDS_PINID='P4_TXN3';
NODE_NAME     C1990 2
 '@T6G_MB_LIB.T6G(SCH_1):PAGE355_I7@PURE_QUANTA.Q_CAP_DIFFBUS(CHIPS)':
 '2': CDS_PINID='\2\';
NET_NAME
'P3E_CPU0_P4_TX_DP<0>'
 '@T6G_MB_LIB.T6G(SCH_1):P3E_CPU0_P4_TX_DP'<0>:
 C_SIGNAL='@t6g_mb_lib.t6g(sch_1):p3e_cpu0_p4_tx_dp(0)';
NODE_NAME     U25 DE53
 '@T6G_MB_LIB.T6G(SCH_1):PAGE26_I59@PURE_QUANTA.GENOA_SP5(CHIPS)':
 'P4_TXP0': CDS_PINID='P4_TXP0';
NODE_NAME     C1995 2
 '@T6G_MB_LIB.T6G(SCH_1):PAGE355_I52@PURE_QUANTA.Q_CAP_DIFFBUS(CHIPS)':
 '2': CDS_PINID='\2\';
NET_NAME
'P3E_CPU0_P4_TX_DP<1>'
 '@T6G_MB_LIB.T6G(SCH_1):P3E_CPU0_P4_TX_DP'<1>:
 C_SIGNAL='@t6g_mb_lib.t6g(sch_1):p3e_cpu0_p4_tx_dp(1)';
NODE_NAME     U25 DE50
 '@T6G_MB_LIB.T6G(SCH_1):PAGE26_I59@PURE_QUANTA.GENOA_SP5(CHIPS)':
 'P4_TXP1': CDS_PINID='P4_TXP1';
NODE_NAME     C1993 2
 '@T6G_MB_LIB.T6G(SCH_1):PAGE355_I12@PURE_QUANTA.Q_CAP_DIFFBUS(CHIPS)':
 '2': CDS_PINID='\2\';
NET_NAME
'P3E_CPU0_P4_TX_DP<2>'
 '@T6G_MB_LIB.T6G(SCH_1):P3E_CPU0_P4_TX_DP'<2>:
 C_SIGNAL='@t6g_mb_lib.t6g(sch_1):p3e_cpu0_p4_tx_dp(2)';
NODE_NAME     U25 DE47
 '@T6G_MB_LIB.T6G(SCH_1):PAGE26_I59@PURE_QUANTA.GENOA_SP5(CHIPS)':
 'P4_TXP2': CDS_PINID='P4_TXP2';
NODE_NAME     C1991 2
 '@T6G_MB_LIB.T6G(SCH_1):PAGE355_I10@PURE_QUANTA.Q_CAP_DIFFBUS(CHIPS)':
 '2': CDS_PINID='\2\';
NET_NAME
'P3E_CPU0_P4_TX_DP<3>'
 '@T6G_MB_LIB.T6G(SCH_1):P3E_CPU0_P4_TX_DP'<3>:
 C_SIGNAL='@t6g_mb_lib.t6g(sch_1):p3e_cpu0_p4_tx_dp(3)';
NODE_NAME     U25 DE44
 '@T6G_MB_LIB.T6G(SCH_1):PAGE26_I59@PURE_QUANTA.GENOA_SP5(CHIPS)':
 'P4_TXP3': CDS_PINID='P4_TXP3';
NODE_NAME     C1989 2
 '@T6G_MB_LIB.T6G(SCH_1):PAGE355_I8@PURE_QUANTA.Q_CAP_DIFFBUS(CHIPS)':
 '2': CDS_PINID='\2\';
NET_NAME
'P3E_CPU1_P4_RX_DN<0>'
 '@T6G_MB_LIB.T6G(SCH_1):P3E_CPU1_P4_RX_DN'<0>:
 C_SIGNAL='@t6g_mb_lib.t6g(sch_1):p3e_cpu1_p4_rx_dn(0)';
NODE_NAME     J59 41
 '@T6G_MB_LIB.T6G(SCH_1):PAGE345_I88@PURE_QUANTA.SCONN75K_APCI0155P004A(CHIPS)':
 'PERN0||SATA-B+': CDS_PINID='\pern0||sata-b+\';
NODE_NAME     U26 DG53
 '@T6G_MB_LIB.T6G(SCH_1):PAGE53_I145@PURE_QUANTA.GENOA_SP5(CHIPS)':
 'P4_RXN0': CDS_PINID='P4_RXN0';
NET_NAME
'P3E_CPU1_P4_RX_DN<1>'
 '@T6G_MB_LIB.T6G(SCH_1):P3E_CPU1_P4_RX_DN'<1>:
 C_SIGNAL='@t6g_mb_lib.t6g(sch_1):p3e_cpu1_p4_rx_dn(1)';
NODE_NAME     J59 29
 '@T6G_MB_LIB.T6G(SCH_1):PAGE345_I88@PURE_QUANTA.SCONN75K_APCI0155P004A(CHIPS)':
 'PERN1': CDS_PINID='PERN1';
NODE_NAME     U26 DG50
 '@T6G_MB_LIB.T6G(SCH_1):PAGE53_I145@PURE_QUANTA.GENOA_SP5(CHIPS)':
 'P4_RXN1': CDS_PINID='P4_RXN1';
NET_NAME
'P3E_CPU1_P4_RX_DN<2>'
 '@T6G_MB_LIB.T6G(SCH_1):P3E_CPU1_P4_RX_DN'<2>:
 C_SIGNAL='@t6g_mb_lib.t6g(sch_1):p3e_cpu1_p4_rx_dn(2)';
NODE_NAME     J59 17
 '@T6G_MB_LIB.T6G(SCH_1):PAGE345_I88@PURE_QUANTA.SCONN75K_APCI0155P004A(CHIPS)':
 'PERN2': CDS_PINID='PERN2';
NODE_NAME     U26 DG47
 '@T6G_MB_LIB.T6G(SCH_1):PAGE53_I145@PURE_QUANTA.GENOA_SP5(CHIPS)':
 'P4_RXN2': CDS_PINID='P4_RXN2';
NET_NAME
'P3E_CPU1_P4_RX_DN<3>'
 '@T6G_MB_LIB.T6G(SCH_1):P3E_CPU1_P4_RX_DN'<3>:
 C_SIGNAL='@t6g_mb_lib.t6g(sch_1):p3e_cpu1_p4_rx_dn(3)';
NODE_NAME     J59 5
 '@T6G_MB_LIB.T6G(SCH_1):PAGE345_I88@PURE_QUANTA.SCONN75K_APCI0155P004A(CHIPS)':
 'PERN3': CDS_PINID='PERN3';
NODE_NAME     U26 DG44
 '@T6G_MB_LIB.T6G(SCH_1):PAGE53_I145@PURE_QUANTA.GENOA_SP5(CHIPS)':
 'P4_RXN3': CDS_PINID='P4_RXN3';
NET_NAME
'P3E_CPU1_P4_RX_DP<0>'
 '@T6G_MB_LIB.T6G(SCH_1):P3E_CPU1_P4_RX_DP'<0>:
 C_SIGNAL='@t6g_mb_lib.t6g(sch_1):p3e_cpu1_p4_rx_dp(0)';
NODE_NAME     J59 43
 '@T6G_MB_LIB.T6G(SCH_1):PAGE345_I88@PURE_QUANTA.SCONN75K_APCI0155P004A(CHIPS)':
 'PERP0||SATA-B-': CDS_PINID='\perp0||sata-b-\';
NODE_NAME     U26 DG54
 '@T6G_MB_LIB.T6G(SCH_1):PAGE53_I145@PURE_QUANTA.GENOA_SP5(CHIPS)':
 'P4_RXP0': CDS_PINID='P4_RXP0';
NET_NAME
'P3E_CPU1_P4_RX_DP<1>'
 '@T6G_MB_LIB.T6G(SCH_1):P3E_CPU1_P4_RX_DP'<1>:
 C_SIGNAL='@t6g_mb_lib.t6g(sch_1):p3e_cpu1_p4_rx_dp(1)';
NODE_NAME     J59 31
 '@T6G_MB_LIB.T6G(SCH_1):PAGE345_I88@PURE_QUANTA.SCONN75K_APCI0155P004A(CHIPS)':
 'PERP1': CDS_PINID='PERP1';
NODE_NAME     U26 DG51
 '@T6G_MB_LIB.T6G(SCH_1):PAGE53_I145@PURE_QUANTA.GENOA_SP5(CHIPS)':
 'P4_RXP1': CDS_PINID='P4_RXP1';
NET_NAME
'P3E_CPU1_P4_RX_DP<2>'
 '@T6G_MB_LIB.T6G(SCH_1):P3E_CPU1_P4_RX_DP'<2>:
 C_SIGNAL='@t6g_mb_lib.t6g(sch_1):p3e_cpu1_p4_rx_dp(2)';
NODE_NAME     J59 19
 '@T6G_MB_LIB.T6G(SCH_1):PAGE345_I88@PURE_QUANTA.SCONN75K_APCI0155P004A(CHIPS)':
 'PERP2': CDS_PINID='PERP2';
NODE_NAME     U26 DG48
 '@T6G_MB_LIB.T6G(SCH_1):PAGE53_I145@PURE_QUANTA.GENOA_SP5(CHIPS)':
 'P4_RXP2': CDS_PINID='P4_RXP2';
NET_NAME
'P3E_CPU1_P4_RX_DP<3>'
 '@T6G_MB_LIB.T6G(SCH_1):P3E_CPU1_P4_RX_DP'<3>:
 C_SIGNAL='@t6g_mb_lib.t6g(sch_1):p3e_cpu1_p4_rx_dp(3)';
NODE_NAME     J59 7
 '@T6G_MB_LIB.T6G(SCH_1):PAGE345_I88@PURE_QUANTA.SCONN75K_APCI0155P004A(CHIPS)':
 'PERP3': CDS_PINID='PERP3';
NODE_NAME     U26 DG45
 '@T6G_MB_LIB.T6G(SCH_1):PAGE53_I145@PURE_QUANTA.GENOA_SP5(CHIPS)':
 'P4_RXP3': CDS_PINID='P4_RXP3';
NET_NAME
'P3E_CPU1_P4_TX_C_DN<0>'
 '@T6G_MB_LIB.T6G(SCH_1):P3E_CPU1_P4_TX_C_DN'<0>:
 C_SIGNAL='@t6g_mb_lib.t6g(sch_1):p3e_cpu1_p4_tx_c_dn(0)';
NODE_NAME     J59 47
 '@T6G_MB_LIB.T6G(SCH_1):PAGE345_I88@PURE_QUANTA.SCONN75K_APCI0155P004A(CHIPS)':
 'PETN0||SATA-A-': CDS_PINID='\petn0||sata-a-\';
NODE_NAME     C9105 1
 '@T6G_MB_LIB.T6G(SCH_1):PAGE355_I161@PURE_QUANTA.Q_CAP_DIFFBUS(CHIPS)':
 '1': CDS_PINID='\1\';
NET_NAME
'P3E_CPU1_P4_TX_C_DN<1>'
 '@T6G_MB_LIB.T6G(SCH_1):P3E_CPU1_P4_TX_C_DN'<1>:
 C_SIGNAL='@t6g_mb_lib.t6g(sch_1):p3e_cpu1_p4_tx_c_dn(1)';
NODE_NAME     J59 35
 '@T6G_MB_LIB.T6G(SCH_1):PAGE345_I88@PURE_QUANTA.SCONN75K_APCI0155P004A(CHIPS)':
 'PETN1': CDS_PINID='PETN1';
NODE_NAME     C9103 1
 '@T6G_MB_LIB.T6G(SCH_1):PAGE355_I137@PURE_QUANTA.Q_CAP_DIFFBUS(CHIPS)':
 '1': CDS_PINID='\1\';
NET_NAME
'P3E_CPU1_P4_TX_C_DN<2>'
 '@T6G_MB_LIB.T6G(SCH_1):P3E_CPU1_P4_TX_C_DN'<2>:
 C_SIGNAL='@t6g_mb_lib.t6g(sch_1):p3e_cpu1_p4_tx_c_dn(2)';
NODE_NAME     J59 23
 '@T6G_MB_LIB.T6G(SCH_1):PAGE345_I88@PURE_QUANTA.SCONN75K_APCI0155P004A(CHIPS)':
 'PETN2': CDS_PINID='PETN2';
NODE_NAME     C1101 1
 '@T6G_MB_LIB.T6G(SCH_1):PAGE355_I135@PURE_QUANTA.Q_CAP_DIFFBUS(CHIPS)':
 '1': CDS_PINID='\1\';
NET_NAME
'P3E_CPU1_P4_TX_C_DN<3>'
 '@T6G_MB_LIB.T6G(SCH_1):P3E_CPU1_P4_TX_C_DN'<3>:
 C_SIGNAL='@t6g_mb_lib.t6g(sch_1):p3e_cpu1_p4_tx_c_dn(3)';
NODE_NAME     J59 11
 '@T6G_MB_LIB.T6G(SCH_1):PAGE345_I88@PURE_QUANTA.SCONN75K_APCI0155P004A(CHIPS)':
 'PETN3': CDS_PINID='PETN3';
NODE_NAME     C1099 1
 '@T6G_MB_LIB.T6G(SCH_1):PAGE355_I133@PURE_QUANTA.Q_CAP_DIFFBUS(CHIPS)':
 '1': CDS_PINID='\1\';
NET_NAME
'P3E_CPU1_P4_TX_C_DP<0>'
 '@T6G_MB_LIB.T6G(SCH_1):P3E_CPU1_P4_TX_C_DP'<0>:
 C_SIGNAL='@t6g_mb_lib.t6g(sch_1):p3e_cpu1_p4_tx_c_dp(0)';
NODE_NAME     J59 49
 '@T6G_MB_LIB.T6G(SCH_1):PAGE345_I88@PURE_QUANTA.SCONN75K_APCI0155P004A(CHIPS)':
 'PETP0||SATA-A+': CDS_PINID='\petp0||sata-a+\';
NODE_NAME     C9104 1
 '@T6G_MB_LIB.T6G(SCH_1):PAGE355_I162@PURE_QUANTA.Q_CAP_DIFFBUS(CHIPS)':
 '1': CDS_PINID='\1\';
NET_NAME
'P3E_CPU1_P4_TX_C_DP<1>'
 '@T6G_MB_LIB.T6G(SCH_1):P3E_CPU1_P4_TX_C_DP'<1>:
 C_SIGNAL='@t6g_mb_lib.t6g(sch_1):p3e_cpu1_p4_tx_c_dp(1)';
NODE_NAME     J59 37
 '@T6G_MB_LIB.T6G(SCH_1):PAGE345_I88@PURE_QUANTA.SCONN75K_APCI0155P004A(CHIPS)':
 'PETP1': CDS_PINID='PETP1';
NODE_NAME     C9102 1
 '@T6G_MB_LIB.T6G(SCH_1):PAGE355_I138@PURE_QUANTA.Q_CAP_DIFFBUS(CHIPS)':
 '1': CDS_PINID='\1\';
NET_NAME
'P3E_CPU1_P4_TX_C_DP<2>'
 '@T6G_MB_LIB.T6G(SCH_1):P3E_CPU1_P4_TX_C_DP'<2>:
 C_SIGNAL='@t6g_mb_lib.t6g(sch_1):p3e_cpu1_p4_tx_c_dp(2)';
NODE_NAME     J59 25
 '@T6G_MB_LIB.T6G(SCH_1):PAGE345_I88@PURE_QUANTA.SCONN75K_APCI0155P004A(CHIPS)':
 'PETP2': CDS_PINID='PETP2';
NODE_NAME     C1100 1
 '@T6G_MB_LIB.T6G(SCH_1):PAGE355_I136@PURE_QUANTA.Q_CAP_DIFFBUS(CHIPS)':
 '1': CDS_PINID='\1\';
NET_NAME
'P3E_CPU1_P4_TX_C_DP<3>'
 '@T6G_MB_LIB.T6G(SCH_1):P3E_CPU1_P4_TX_C_DP'<3>:
 C_SIGNAL='@t6g_mb_lib.t6g(sch_1):p3e_cpu1_p4_tx_c_dp(3)';
NODE_NAME     J59 13
 '@T6G_MB_LIB.T6G(SCH_1):PAGE345_I88@PURE_QUANTA.SCONN75K_APCI0155P004A(CHIPS)':
 'PETP3': CDS_PINID='PETP3';
NODE_NAME     C1098 1
 '@T6G_MB_LIB.T6G(SCH_1):PAGE355_I134@PURE_QUANTA.Q_CAP_DIFFBUS(CHIPS)':
 '1': CDS_PINID='\1\';
NET_NAME
'P3E_CPU1_P4_TX_DN<0>'
 '@T6G_MB_LIB.T6G(SCH_1):P3E_CPU1_P4_TX_DN'<0>:
 C_SIGNAL='@t6g_mb_lib.t6g(sch_1):p3e_cpu1_p4_tx_dn(0)';
NODE_NAME     C9105 2
 '@T6G_MB_LIB.T6G(SCH_1):PAGE355_I161@PURE_QUANTA.Q_CAP_DIFFBUS(CHIPS)':
 '2': CDS_PINID='\2\';
NODE_NAME     U26 DE52
 '@T6G_MB_LIB.T6G(SCH_1):PAGE53_I145@PURE_QUANTA.GENOA_SP5(CHIPS)':
 'P4_TXN0': CDS_PINID='P4_TXN0';
NET_NAME
'P3E_CPU1_P4_TX_DN<1>'
 '@T6G_MB_LIB.T6G(SCH_1):P3E_CPU1_P4_TX_DN'<1>:
 C_SIGNAL='@t6g_mb_lib.t6g(sch_1):p3e_cpu1_p4_tx_dn(1)';
NODE_NAME     C9103 2
 '@T6G_MB_LIB.T6G(SCH_1):PAGE355_I137@PURE_QUANTA.Q_CAP_DIFFBUS(CHIPS)':
 '2': CDS_PINID='\2\';
NODE_NAME     U26 DE49
 '@T6G_MB_LIB.T6G(SCH_1):PAGE53_I145@PURE_QUANTA.GENOA_SP5(CHIPS)':
 'P4_TXN1': CDS_PINID='P4_TXN1';
NET_NAME
'P3E_CPU1_P4_TX_DN<2>'
 '@T6G_MB_LIB.T6G(SCH_1):P3E_CPU1_P4_TX_DN'<2>:
 C_SIGNAL='@t6g_mb_lib.t6g(sch_1):p3e_cpu1_p4_tx_dn(2)';
NODE_NAME     C1101 2
 '@T6G_MB_LIB.T6G(SCH_1):PAGE355_I135@PURE_QUANTA.Q_CAP_DIFFBUS(CHIPS)':
 '2': CDS_PINID='\2\';
NODE_NAME     U26 DE46
 '@T6G_MB_LIB.T6G(SCH_1):PAGE53_I145@PURE_QUANTA.GENOA_SP5(CHIPS)':
 'P4_TXN2': CDS_PINID='P4_TXN2';
NET_NAME
'P3E_CPU1_P4_TX_DN<3>'
 '@T6G_MB_LIB.T6G(SCH_1):P3E_CPU1_P4_TX_DN'<3>:
 C_SIGNAL='@t6g_mb_lib.t6g(sch_1):p3e_cpu1_p4_tx_dn(3)';
NODE_NAME     C1099 2
 '@T6G_MB_LIB.T6G(SCH_1):PAGE355_I133@PURE_QUANTA.Q_CAP_DIFFBUS(CHIPS)':
 '2': CDS_PINID='\2\';
NODE_NAME     U26 DE43
 '@T6G_MB_LIB.T6G(SCH_1):PAGE53_I145@PURE_QUANTA.GENOA_SP5(CHIPS)':
 'P4_TXN3': CDS_PINID='P4_TXN3';
NET_NAME
'P3E_CPU1_P4_TX_DP<0>'
 '@T6G_MB_LIB.T6G(SCH_1):P3E_CPU1_P4_TX_DP'<0>:
 C_SIGNAL='@t6g_mb_lib.t6g(sch_1):p3e_cpu1_p4_tx_dp(0)';
NODE_NAME     C9104 2
 '@T6G_MB_LIB.T6G(SCH_1):PAGE355_I162@PURE_QUANTA.Q_CAP_DIFFBUS(CHIPS)':
 '2': CDS_PINID='\2\';
NODE_NAME     U26 DE53
 '@T6G_MB_LIB.T6G(SCH_1):PAGE53_I145@PURE_QUANTA.GENOA_SP5(CHIPS)':
 'P4_TXP0': CDS_PINID='P4_TXP0';
NET_NAME
'P3E_CPU1_P4_TX_DP<1>'
 '@T6G_MB_LIB.T6G(SCH_1):P3E_CPU1_P4_TX_DP'<1>:
 C_SIGNAL='@t6g_mb_lib.t6g(sch_1):p3e_cpu1_p4_tx_dp(1)';
NODE_NAME     C9102 2
 '@T6G_MB_LIB.T6G(SCH_1):PAGE355_I138@PURE_QUANTA.Q_CAP_DIFFBUS(CHIPS)':
 '2': CDS_PINID='\2\';
NODE_NAME     U26 DE50
 '@T6G_MB_LIB.T6G(SCH_1):PAGE53_I145@PURE_QUANTA.GENOA_SP5(CHIPS)':
 'P4_TXP1': CDS_PINID='P4_TXP1';
NET_NAME
'P3E_CPU1_P4_TX_DP<2>'
 '@T6G_MB_LIB.T6G(SCH_1):P3E_CPU1_P4_TX_DP'<2>:
 C_SIGNAL='@t6g_mb_lib.t6g(sch_1):p3e_cpu1_p4_tx_dp(2)';
NODE_NAME     C1100 2
 '@T6G_MB_LIB.T6G(SCH_1):PAGE355_I136@PURE_QUANTA.Q_CAP_DIFFBUS(CHIPS)':
 '2': CDS_PINID='\2\';
NODE_NAME     U26 DE47
 '@T6G_MB_LIB.T6G(SCH_1):PAGE53_I145@PURE_QUANTA.GENOA_SP5(CHIPS)':
 'P4_TXP2': CDS_PINID='P4_TXP2';
NET_NAME
'P3E_CPU1_P4_TX_DP<3>'
 '@T6G_MB_LIB.T6G(SCH_1):P3E_CPU1_P4_TX_DP'<3>:
 C_SIGNAL='@t6g_mb_lib.t6g(sch_1):p3e_cpu1_p4_tx_dp(3)';
NODE_NAME     C1098 2
 '@T6G_MB_LIB.T6G(SCH_1):PAGE355_I134@PURE_QUANTA.Q_CAP_DIFFBUS(CHIPS)':
 '2': CDS_PINID='\2\';
NODE_NAME     U26 DE44
 '@T6G_MB_LIB.T6G(SCH_1):PAGE53_I145@PURE_QUANTA.GENOA_SP5(CHIPS)':
 'P4_TXP3': CDS_PINID='P4_TXP3';
NET_NAME
'P3E_CPU1_P5_RX_DN<0>'
 '@T6G_MB_LIB.T6G(SCH_1):P3E_CPU1_P5_RX_DN'<0>:
 C_SIGNAL='@t6g_mb_lib.t6g(sch_1):p3e_cpu1_p5_rx_dn(0)';
NODE_NAME     U26 E43
 '@T6G_MB_LIB.T6G(SCH_1):PAGE53_I145@PURE_QUANTA.GENOA_SP5(CHIPS)':
 'P5_RXP2': CDS_PINID='P5_RXP2';
NODE_NAME     J112 N8
 '@T6G_MB_LIB.T6G(SCH_1):PAGE329_I7@PURE_QUANTA.CONN160_10131762101LF(CHIPS)':
 'N8': CDS_PINID='N8';
NET_NAME
'P3E_CPU1_P5_RX_DN<1>'
 '@T6G_MB_LIB.T6G(SCH_1):P3E_CPU1_P5_RX_DN'<1>:
 C_SIGNAL='@t6g_mb_lib.t6g(sch_1):p3e_cpu1_p5_rx_dn(1)';
NODE_NAME     U26 E40
 '@T6G_MB_LIB.T6G(SCH_1):PAGE53_I145@PURE_QUANTA.GENOA_SP5(CHIPS)':
 'P5_RXP3': CDS_PINID='P5_RXP3';
NODE_NAME     J112 O7
 '@T6G_MB_LIB.T6G(SCH_1):PAGE329_I7@PURE_QUANTA.CONN160_10131762101LF(CHIPS)':
 'O7': CDS_PINID='O7';
NET_NAME
'P3E_CPU1_P5_RX_DP<0>'
 '@T6G_MB_LIB.T6G(SCH_1):P3E_CPU1_P5_RX_DP'<0>:
 C_SIGNAL='@t6g_mb_lib.t6g(sch_1):p3e_cpu1_p5_rx_dp(0)';
NODE_NAME     U26 E44
 '@T6G_MB_LIB.T6G(SCH_1):PAGE53_I145@PURE_QUANTA.GENOA_SP5(CHIPS)':
 'P5_RXN2': CDS_PINID='P5_RXN2';
NODE_NAME     J112 O8
 '@T6G_MB_LIB.T6G(SCH_1):PAGE329_I7@PURE_QUANTA.CONN160_10131762101LF(CHIPS)':
 'O8': CDS_PINID='O8';
NET_NAME
'P3E_CPU1_P5_RX_DP<1>'
 '@T6G_MB_LIB.T6G(SCH_1):P3E_CPU1_P5_RX_DP'<1>:
 C_SIGNAL='@t6g_mb_lib.t6g(sch_1):p3e_cpu1_p5_rx_dp(1)';
NODE_NAME     U26 E41
 '@T6G_MB_LIB.T6G(SCH_1):PAGE53_I145@PURE_QUANTA.GENOA_SP5(CHIPS)':
 'P5_RXN3': CDS_PINID='P5_RXN3';
NODE_NAME     J112 P7
 '@T6G_MB_LIB.T6G(SCH_1):PAGE329_I7@PURE_QUANTA.CONN160_10131762101LF(CHIPS)':
 'P7': CDS_PINID='P7';
NET_NAME
'P3E_CPU1_P5_TX_C_DN<0>'
 '@T6G_MB_LIB.T6G(SCH_1):P3E_CPU1_P5_TX_C_DN'<0>:
 C_SIGNAL='@t6g_mb_lib.t6g(sch_1):p3e_cpu1_p5_tx_c_dn(0)';
NODE_NAME     C2076 1
 '@T6G_MB_LIB.T6G(SCH_1):PAGE53_I134@PURE_QUANTA.Q_CAP_DIFFBUS(CHIPS)':
 '1': CDS_PINID='\1\';
NODE_NAME     J112 Q8
 '@T6G_MB_LIB.T6G(SCH_1):PAGE329_I7@PURE_QUANTA.CONN160_10131762101LF(CHIPS)':
 'Q8': CDS_PINID='Q8';
NET_NAME
'P3E_CPU1_P5_TX_C_DN<1>'
 '@T6G_MB_LIB.T6G(SCH_1):P3E_CPU1_P5_TX_C_DN'<1>:
 C_SIGNAL='@t6g_mb_lib.t6g(sch_1):p3e_cpu1_p5_tx_c_dn(1)';
NODE_NAME     C2074 1
 '@T6G_MB_LIB.T6G(SCH_1):PAGE53_I133@PURE_QUANTA.Q_CAP_DIFFBUS(CHIPS)':
 '1': CDS_PINID='\1\';
NODE_NAME     J112 S7
 '@T6G_MB_LIB.T6G(SCH_1):PAGE329_I7@PURE_QUANTA.CONN160_10131762101LF(CHIPS)':
 'S7': CDS_PINID='S7';
NET_NAME
'P3E_CPU1_P5_TX_C_DP<0>'
 '@T6G_MB_LIB.T6G(SCH_1):P3E_CPU1_P5_TX_C_DP'<0>:
 C_SIGNAL='@t6g_mb_lib.t6g(sch_1):p3e_cpu1_p5_tx_c_dp(0)';
NODE_NAME     C2075 1
 '@T6G_MB_LIB.T6G(SCH_1):PAGE53_I135@PURE_QUANTA.Q_CAP_DIFFBUS(CHIPS)':
 '1': CDS_PINID='\1\';
NODE_NAME     J112 R8
 '@T6G_MB_LIB.T6G(SCH_1):PAGE329_I7@PURE_QUANTA.CONN160_10131762101LF(CHIPS)':
 'R8': CDS_PINID='R8';
NET_NAME
'P3E_CPU1_P5_TX_C_DP<1>'
 '@T6G_MB_LIB.T6G(SCH_1):P3E_CPU1_P5_TX_C_DP'<1>:
 C_SIGNAL='@t6g_mb_lib.t6g(sch_1):p3e_cpu1_p5_tx_c_dp(1)';
NODE_NAME     C2073 1
 '@T6G_MB_LIB.T6G(SCH_1):PAGE53_I132@PURE_QUANTA.Q_CAP_DIFFBUS(CHIPS)':
 '1': CDS_PINID='\1\';
NODE_NAME     J112 R7
 '@T6G_MB_LIB.T6G(SCH_1):PAGE329_I7@PURE_QUANTA.CONN160_10131762101LF(CHIPS)':
 'R7': CDS_PINID='R7';
NET_NAME
'P3E_CPU1_P5_TX_DN<0>'
 '@T6G_MB_LIB.T6G(SCH_1):P3E_CPU1_P5_TX_DN'<0>:
 C_SIGNAL='@t6g_mb_lib.t6g(sch_1):p3e_cpu1_p5_tx_dn(0)';
NODE_NAME     C2076 2
 '@T6G_MB_LIB.T6G(SCH_1):PAGE53_I134@PURE_QUANTA.Q_CAP_DIFFBUS(CHIPS)':
 '2': CDS_PINID='\2\';
NODE_NAME     U26 C45
 '@T6G_MB_LIB.T6G(SCH_1):PAGE53_I145@PURE_QUANTA.GENOA_SP5(CHIPS)':
 'P5_TXN2': CDS_PINID='P5_TXN2';
NET_NAME
'P3E_CPU1_P5_TX_DN<1>'
 '@T6G_MB_LIB.T6G(SCH_1):P3E_CPU1_P5_TX_DN'<1>:
 C_SIGNAL='@t6g_mb_lib.t6g(sch_1):p3e_cpu1_p5_tx_dn(1)';
NODE_NAME     C2074 2
 '@T6G_MB_LIB.T6G(SCH_1):PAGE53_I133@PURE_QUANTA.Q_CAP_DIFFBUS(CHIPS)':
 '2': CDS_PINID='\2\';
NODE_NAME     U26 C42
 '@T6G_MB_LIB.T6G(SCH_1):PAGE53_I145@PURE_QUANTA.GENOA_SP5(CHIPS)':
 'P5_TXN3': CDS_PINID='P5_TXN3';
NET_NAME
'P3E_CPU1_P5_TX_DP<0>'
 '@T6G_MB_LIB.T6G(SCH_1):P3E_CPU1_P5_TX_DP'<0>:
 C_SIGNAL='@t6g_mb_lib.t6g(sch_1):p3e_cpu1_p5_tx_dp(0)';
NODE_NAME     C2075 2
 '@T6G_MB_LIB.T6G(SCH_1):PAGE53_I135@PURE_QUANTA.Q_CAP_DIFFBUS(CHIPS)':
 '2': CDS_PINID='\2\';
NODE_NAME     U26 C44
 '@T6G_MB_LIB.T6G(SCH_1):PAGE53_I145@PURE_QUANTA.GENOA_SP5(CHIPS)':
 'P5_TXP2': CDS_PINID='P5_TXP2';
NET_NAME
'P3E_CPU1_P5_TX_DP<1>'
 '@T6G_MB_LIB.T6G(SCH_1):P3E_CPU1_P5_TX_DP'<1>:
 C_SIGNAL='@t6g_mb_lib.t6g(sch_1):p3e_cpu1_p5_tx_dp(1)';
NODE_NAME     C2073 2
 '@T6G_MB_LIB.T6G(SCH_1):PAGE53_I132@PURE_QUANTA.Q_CAP_DIFFBUS(CHIPS)':
 '2': CDS_PINID='\2\';
NODE_NAME     U26 C41
 '@T6G_MB_LIB.T6G(SCH_1):PAGE53_I145@PURE_QUANTA.GENOA_SP5(CHIPS)':
 'P5_TXP3': CDS_PINID='P5_TXP3';
NET_NAME
'P3V3'
 '@T6G_MB_LIB.T6G(SCH_1):P3V3':
 C_SIGNAL='@t6g_mb_lib.t6g(sch_1):p3v3',
 CDS_GLOBAL_NET='TRUE';
NODE_NAME     R88 1
 '@T6G_MB_LIB.T6G(SCH_1):PAGE85_I526@PURE_QUANTA.Q_RES(CHIPS)':
 'A': CDS_PINID='A';
NODE_NAME     R89 1
 '@T6G_MB_LIB.T6G(SCH_1):PAGE85_I528@PURE_QUANTA.Q_RES(CHIPS)':
 'A': CDS_PINID='A';
NODE_NAME     R90 1
 '@T6G_MB_LIB.T6G(SCH_1):PAGE86_I365@PURE_QUANTA.Q_RES(CHIPS)':
 'A': CDS_PINID='A';
NODE_NAME     R91 1
 '@T6G_MB_LIB.T6G(SCH_1):PAGE87_I365@PURE_QUANTA.Q_RES(CHIPS)':
 'A': CDS_PINID='A';
NODE_NAME     R92 1
 '@T6G_MB_LIB.T6G(SCH_1):PAGE88_I367@PURE_QUANTA.Q_RES(CHIPS)':
 'A': CDS_PINID='A';
NODE_NAME     R93 1
 '@T6G_MB_LIB.T6G(SCH_1):PAGE89_I364@PURE_QUANTA.Q_RES(CHIPS)':
 'A': CDS_PINID='A';
NODE_NAME     R94 1
 '@T6G_MB_LIB.T6G(SCH_1):PAGE90_I365@PURE_QUANTA.Q_RES(CHIPS)':
 'A': CDS_PINID='A';
NODE_NAME     R96 1
 '@T6G_MB_LIB.T6G(SCH_1):PAGE91_I187@PURE_QUANTA.Q_RES(CHIPS)':
 'A': CDS_PINID='A';
NODE_NAME     R95 1
 '@T6G_MB_LIB.T6G(SCH_1):PAGE91_I190@PURE_QUANTA.Q_RES(CHIPS)':
 'A': CDS_PINID='A';
NODE_NAME     R97 1
 '@T6G_MB_LIB.T6G(SCH_1):PAGE92_I191@PURE_QUANTA.Q_RES(CHIPS)':
 'A': CDS_PINID='A';
NODE_NAME     R98 1
 '@T6G_MB_LIB.T6G(SCH_1):PAGE93_I189@PURE_QUANTA.Q_RES(CHIPS)':
 'A': CDS_PINID='A';
NODE_NAME     R99 1
 '@T6G_MB_LIB.T6G(SCH_1):PAGE94_I189@PURE_QUANTA.Q_RES(CHIPS)':
 'A': CDS_PINID='A';
NODE_NAME     R100 1
 '@T6G_MB_LIB.T6G(SCH_1):PAGE95_I189@PURE_QUANTA.Q_RES(CHIPS)':
 'A': CDS_PINID='A';
NODE_NAME     R101 1
 '@T6G_MB_LIB.T6G(SCH_1):PAGE96_I189@PURE_QUANTA.Q_RES(CHIPS)':
 'A': CDS_PINID='A';
NODE_NAME     R102 1
 '@T6G_MB_LIB.T6G(SCH_1):PAGE97_I189@PURE_QUANTA.Q_RES(CHIPS)':
 'A': CDS_PINID='A';
NODE_NAME     R103 1
 '@T6G_MB_LIB.T6G(SCH_1):PAGE97_I191@PURE_QUANTA.Q_RES(CHIPS)':
 'A': CDS_PINID='A';
NODE_NAME     R104 1
 '@T6G_MB_LIB.T6G(SCH_1):PAGE98_I190@PURE_QUANTA.Q_RES(CHIPS)':
 'A': CDS_PINID='A';
NODE_NAME     R105 1
 '@T6G_MB_LIB.T6G(SCH_1):PAGE99_I190@PURE_QUANTA.Q_RES(CHIPS)':
 'A': CDS_PINID='A';
NODE_NAME     R106 1
 '@T6G_MB_LIB.T6G(SCH_1):PAGE100_I190@PURE_QUANTA.Q_RES(CHIPS)':
 'A': CDS_PINID='A';
NODE_NAME     R107 1
 '@T6G_MB_LIB.T6G(SCH_1):PAGE101_I190@PURE_QUANTA.Q_RES(CHIPS)':
 'A': CDS_PINID='A';
NODE_NAME     R108 1
 '@T6G_MB_LIB.T6G(SCH_1):PAGE102_I190@PURE_QUANTA.Q_RES(CHIPS)':
 'A': CDS_PINID='A';
NODE_NAME     R109 1
 '@T6G_MB_LIB.T6G(SCH_1):PAGE103_I189@PURE_QUANTA.Q_RES(CHIPS)':
 'A': CDS_PINID='A';
NODE_NAME     R110 1
 '@T6G_MB_LIB.T6G(SCH_1):PAGE103_I192@PURE_QUANTA.Q_RES(CHIPS)':
 'A': CDS_PINID='A';
NODE_NAME     R111 1
 '@T6G_MB_LIB.T6G(SCH_1):PAGE104_I190@PURE_QUANTA.Q_RES(CHIPS)':
 'A': CDS_PINID='A';
NODE_NAME     R112 1
 '@T6G_MB_LIB.T6G(SCH_1):PAGE105_I190@PURE_QUANTA.Q_RES(CHIPS)':
 'A': CDS_PINID='A';
NODE_NAME     R113 1
 '@T6G_MB_LIB.T6G(SCH_1):PAGE106_I190@PURE_QUANTA.Q_RES(CHIPS)':
 'A': CDS_PINID='A';
NODE_NAME     R114 1
 '@T6G_MB_LIB.T6G(SCH_1):PAGE107_I190@PURE_QUANTA.Q_RES(CHIPS)':
 'A': CDS_PINID='A';
NODE_NAME     R115 1
 '@T6G_MB_LIB.T6G(SCH_1):PAGE108_I190@PURE_QUANTA.Q_RES(CHIPS)':
 'A': CDS_PINID='A';
NODE_NAME     D1 1
 '@T6G_MB_LIB.T6G(SCH_1):PAGE273_I27@PURE_QUANTA.BAT547F(CHIPS)':
 '1': CDS_PINID='\1\';
NODE_NAME     Q56 1
 '@T6G_MB_LIB.T6G(SCH_1):PAGE273_I50@PURE_QUANTA.MOSFET_NCH_1D3S(CHIPS)':
 '1': CDS_PINID='\1\';
NODE_NAME     Q56 2
 '@T6G_MB_LIB.T6G(SCH_1):PAGE273_I50@PURE_QUANTA.MOSFET_NCH_1D3S(CHIPS)':
 '2': CDS_PINID='\2\';
NODE_NAME     Q56 3
 '@T6G_MB_LIB.T6G(SCH_1):PAGE273_I50@PURE_QUANTA.MOSFET_NCH_1D3S(CHIPS)':
 '3': CDS_PINID='\3\';
NODE_NAME     C1340 1
 '@T6G_MB_LIB.T6G(SCH_1):PAGE273_I61@PURE_QUANTA.Q_CAP(CHIPS)':
 'A': CDS_PINID='A';
NODE_NAME     C2018 1
 '@T6G_MB_LIB.T6G(SCH_1):PAGE360_I26@PURE_QUANTA.Q_CAP(CHIPS)':
 'A': CDS_PINID='A';
NODE_NAME     R3574 1
 '@T6G_MB_LIB.T6G(SCH_1):PAGE360_I35@PURE_QUANTA.Q_RES(CHIPS)':
 'A': CDS_PINID='A';
NODE_NAME     U264 11
 '@T6G_MB_LIB.T6G(SCH_1):PAGE360_I46@PURE_QUANTA.ISL28022FRZT(CHIPS)':
 'VBUS': CDS_PINID='VBUS';
NODE_NAME     R3634 2
 '@T6G_MB_LIB.T6G(SCH_1):PAGE360_I92@PURE_QUANTA.Q_RES(CHIPS)':
 'B': CDS_PINID='B';
NODE_NAME     C26 1
 '@T6G_MB_LIB.T6G(SCH_1):PAGE137_I29@PURE_QUANTA.Q_CAP(CHIPS)':
 'A': CDS_PINID='A';
NODE_NAME     R78 1
 '@T6G_MB_LIB.T6G(SCH_1):PAGE137_I31@PURE_QUANTA.Q_RES(CHIPS)':
 'A': CDS_PINID='A';
NODE_NAME     R361 1
 '@T6G_MB_LIB.T6G(SCH_1):PAGE137_I40@PURE_QUANTA.Q_RES(CHIPS)':
 'A': CDS_PINID='A';
NODE_NAME     R365 1
 '@T6G_MB_LIB.T6G(SCH_1):PAGE137_I41@PURE_QUANTA.Q_RES(CHIPS)':
 'A': CDS_PINID='A';
NODE_NAME     U5 8
 '@T6G_MB_LIB.T6G(SCH_1):PAGE137_I48@PURE_QUANTA.PCA9617ADP(CHIPS)':
 'VCCB': CDS_PINID='VCCB';
NODE_NAME     R3100 2
 '@T6G_MB_LIB.T6G(SCH_1):PAGE254_I8@PURE_QUANTA.Q_RES(CHIPS)':
 'B': CDS_PINID='B';
NODE_NAME     C61 1
 '@T6G_MB_LIB.T6G(SCH_1):PAGE273_I59@PURE_QUANTA.Q_CAP(CHIPS)':
 'A': CDS_PINID='A';
NODE_NAME     R2908 1
 '@T6G_MB_LIB.T6G(SCH_1):PAGE369_I21@PURE_QUANTA.Q_RES(CHIPS)':
 'A': CDS_PINID='A';
NODE_NAME     U6006 3
 '@T6G_MB_LIB.T6G(SCH_1):PAGE273_I131@PURE_QUANTA.APX80929SAG7(CHIPS)':
 'VCC': CDS_PINID='VCC';
NODE_NAME     C6500 1
 '@T6G_MB_LIB.T6G(SCH_1):PAGE273_I133@PURE_QUANTA.Q_CAP(CHIPS)':
 'A': CDS_PINID='A';
NODE_NAME     R1491 1
 '@T6G_MB_LIB.T6G(SCH_1):PAGE273_I141@PURE_QUANTA.Q_RES(CHIPS)':
 'A': CDS_PINID='A';
NET_NAME
'P3V3_9ZXL045_P0'
 '@T6G_MB_LIB.T6G(SCH_1):P3V3_9ZXL045_P0':
 C_SIGNAL='@t6g_mb_lib.t6g(sch_1):p3v3_9zxl045_p0';
NODE_NAME     R4475 1
 '@T6G_MB_LIB.T6G(SCH_1):PAGE160_I6@PURE_QUANTA.Q_RES(CHIPS)':
 'A': CDS_PINID='A';
NODE_NAME     L19 2
 '@T6G_MB_LIB.T6G(SCH_1):PAGE160_I26@PURE_QUANTA.Q_INDUCTOR(CHIPS)':
 '2': CDS_PINID='\2\';
NODE_NAME     R4493 1
 '@T6G_MB_LIB.T6G(SCH_1):PAGE160_I27@PURE_QUANTA.Q_RES(CHIPS)':
 'A': CDS_PINID='A';
NET_NAME
'P3V3_9ZXL045_P0_VDD'
 '@T6G_MB_LIB.T6G(SCH_1):P3V3_9ZXL045_P0_VDD':
 C_SIGNAL='@t6g_mb_lib.t6g(sch_1):p3v3_9zxl045_p0_vdd',
 CDS_GLOBAL_NET='TRUE';
NODE_NAME     L20 2
 '@T6G_MB_LIB.T6G(SCH_1):PAGE160_I24@PURE_QUANTA.Q_INDUCTOR(CHIPS)':
 '2': CDS_PINID='\2\';
NODE_NAME     C2329 1
 '@T6G_MB_LIB.T6G(SCH_1):PAGE160_I40@PURE_QUANTA.Q_CAP(CHIPS)':
 'A': CDS_PINID='A';
NODE_NAME     C79 1
 '@T6G_MB_LIB.T6G(SCH_1):PAGE160_I41@PURE_QUANTA.Q_CAP(CHIPS)':
 'A': CDS_PINID='A';
NODE_NAME     C80 1
 '@T6G_MB_LIB.T6G(SCH_1):PAGE160_I44@PURE_QUANTA.Q_CAP(CHIPS)':
 'A': CDS_PINID='A';
NODE_NAME     C81 1
 '@T6G_MB_LIB.T6G(SCH_1):PAGE160_I45@PURE_QUANTA.Q_CAP(CHIPS)':
 'A': CDS_PINID='A';
NODE_NAME     C2339 1
 '@T6G_MB_LIB.T6G(SCH_1):PAGE160_I47@PURE_QUANTA.Q_CAP(CHIPS)':
 'A': CDS_PINID='A';
NODE_NAME     U314 12
 '@T6G_MB_LIB.T6G(SCH_1):PAGE160_I63@PURE_QUANTA.9ZXL0451EKILFT(CHIPS)':
 'VDD0': CDS_PINID='VDD0';
NODE_NAME     U314 16
 '@T6G_MB_LIB.T6G(SCH_1):PAGE160_I63@PURE_QUANTA.9ZXL0451EKILFT(CHIPS)':
 'VDD1': CDS_PINID='VDD1';
NODE_NAME     U314 21
 '@T6G_MB_LIB.T6G(SCH_1):PAGE160_I63@PURE_QUANTA.9ZXL0451EKILFT(CHIPS)':
 'VDD2': CDS_PINID='VDD2';
NODE_NAME     U314 25
 '@T6G_MB_LIB.T6G(SCH_1):PAGE160_I63@PURE_QUANTA.9ZXL0451EKILFT(CHIPS)':
 'VDD3': CDS_PINID='VDD3';
NODE_NAME     U314 29
 '@T6G_MB_LIB.T6G(SCH_1):PAGE160_I63@PURE_QUANTA.9ZXL0451EKILFT(CHIPS)':
 'VDD4': CDS_PINID='VDD4';
NODE_NAME     C2328 1
 '@T6G_MB_LIB.T6G(SCH_1):PAGE160_I71@PURE_QUANTA.Q_CAP(CHIPS)':
 'A': CDS_PINID='A';
NET_NAME
'P3V3_9ZXL045_P0_VDDA'
 '@T6G_MB_LIB.T6G(SCH_1):P3V3_9ZXL045_P0_VDDA':
 C_SIGNAL='@t6g_mb_lib.t6g(sch_1):p3v3_9zxl045_p0_vdda',
 CDS_GLOBAL_NET='TRUE';
NODE_NAME     C2334 1
 '@T6G_MB_LIB.T6G(SCH_1):PAGE160_I20@PURE_QUANTA.Q_CAP(CHIPS)':
 'A': CDS_PINID='A';
NODE_NAME     R4493 2
 '@T6G_MB_LIB.T6G(SCH_1):PAGE160_I27@PURE_QUANTA.Q_RES(CHIPS)':
 'B': CDS_PINID='B';
NODE_NAME     U314 31
 '@T6G_MB_LIB.T6G(SCH_1):PAGE160_I63@PURE_QUANTA.9ZXL0451EKILFT(CHIPS)':
 'VDDA': CDS_PINID='VDDA';
NODE_NAME     C76 1
 '@T6G_MB_LIB.T6G(SCH_1):PAGE160_I69@PURE_QUANTA.Q_CAP(CHIPS)':
 'A': CDS_PINID='A';
NET_NAME
'P3V3_9ZXL045_P0_VDDR'
 '@T6G_MB_LIB.T6G(SCH_1):P3V3_9ZXL045_P0_VDDR':
 C_SIGNAL='@t6g_mb_lib.t6g(sch_1):p3v3_9zxl045_p0_vddr',
 CDS_GLOBAL_NET='TRUE';
NODE_NAME     R4475 2
 '@T6G_MB_LIB.T6G(SCH_1):PAGE160_I6@PURE_QUANTA.Q_RES(CHIPS)':
 'B': CDS_PINID='B';
NODE_NAME     C78 1
 '@T6G_MB_LIB.T6G(SCH_1):PAGE160_I18@PURE_QUANTA.Q_CAP(CHIPS)':
 'A': CDS_PINID='A';
NODE_NAME     U314 2
 '@T6G_MB_LIB.T6G(SCH_1):PAGE160_I63@PURE_QUANTA.9ZXL0451EKILFT(CHIPS)':
 'VDDR': CDS_PINID='VDDR';
NODE_NAME     C77 1
 '@T6G_MB_LIB.T6G(SCH_1):PAGE160_I70@PURE_QUANTA.Q_CAP(CHIPS)':
 'A': CDS_PINID='A';
NET_NAME
'P3V3_9ZXL045_P1'
 '@T6G_MB_LIB.T6G(SCH_1):P3V3_9ZXL045_P1':
 C_SIGNAL='@t6g_mb_lib.t6g(sch_1):p3v3_9zxl045_p1';
NODE_NAME     L1 2
 '@T6G_MB_LIB.T6G(SCH_1):PAGE379_I2@PURE_QUANTA.Q_INDUCTOR(CHIPS)':
 '2': CDS_PINID='\2\';
NODE_NAME     R555 1
 '@T6G_MB_LIB.T6G(SCH_1):PAGE379_I20@PURE_QUANTA.Q_RES(CHIPS)':
 'A': CDS_PINID='A';
NODE_NAME     R586 1
 '@T6G_MB_LIB.T6G(SCH_1):PAGE379_I21@PURE_QUANTA.Q_RES(CHIPS)':
 'A': CDS_PINID='A';
NET_NAME
'P3V3_9ZXL045_P1_VDD'
 '@T6G_MB_LIB.T6G(SCH_1):P3V3_9ZXL045_P1_VDD':
 C_SIGNAL='@t6g_mb_lib.t6g(sch_1):p3v3_9zxl045_p1_vdd',
 CDS_GLOBAL_NET='TRUE';
NODE_NAME     L2 2
 '@T6G_MB_LIB.T6G(SCH_1):PAGE379_I32@PURE_QUANTA.Q_INDUCTOR(CHIPS)':
 '2': CDS_PINID='\2\';
NODE_NAME     C58 1
 '@T6G_MB_LIB.T6G(SCH_1):PAGE379_I34@PURE_QUANTA.Q_CAP(CHIPS)':
 'A': CDS_PINID='A';
NODE_NAME     C90 1
 '@T6G_MB_LIB.T6G(SCH_1):PAGE379_I35@PURE_QUANTA.Q_CAP(CHIPS)':
 'A': CDS_PINID='A';
NODE_NAME     C98 1
 '@T6G_MB_LIB.T6G(SCH_1):PAGE379_I36@PURE_QUANTA.Q_CAP(CHIPS)':
 'A': CDS_PINID='A';
NODE_NAME     C99 1
 '@T6G_MB_LIB.T6G(SCH_1):PAGE379_I58@PURE_QUANTA.Q_CAP(CHIPS)':
 'A': CDS_PINID='A';
NODE_NAME     C75 1
 '@T6G_MB_LIB.T6G(SCH_1):PAGE379_I60@PURE_QUANTA.Q_CAP(CHIPS)':
 'A': CDS_PINID='A';
NODE_NAME     U10 12
 '@T6G_MB_LIB.T6G(SCH_1):PAGE379_I63@PURE_QUANTA.9ZXL0451EKILFT(CHIPS)':
 'VDD0': CDS_PINID='VDD0';
NODE_NAME     U10 16
 '@T6G_MB_LIB.T6G(SCH_1):PAGE379_I63@PURE_QUANTA.9ZXL0451EKILFT(CHIPS)':
 'VDD1': CDS_PINID='VDD1';
NODE_NAME     U10 21
 '@T6G_MB_LIB.T6G(SCH_1):PAGE379_I63@PURE_QUANTA.9ZXL0451EKILFT(CHIPS)':
 'VDD2': CDS_PINID='VDD2';
NODE_NAME     U10 25
 '@T6G_MB_LIB.T6G(SCH_1):PAGE379_I63@PURE_QUANTA.9ZXL0451EKILFT(CHIPS)':
 'VDD3': CDS_PINID='VDD3';
NODE_NAME     U10 29
 '@T6G_MB_LIB.T6G(SCH_1):PAGE379_I63@PURE_QUANTA.9ZXL0451EKILFT(CHIPS)':
 'VDD4': CDS_PINID='VDD4';
NODE_NAME     C28 1
 '@T6G_MB_LIB.T6G(SCH_1):PAGE379_I79@PURE_QUANTA.Q_CAP(CHIPS)':
 'A': CDS_PINID='A';
NET_NAME
'P3V3_9ZXL045_P1_VDDA'
 '@T6G_MB_LIB.T6G(SCH_1):P3V3_9ZXL045_P1_VDDA':
 C_SIGNAL='@t6g_mb_lib.t6g(sch_1):p3v3_9zxl045_p1_vdda',
 CDS_GLOBAL_NET='TRUE';
NODE_NAME     R586 2
 '@T6G_MB_LIB.T6G(SCH_1):PAGE379_I21@PURE_QUANTA.Q_RES(CHIPS)':
 'B': CDS_PINID='B';
NODE_NAME     C68 1
 '@T6G_MB_LIB.T6G(SCH_1):PAGE379_I24@PURE_QUANTA.Q_CAP(CHIPS)':
 'A': CDS_PINID='A';
NODE_NAME     U10 31
 '@T6G_MB_LIB.T6G(SCH_1):PAGE379_I63@PURE_QUANTA.9ZXL0451EKILFT(CHIPS)':
 'VDDA': CDS_PINID='VDDA';
NODE_NAME     C82 1
 '@T6G_MB_LIB.T6G(SCH_1):PAGE379_I77@PURE_QUANTA.Q_CAP(CHIPS)':
 'A': CDS_PINID='A';
NET_NAME
'P3V3_9ZXL045_P1_VDDR'
 '@T6G_MB_LIB.T6G(SCH_1):P3V3_9ZXL045_P1_VDDR':
 C_SIGNAL='@t6g_mb_lib.t6g(sch_1):p3v3_9zxl045_p1_vddr',
 CDS_GLOBAL_NET='TRUE';
NODE_NAME     R555 2
 '@T6G_MB_LIB.T6G(SCH_1):PAGE379_I20@PURE_QUANTA.Q_RES(CHIPS)':
 'B': CDS_PINID='B';
NODE_NAME     C84 1
 '@T6G_MB_LIB.T6G(SCH_1):PAGE379_I26@PURE_QUANTA.Q_CAP(CHIPS)':
 'A': CDS_PINID='A';
NODE_NAME     U10 2
 '@T6G_MB_LIB.T6G(SCH_1):PAGE379_I63@PURE_QUANTA.9ZXL0451EKILFT(CHIPS)':
 'VDDR': CDS_PINID='VDDR';
NODE_NAME     C83 1
 '@T6G_MB_LIB.T6G(SCH_1):PAGE379_I78@PURE_QUANTA.Q_CAP(CHIPS)':
 'A': CDS_PINID='A';
NET_NAME
'P3V3_ADC'
 '@T6G_MB_LIB.T6G(SCH_1):P3V3_ADC':
 C_SIGNAL='@t6g_mb_lib.t6g(sch_1):p3v3_adc';
NODE_NAME     R2843 1
 '@T6G_MB_LIB.T6G(SCH_1):PAGE369_I20@PURE_QUANTA.Q_RES(CHIPS)':
 'A': CDS_PINID='A';
NODE_NAME     R2908 2
 '@T6G_MB_LIB.T6G(SCH_1):PAGE369_I21@PURE_QUANTA.Q_RES(CHIPS)':
 'B': CDS_PINID='B';
NODE_NAME     R3684 1
 '@T6G_MB_LIB.T6G(SCH_1):PAGE369_I22@PURE_QUANTA.Q_RES(CHIPS)':
 'A': CDS_PINID='A';
NODE_NAME     R3683 1
 '@T6G_MB_LIB.T6G(SCH_1):PAGE369_I23@PURE_QUANTA.Q_RES(CHIPS)':
 'A': CDS_PINID='A';
NET_NAME
'P3V3_ADC128_2_VCC'
 '@T6G_MB_LIB.T6G(SCH_1):P3V3_ADC128_2_VCC':
 C_SIGNAL='@t6g_mb_lib.t6g(sch_1):p3v3_adc128_2_vcc';
NODE_NAME     C1094 1
 '@T6G_MB_LIB.T6G(SCH_1):PAGE263_I68@PURE_QUANTA.Q_CAP(CHIPS)':
 'A': CDS_PINID='A';
NODE_NAME     L25 2
 '@T6G_MB_LIB.T6G(SCH_1):PAGE263_I69@PURE_QUANTA.Q_INDUCTOR(CHIPS)':
 '2': CDS_PINID='\2\';
NODE_NAME     C1095 1
 '@T6G_MB_LIB.T6G(SCH_1):PAGE263_I130@PURE_QUANTA.Q_CAP(CHIPS)':
 'A': CDS_PINID='A';
NODE_NAME     R1267 1
 '@T6G_MB_LIB.T6G(SCH_1):PAGE263_I131@PURE_QUANTA.Q_RES(CHIPS)':
 'A': CDS_PINID='A';
NODE_NAME     U51 5
 '@T6G_MB_LIB.T6G(SCH_1):PAGE263_I142@PURE_QUANTA.ADC128D818CIMTXNOPB(CHIPS)':
 'V+': CDS_PINID='\v+\';
NET_NAME
'P3V3_ADC128_VCC'
 '@T6G_MB_LIB.T6G(SCH_1):P3V3_ADC128_VCC':
 C_SIGNAL='@t6g_mb_lib.t6g(sch_1):p3v3_adc128_vcc';
NODE_NAME     L16 2
 '@T6G_MB_LIB.T6G(SCH_1):PAGE369_I69@PURE_QUANTA.Q_INDUCTOR(CHIPS)':
 '2': CDS_PINID='\2\';
NODE_NAME     C2051 1
 '@T6G_MB_LIB.T6G(SCH_1):PAGE369_I71@PURE_QUANTA.Q_CAP(CHIPS)':
 'A': CDS_PINID='A';
NODE_NAME     C2052 1
 '@T6G_MB_LIB.T6G(SCH_1):PAGE369_I72@PURE_QUANTA.Q_CAP(CHIPS)':
 'A': CDS_PINID='A';
NODE_NAME     R3689 1
 '@T6G_MB_LIB.T6G(SCH_1):PAGE369_I131@PURE_QUANTA.Q_RES(CHIPS)':
 'A': CDS_PINID='A';
NODE_NAME     U269 5
 '@T6G_MB_LIB.T6G(SCH_1):PAGE369_I142@PURE_QUANTA.ADC128D818CIMTXNOPB(CHIPS)':
 'V+': CDS_PINID='\v+\';
NET_NAME
'P3V3_ADC_MAM'
 '@T6G_MB_LIB.T6G(SCH_1):P3V3_ADC_MAM':
 C_SIGNAL='@t6g_mb_lib.t6g(sch_1):p3v3_adc_mam';
NODE_NAME     R3683 2
 '@T6G_MB_LIB.T6G(SCH_1):PAGE369_I23@PURE_QUANTA.Q_RES(CHIPS)':
 'B': CDS_PINID='B';
NODE_NAME     C2043 1
 '@T6G_MB_LIB.T6G(SCH_1):PAGE369_I55@PURE_QUANTA.Q_CAP(CHIPS)':
 'A': CDS_PINID='A';
NODE_NAME     U193 9
 '@T6G_MB_LIB.T6G(SCH_1):PAGE369_I169@PURE_QUANTA.MAX11617EEET(CHIPS)':
 'AIN4': CDS_PINID='AIN4';
NET_NAME
'P3V3_ADC_TIC'
 '@T6G_MB_LIB.T6G(SCH_1):P3V3_ADC_TIC':
 C_SIGNAL='@t6g_mb_lib.t6g(sch_1):p3v3_adc_tic';
NODE_NAME     R3684 2
 '@T6G_MB_LIB.T6G(SCH_1):PAGE369_I22@PURE_QUANTA.Q_RES(CHIPS)':
 'B': CDS_PINID='B';
NODE_NAME     C2048 1
 '@T6G_MB_LIB.T6G(SCH_1):PAGE369_I32@PURE_QUANTA.Q_CAP(CHIPS)':
 'A': CDS_PINID='A';
NODE_NAME     U269 12
 '@T6G_MB_LIB.T6G(SCH_1):PAGE369_I142@PURE_QUANTA.ADC128D818CIMTXNOPB(CHIPS)':
 'IN4': CDS_PINID='IN4';
NET_NAME
'P3V3_AUX'
 '@T6G_MB_LIB.T6G(SCH_1):P3V3_AUX':
 C_SIGNAL='@t6g_mb_lib.t6g(sch_1):p3v3_aux',
 CDS_GLOBAL_NET='TRUE';
NODE_NAME     R387 1
 '@T6G_MB_LIB.T6G(SCH_1):PAGE27_I388@PURE_QUANTA.Q_RES(CHIPS)':
 'A': CDS_PINID='A';
NODE_NAME     R388 1
 '@T6G_MB_LIB.T6G(SCH_1):PAGE27_I389@PURE_QUANTA.Q_RES(CHIPS)':
 'A': CDS_PINID='A';
NODE_NAME     R390 1
 '@T6G_MB_LIB.T6G(SCH_1):PAGE27_I390@PURE_QUANTA.Q_RES(CHIPS)':
 'A': CDS_PINID='A';
NODE_NAME     R389 1
 '@T6G_MB_LIB.T6G(SCH_1):PAGE27_I391@PURE_QUANTA.Q_RES(CHIPS)':
 'A': CDS_PINID='A';
NODE_NAME     R391 1
 '@T6G_MB_LIB.T6G(SCH_1):PAGE27_I392@PURE_QUANTA.Q_RES(CHIPS)':
 'A': CDS_PINID='A';
NODE_NAME     R396 1
 '@T6G_MB_LIB.T6G(SCH_1):PAGE27_I393@PURE_QUANTA.Q_RES(CHIPS)':
 'A': CDS_PINID='A';
NODE_NAME     R397 1
 '@T6G_MB_LIB.T6G(SCH_1):PAGE27_I394@PURE_QUANTA.Q_RES(CHIPS)':
 'A': CDS_PINID='A';
NODE_NAME     R499 1
 '@T6G_MB_LIB.T6G(SCH_1):PAGE34_I4@PURE_QUANTA.Q_RES(CHIPS)':
 'A': CDS_PINID='A';
NODE_NAME     R590 1
 '@T6G_MB_LIB.T6G(SCH_1):PAGE34_I5@PURE_QUANTA.Q_RES(CHIPS)':
 'A': CDS_PINID='A';
NODE_NAME     U27 8
 '@T6G_MB_LIB.T6G(SCH_1):PAGE34_I18@PURE_QUANTA.PCA9617ADP(CHIPS)':
 'VCCB': CDS_PINID='VCCB';
NODE_NAME     C43 1
 '@T6G_MB_LIB.T6G(SCH_1):PAGE34_I47@PURE_QUANTA.Q_CAP(CHIPS)':
 'A': CDS_PINID='A';
NODE_NAME     R517 1
 '@T6G_MB_LIB.T6G(SCH_1):PAGE54_I387@PURE_QUANTA.Q_RES(CHIPS)':
 'A': CDS_PINID='A';
NODE_NAME     R522 1
 '@T6G_MB_LIB.T6G(SCH_1):PAGE54_I388@PURE_QUANTA.Q_RES(CHIPS)':
 'A': CDS_PINID='A';
NODE_NAME     R513 1
 '@T6G_MB_LIB.T6G(SCH_1):PAGE54_I390@PURE_QUANTA.Q_RES(CHIPS)':
 'A': CDS_PINID='A';
NODE_NAME     R515 1
 '@T6G_MB_LIB.T6G(SCH_1):PAGE54_I391@PURE_QUANTA.Q_RES(CHIPS)':
 'A': CDS_PINID='A';
NODE_NAME     R512 1
 '@T6G_MB_LIB.T6G(SCH_1):PAGE54_I400@PURE_QUANTA.Q_RES(CHIPS)':
 'A': CDS_PINID='A';
NODE_NAME     R514 1
 '@T6G_MB_LIB.T6G(SCH_1):PAGE54_I401@PURE_QUANTA.Q_RES(CHIPS)':
 'A': CDS_PINID='A';
NODE_NAME     R516 1
 '@T6G_MB_LIB.T6G(SCH_1):PAGE54_I402@PURE_QUANTA.Q_RES(CHIPS)':
 'A': CDS_PINID='A';
NODE_NAME     C1104 1
 '@T6G_MB_LIB.T6G(SCH_1):PAGE76_I50@PURE_QUANTA.Q_CAP(CHIPS)':
 'A': CDS_PINID='A';
NODE_NAME     C1105 1
 '@T6G_MB_LIB.T6G(SCH_1):PAGE76_I59@PURE_QUANTA.Q_CAP(CHIPS)':
 'A': CDS_PINID='A';
NODE_NAME     U53 15
 '@T6G_MB_LIB.T6G(SCH_1):PAGE76_I63@PURE_QUANTA.SN74AVC4T774PWR(CHIPS)':
 'VCCB': CDS_PINID='VCCB';
NODE_NAME     U54 11
 '@T6G_MB_LIB.T6G(SCH_1):PAGE76_I67@PURE_QUANTA.PI4ULS3V304AZMAEX(CHIPS)':
 'VCCB': CDS_PINID='VCCB';
NODE_NAME     R610 1
 '@T6G_MB_LIB.T6G(SCH_1):PAGE76_I97@PURE_QUANTA.Q_RES(CHIPS)':
 'A': CDS_PINID='A';
NODE_NAME     C88 1
 '@T6G_MB_LIB.T6G(SCH_1):PAGE85_I523@PURE_QUANTA.Q_CAP(CHIPS)':
 'A': CDS_PINID='A';
NODE_NAME     J15 3
 '@T6G_MB_LIB.T6G(SCH_1):PAGE86_I350@PURE_QUANTA.SCONN288_DDR506112002KQ(CHIPS)':
 'VIN_MGMT': CDS_PINID='VIN_MGMT';
NODE_NAME     C92 1
 '@T6G_MB_LIB.T6G(SCH_1):PAGE86_I362@PURE_QUANTA.Q_CAP(CHIPS)':
 'A': CDS_PINID='A';
NODE_NAME     J17 3
 '@T6G_MB_LIB.T6G(SCH_1):PAGE87_I350@PURE_QUANTA.SCONN288_DDR506112002KQ(CHIPS)':
 'VIN_MGMT': CDS_PINID='VIN_MGMT';
NODE_NAME     C96 1
 '@T6G_MB_LIB.T6G(SCH_1):PAGE87_I362@PURE_QUANTA.Q_CAP(CHIPS)':
 'A': CDS_PINID='A';
NODE_NAME     J19 3
 '@T6G_MB_LIB.T6G(SCH_1):PAGE88_I350@PURE_QUANTA.SCONN288_DDR506112002KQ(CHIPS)':
 'VIN_MGMT': CDS_PINID='VIN_MGMT';
NODE_NAME     C100 1
 '@T6G_MB_LIB.T6G(SCH_1):PAGE88_I362@PURE_QUANTA.Q_CAP(CHIPS)':
 'A': CDS_PINID='A';
NODE_NAME     J21 3
 '@T6G_MB_LIB.T6G(SCH_1):PAGE89_I348@PURE_QUANTA.SCONN288_DDR506112002KQ(CHIPS)':
 'VIN_MGMT': CDS_PINID='VIN_MGMT';
NODE_NAME     C104 1
 '@T6G_MB_LIB.T6G(SCH_1):PAGE89_I360@PURE_QUANTA.Q_CAP(CHIPS)':
 'A': CDS_PINID='A';
NODE_NAME     J23 3
 '@T6G_MB_LIB.T6G(SCH_1):PAGE90_I350@PURE_QUANTA.SCONN288_DDR506112002KQ(CHIPS)':
 'VIN_MGMT': CDS_PINID='VIN_MGMT';
NODE_NAME     C108 1
 '@T6G_MB_LIB.T6G(SCH_1):PAGE90_I361@PURE_QUANTA.Q_CAP(CHIPS)':
 'A': CDS_PINID='A';
NODE_NAME     J16 3
 '@T6G_MB_LIB.T6G(SCH_1):PAGE91_I22@PURE_QUANTA.SCONN288_DDR506112002KQ(CHIPS)':
 'VIN_MGMT': CDS_PINID='VIN_MGMT';
NODE_NAME     C112 1
 '@T6G_MB_LIB.T6G(SCH_1):PAGE91_I183@PURE_QUANTA.Q_CAP(CHIPS)':
 'A': CDS_PINID='A';
NODE_NAME     J69 3
 '@T6G_MB_LIB.T6G(SCH_1):PAGE92_I22@PURE_QUANTA.SCONN288_DDR506112002KQ(CHIPS)':
 'VIN_MGMT': CDS_PINID='VIN_MGMT';
NODE_NAME     C116 1
 '@T6G_MB_LIB.T6G(SCH_1):PAGE92_I186@PURE_QUANTA.Q_CAP(CHIPS)':
 'A': CDS_PINID='A';
NODE_NAME     J18 3
 '@T6G_MB_LIB.T6G(SCH_1):PAGE93_I22@PURE_QUANTA.SCONN288_DDR506112002KQ(CHIPS)':
 'VIN_MGMT': CDS_PINID='VIN_MGMT';
NODE_NAME     C120 1
 '@T6G_MB_LIB.T6G(SCH_1):PAGE93_I185@PURE_QUANTA.Q_CAP(CHIPS)':
 'A': CDS_PINID='A';
NODE_NAME     J68 3
 '@T6G_MB_LIB.T6G(SCH_1):PAGE94_I22@PURE_QUANTA.SCONN288_DDR506112002KQ(CHIPS)':
 'VIN_MGMT': CDS_PINID='VIN_MGMT';
NODE_NAME     C124 1
 '@T6G_MB_LIB.T6G(SCH_1):PAGE94_I185@PURE_QUANTA.Q_CAP(CHIPS)':
 'A': CDS_PINID='A';
NODE_NAME     J20 3
 '@T6G_MB_LIB.T6G(SCH_1):PAGE95_I22@PURE_QUANTA.SCONN288_DDR506112002KQ(CHIPS)':
 'VIN_MGMT': CDS_PINID='VIN_MGMT';
NODE_NAME     C128 1
 '@T6G_MB_LIB.T6G(SCH_1):PAGE95_I185@PURE_QUANTA.Q_CAP(CHIPS)':
 'A': CDS_PINID='A';
NODE_NAME     J67 3
 '@T6G_MB_LIB.T6G(SCH_1):PAGE96_I22@PURE_QUANTA.SCONN288_DDR506112002KQ(CHIPS)':
 'VIN_MGMT': CDS_PINID='VIN_MGMT';
NODE_NAME     C132 1
 '@T6G_MB_LIB.T6G(SCH_1):PAGE96_I185@PURE_QUANTA.Q_CAP(CHIPS)':
 'A': CDS_PINID='A';
NODE_NAME     J24 3
 '@T6G_MB_LIB.T6G(SCH_1):PAGE97_I22@PURE_QUANTA.SCONN288_DDR506112002KQ(CHIPS)':
 'VIN_MGMT': CDS_PINID='VIN_MGMT';
NODE_NAME     C136 1
 '@T6G_MB_LIB.T6G(SCH_1):PAGE97_I185@PURE_QUANTA.Q_CAP(CHIPS)':
 'A': CDS_PINID='A';
NODE_NAME     J26 3
 '@T6G_MB_LIB.T6G(SCH_1):PAGE98_I22@PURE_QUANTA.SCONN288_DDR506112002KQ(CHIPS)':
 'VIN_MGMT': CDS_PINID='VIN_MGMT';
NODE_NAME     C140 1
 '@T6G_MB_LIB.T6G(SCH_1):PAGE98_I185@PURE_QUANTA.Q_CAP(CHIPS)':
 'A': CDS_PINID='A';
NODE_NAME     J28 3
 '@T6G_MB_LIB.T6G(SCH_1):PAGE99_I22@PURE_QUANTA.SCONN288_DDR506112002KQ(CHIPS)':
 'VIN_MGMT': CDS_PINID='VIN_MGMT';
NODE_NAME     C144 1
 '@T6G_MB_LIB.T6G(SCH_1):PAGE99_I185@PURE_QUANTA.Q_CAP(CHIPS)':
 'A': CDS_PINID='A';
NODE_NAME     J30 3
 '@T6G_MB_LIB.T6G(SCH_1):PAGE100_I52@PURE_QUANTA.SCONN288_DDR506112002KQ(CHIPS)':
 'VIN_MGMT': CDS_PINID='VIN_MGMT';
NODE_NAME     C148 1
 '@T6G_MB_LIB.T6G(SCH_1):PAGE100_I185@PURE_QUANTA.Q_CAP(CHIPS)':
 'A': CDS_PINID='A';
NODE_NAME     J32 3
 '@T6G_MB_LIB.T6G(SCH_1):PAGE101_I52@PURE_QUANTA.SCONN288_DDR506112002KQ(CHIPS)':
 'VIN_MGMT': CDS_PINID='VIN_MGMT';
NODE_NAME     C152 1
 '@T6G_MB_LIB.T6G(SCH_1):PAGE101_I185@PURE_QUANTA.Q_CAP(CHIPS)':
 'A': CDS_PINID='A';
NODE_NAME     J33 3
 '@T6G_MB_LIB.T6G(SCH_1):PAGE102_I22@PURE_QUANTA.SCONN288_DDR506112002KQ(CHIPS)':
 'VIN_MGMT': CDS_PINID='VIN_MGMT';
NODE_NAME     C156 1
 '@T6G_MB_LIB.T6G(SCH_1):PAGE102_I185@PURE_QUANTA.Q_CAP(CHIPS)':
 'A': CDS_PINID='A';
NODE_NAME     J102 3
 '@T6G_MB_LIB.T6G(SCH_1):PAGE103_I22@PURE_QUANTA.SCONN288_DDR506112002KQ(CHIPS)':
 'VIN_MGMT': CDS_PINID='VIN_MGMT';
NODE_NAME     C160 1
 '@T6G_MB_LIB.T6G(SCH_1):PAGE103_I185@PURE_QUANTA.Q_CAP(CHIPS)':
 'A': CDS_PINID='A';
NODE_NAME     J27 3
 '@T6G_MB_LIB.T6G(SCH_1):PAGE104_I22@PURE_QUANTA.SCONN288_DDR506112002KQ(CHIPS)':
 'VIN_MGMT': CDS_PINID='VIN_MGMT';
NODE_NAME     C164 1
 '@T6G_MB_LIB.T6G(SCH_1):PAGE104_I185@PURE_QUANTA.Q_CAP(CHIPS)':
 'A': CDS_PINID='A';
NODE_NAME     J100 3
 '@T6G_MB_LIB.T6G(SCH_1):PAGE105_I22@PURE_QUANTA.SCONN288_DDR506112002KQ(CHIPS)':
 'VIN_MGMT': CDS_PINID='VIN_MGMT';
NODE_NAME     C168 1
 '@T6G_MB_LIB.T6G(SCH_1):PAGE105_I185@PURE_QUANTA.Q_CAP(CHIPS)':
 'A': CDS_PINID='A';
NODE_NAME     J29 3
 '@T6G_MB_LIB.T6G(SCH_1):PAGE106_I22@PURE_QUANTA.SCONN288_DDR506112002KQ(CHIPS)':
 'VIN_MGMT': CDS_PINID='VIN_MGMT';
NODE_NAME     C172 1
 '@T6G_MB_LIB.T6G(SCH_1):PAGE106_I185@PURE_QUANTA.Q_CAP(CHIPS)':
 'A': CDS_PINID='A';
NODE_NAME     J99 3
 '@T6G_MB_LIB.T6G(SCH_1):PAGE107_I22@PURE_QUANTA.SCONN288_DDR506112002KQ(CHIPS)':
 'VIN_MGMT': CDS_PINID='VIN_MGMT';
NODE_NAME     C176 1
 '@T6G_MB_LIB.T6G(SCH_1):PAGE107_I185@PURE_QUANTA.Q_CAP(CHIPS)':
 'A': CDS_PINID='A';
NODE_NAME     J37 3
 '@T6G_MB_LIB.T6G(SCH_1):PAGE108_I22@PURE_QUANTA.SCONN288_DDR506112002KQ(CHIPS)':
 'VIN_MGMT': CDS_PINID='VIN_MGMT';
NODE_NAME     C180 1
 '@T6G_MB_LIB.T6G(SCH_1):PAGE108_I185@PURE_QUANTA.Q_CAP(CHIPS)':
 'A': CDS_PINID='A';
NODE_NAME     U105 10
 '@T6G_MB_LIB.T6G(SCH_1):PAGE136_I47@PURE_QUANTA.PI3CSW12ZUAEX(CHIPS)':
 'VDD': CDS_PINID='VDD';
NODE_NAME     C1336 1
 '@T6G_MB_LIB.T6G(SCH_1):PAGE136_I50@PURE_QUANTA.Q_CAP(CHIPS)':
 'A': CDS_PINID='A';
NODE_NAME     U106 10
 '@T6G_MB_LIB.T6G(SCH_1):PAGE136_I54@PURE_QUANTA.PI3CSW12ZUAEX(CHIPS)':
 'VDD': CDS_PINID='VDD';
NODE_NAME     C1337 1
 '@T6G_MB_LIB.T6G(SCH_1):PAGE136_I56@PURE_QUANTA.Q_CAP(CHIPS)':
 'A': CDS_PINID='A';
NODE_NAME     C1338 1
 '@T6G_MB_LIB.T6G(SCH_1):PAGE136_I61@PURE_QUANTA.Q_CAP(CHIPS)':
 'A': CDS_PINID='A';
NODE_NAME     U107 10
 '@T6G_MB_LIB.T6G(SCH_1):PAGE136_I63@PURE_QUANTA.PI3CSW12ZUAEX(CHIPS)':
 'VDD': CDS_PINID='VDD';
NODE_NAME     C1339 1
 '@T6G_MB_LIB.T6G(SCH_1):PAGE136_I66@PURE_QUANTA.Q_CAP(CHIPS)':
 'A': CDS_PINID='A';
NODE_NAME     U108 10
 '@T6G_MB_LIB.T6G(SCH_1):PAGE136_I68@PURE_QUANTA.PI3CSW12ZUAEX(CHIPS)':
 'VDD': CDS_PINID='VDD';
NODE_NAME     U116 15
 '@T6G_MB_LIB.T6G(SCH_1):PAGE141_I117@PURE_QUANTA.SN74AVC4T774PWR(CHIPS)':
 'VCCB': CDS_PINID='VCCB';
NODE_NAME     C1354 1
 '@T6G_MB_LIB.T6G(SCH_1):PAGE141_I133@PURE_QUANTA.Q_CAP(CHIPS)':
 'A': CDS_PINID='A';
NODE_NAME     R821 1
 '@T6G_MB_LIB.T6G(SCH_1):PAGE141_I185@PURE_QUANTA.Q_RES(CHIPS)':
 'A': CDS_PINID='A';
NODE_NAME     R825 1
 '@T6G_MB_LIB.T6G(SCH_1):PAGE141_I203@PURE_QUANTA.Q_RES(CHIPS)':
 'A': CDS_PINID='A';
NODE_NAME     R824 1
 '@T6G_MB_LIB.T6G(SCH_1):PAGE141_I204@PURE_QUANTA.Q_RES(CHIPS)':
 'A': CDS_PINID='A';
NODE_NAME     R823 1
 '@T6G_MB_LIB.T6G(SCH_1):PAGE141_I205@PURE_QUANTA.Q_RES(CHIPS)':
 'A': CDS_PINID='A';
NODE_NAME     R822 1
 '@T6G_MB_LIB.T6G(SCH_1):PAGE141_I206@PURE_QUANTA.Q_RES(CHIPS)':
 'A': CDS_PINID='A';
NODE_NAME     R950 2
 '@T6G_MB_LIB.T6G(SCH_1):PAGE143_I3@PURE_QUANTA.Q_RES(CHIPS)':
 'B': CDS_PINID='B';
NODE_NAME     R946 1
 '@T6G_MB_LIB.T6G(SCH_1):PAGE143_I5@PURE_QUANTA.Q_RES(CHIPS)':
 'A': CDS_PINID='A';
NODE_NAME     R948 2
 '@T6G_MB_LIB.T6G(SCH_1):PAGE143_I7@PURE_QUANTA.Q_RES(CHIPS)':
 'B': CDS_PINID='B';
NODE_NAME     R947 1
 '@T6G_MB_LIB.T6G(SCH_1):PAGE143_I11@PURE_QUANTA.Q_RES(CHIPS)':
 'A': CDS_PINID='A';
NODE_NAME     R944 1
 '@T6G_MB_LIB.T6G(SCH_1):PAGE143_I15@PURE_QUANTA.Q_RES(CHIPS)':
 'A': CDS_PINID='A';
NODE_NAME     R945 1
 '@T6G_MB_LIB.T6G(SCH_1):PAGE143_I18@PURE_QUANTA.Q_RES(CHIPS)':
 'A': CDS_PINID='A';
NODE_NAME     R1734 1
 '@T6G_MB_LIB.T6G(SCH_1):PAGE148_I244@PURE_QUANTA.Q_RES(CHIPS)':
 'A': CDS_PINID='A';
NODE_NAME     R1731 1
 '@T6G_MB_LIB.T6G(SCH_1):PAGE148_I245@PURE_QUANTA.Q_RES(CHIPS)':
 'A': CDS_PINID='A';
NODE_NAME     R1728 1
 '@T6G_MB_LIB.T6G(SCH_1):PAGE148_I249@PURE_QUANTA.Q_RES(CHIPS)':
 'A': CDS_PINID='A';
NODE_NAME     R1727 1
 '@T6G_MB_LIB.T6G(SCH_1):PAGE148_I250@PURE_QUANTA.Q_RES(CHIPS)':
 'A': CDS_PINID='A';
NODE_NAME     R1747 1
 '@T6G_MB_LIB.T6G(SCH_1):PAGE148_I255@PURE_QUANTA.Q_RES(CHIPS)':
 'A': CDS_PINID='A';
NODE_NAME     R1746 1
 '@T6G_MB_LIB.T6G(SCH_1):PAGE148_I256@PURE_QUANTA.Q_RES(CHIPS)':
 'A': CDS_PINID='A';
NODE_NAME     R1745 1
 '@T6G_MB_LIB.T6G(SCH_1):PAGE148_I257@PURE_QUANTA.Q_RES(CHIPS)':
 'A': CDS_PINID='A';
NODE_NAME     R1744 1
 '@T6G_MB_LIB.T6G(SCH_1):PAGE148_I261@PURE_QUANTA.Q_RES(CHIPS)':
 'A': CDS_PINID='A';
NODE_NAME     U160 16
 '@T6G_MB_LIB.T6G(SCH_1):PAGE148_I266@PURE_QUANTA.74LV4052PW(CHIPS)':
 'VCC': CDS_PINID='VCC';
NODE_NAME     C1554 1
 '@T6G_MB_LIB.T6G(SCH_1):PAGE148_I293@PURE_QUANTA.Q_CAP(CHIPS)':
 'A': CDS_PINID='A';
NODE_NAME     C194 1
 '@T6G_MB_LIB.T6G(SCH_1):PAGE148_I299@PURE_QUANTA.Q_CAP(CHIPS)':
 'A': CDS_PINID='A';
NODE_NAME     U212 16
 '@T6G_MB_LIB.T6G(SCH_1):PAGE148_I302@PURE_QUANTA.74LV4052PW(CHIPS)':
 'VCC': CDS_PINID='VCC';
NODE_NAME     R1730 1
 '@T6G_MB_LIB.T6G(SCH_1):PAGE148_I305@PURE_QUANTA.Q_RES(CHIPS)':
 'A': CDS_PINID='A';
NODE_NAME     R1659 1
 '@T6G_MB_LIB.T6G(SCH_1):PAGE148_I309@PURE_QUANTA.Q_RES(CHIPS)':
 'A': CDS_PINID='A';
NODE_NAME     R1343 1
 '@T6G_MB_LIB.T6G(SCH_1):PAGE148_I339@PURE_QUANTA.Q_RES(CHIPS)':
 'A': CDS_PINID='A';
NODE_NAME     U99 5
 '@T6G_MB_LIB.T6G(SCH_1):PAGE148_I340@PURE_QUANTA.SN74LVC1G07DBVR(CHIPS)':
 'VCC': CDS_PINID='VCC';
NODE_NAME     C553 1
 '@T6G_MB_LIB.T6G(SCH_1):PAGE148_I342@PURE_QUANTA.Q_CAP(CHIPS)':
 'A': CDS_PINID='A';
NODE_NAME     U147 10
 '@T6G_MB_LIB.T6G(SCH_1):PAGE149_I1@PURE_QUANTA.SN74AVC2T245RSWR(CHIPS)':
 'DIR1': CDS_PINID='DIR1';
NODE_NAME     U147 7
 '@T6G_MB_LIB.T6G(SCH_1):PAGE149_I1@PURE_QUANTA.SN74AVC2T245RSWR(CHIPS)':
 'VCCA': CDS_PINID='VCCA';
NODE_NAME     U148 1
 '@T6G_MB_LIB.T6G(SCH_1):PAGE149_I34@PURE_QUANTA.SN74AVC4T774PWR(CHIPS)':
 'DIR1': CDS_PINID='DIR1';
NODE_NAME     U148 2
 '@T6G_MB_LIB.T6G(SCH_1):PAGE149_I34@PURE_QUANTA.SN74AVC4T774PWR(CHIPS)':
 'DIR2': CDS_PINID='DIR2';
NODE_NAME     U148 7
 '@T6G_MB_LIB.T6G(SCH_1):PAGE149_I34@PURE_QUANTA.SN74AVC4T774PWR(CHIPS)':
 'DIR3': CDS_PINID='DIR3';
NODE_NAME     U148 8
 '@T6G_MB_LIB.T6G(SCH_1):PAGE149_I34@PURE_QUANTA.SN74AVC4T774PWR(CHIPS)':
 'DIR4': CDS_PINID='DIR4';
NODE_NAME     U148 16
 '@T6G_MB_LIB.T6G(SCH_1):PAGE149_I34@PURE_QUANTA.SN74AVC4T774PWR(CHIPS)':
 'VCCA': CDS_PINID='VCCA';
NODE_NAME     C1506 1
 '@T6G_MB_LIB.T6G(SCH_1):PAGE149_I62@PURE_QUANTA.Q_CAP(CHIPS)':
 'A': CDS_PINID='A';
NODE_NAME     C1503 1
 '@T6G_MB_LIB.T6G(SCH_1):PAGE149_I80@PURE_QUANTA.Q_CAP(CHIPS)':
 'A': CDS_PINID='A';
NODE_NAME     R1622 1
 '@T6G_MB_LIB.T6G(SCH_1):PAGE149_I83@PURE_QUANTA.Q_RES(CHIPS)':
 'A': CDS_PINID='A';
NODE_NAME     R1444 1
 '@T6G_MB_LIB.T6G(SCH_1):PAGE142_I82@PURE_QUANTA.Q_RES(CHIPS)':
 'A': CDS_PINID='A';
NODE_NAME     R1507 1
 '@T6G_MB_LIB.T6G(SCH_1):PAGE142_I87@PURE_QUANTA.Q_RES(CHIPS)':
 'A': CDS_PINID='A';
NODE_NAME     PR397 1
 '@T6G_MB_LIB.T6G(SCH_1):PAGE201_I12@PURE_QUANTA.Q_RES(CHIPS)':
 'A': CDS_PINID='A';
NODE_NAME     R8009 1
 '@T6G_MB_LIB.T6G(SCH_1):PAGE201_I26@PURE_QUANTA.Q_RES(CHIPS)':
 'A': CDS_PINID='A';
NODE_NAME     R20 1
 '@T6G_MB_LIB.T6G(SCH_1):PAGE76_I115@PURE_QUANTA.Q_RES(CHIPS)':
 'A': CDS_PINID='A';
NODE_NAME     R21 1
 '@T6G_MB_LIB.T6G(SCH_1):PAGE76_I116@PURE_QUANTA.Q_RES(CHIPS)':
 'A': CDS_PINID='A';
NODE_NAME     R127 1
 '@T6G_MB_LIB.T6G(SCH_1):PAGE76_I117@PURE_QUANTA.Q_RES(CHIPS)':
 'A': CDS_PINID='A';
NODE_NAME     R128 1
 '@T6G_MB_LIB.T6G(SCH_1):PAGE76_I118@PURE_QUANTA.Q_RES(CHIPS)':
 'A': CDS_PINID='A';
NODE_NAME     R129 1
 '@T6G_MB_LIB.T6G(SCH_1):PAGE76_I119@PURE_QUANTA.Q_RES(CHIPS)':
 'A': CDS_PINID='A';
NODE_NAME     J1 3
 '@T6G_MB_LIB.T6G(SCH_1):PAGE85_I536@PURE_QUANTA.SCONN288_DDR506112002KQ(CHIPS)':
 'VIN_MGMT': CDS_PINID='VIN_MGMT';
NODE_NAME     R8300 1
 '@T6G_MB_LIB.T6G(SCH_1):PAGE168_I82@PURE_QUANTA.Q_RES(CHIPS)':
 'A': CDS_PINID='A';
NODE_NAME     PR446 2
 '@T6G_MB_LIB.T6G(SCH_1):PAGE169_I4@PURE_QUANTA.Q_RES(CHIPS)':
 'B': CDS_PINID='B';
NODE_NAME     R1547 1
 '@T6G_MB_LIB.T6G(SCH_1):PAGE76_I148@PURE_QUANTA.Q_RES(CHIPS)':
 'A': CDS_PINID='A';
NODE_NAME     R1655 1
 '@T6G_MB_LIB.T6G(SCH_1):PAGE76_I191@PURE_QUANTA.Q_RES(CHIPS)':
 'A': CDS_PINID='A';
NODE_NAME     PC569 2
 '@T6G_MB_LIB.T6G(SCH_1):PAGE245_I53@PURE_QUANTA.Q_CAP(CHIPS)':
 'B': CDS_PINID='B';
NODE_NAME     PL8066 2
 '@T6G_MB_LIB.T6G(SCH_1):PAGE245_I55@PURE_QUANTA.Q_INDUCTOR(CHIPS)':
 '2': CDS_PINID='\2\';
NODE_NAME     PC1866 1
 '@T6G_MB_LIB.T6G(SCH_1):PAGE245_I57@PURE_QUANTA.Q_CAPP(CHIPS)':
 'A': CDS_PINID='A';
NODE_NAME     PC1867 1
 '@T6G_MB_LIB.T6G(SCH_1):PAGE245_I58@PURE_QUANTA.Q_CAPP(CHIPS)':
 'A': CDS_PINID='A';
NODE_NAME     PC1868 1
 '@T6G_MB_LIB.T6G(SCH_1):PAGE245_I59@PURE_QUANTA.Q_CAP(CHIPS)':
 'A': CDS_PINID='A';
NODE_NAME     PC1600 1
 '@T6G_MB_LIB.T6G(SCH_1):PAGE245_I62@PURE_QUANTA.Q_CAP(CHIPS)':
 'A': CDS_PINID='A';
NODE_NAME     PC1869 1
 '@T6G_MB_LIB.T6G(SCH_1):PAGE245_I63@PURE_QUANTA.Q_CAP(CHIPS)':
 'A': CDS_PINID='A';
NODE_NAME     PR8073 1
 '@T6G_MB_LIB.T6G(SCH_1):PAGE245_I65@PURE_QUANTA.Q_RES(CHIPS)':
 'A': CDS_PINID='A';
NODE_NAME     R3435 1
 '@T6G_MB_LIB.T6G(SCH_1):PAGE299_I23@PURE_QUANTA.Q_RES(CHIPS)':
 'A': CDS_PINID='A';
NODE_NAME     R3437 1
 '@T6G_MB_LIB.T6G(SCH_1):PAGE299_I27@PURE_QUANTA.Q_RES(CHIPS)':
 'A': CDS_PINID='A';
NODE_NAME     R3434 1
 '@T6G_MB_LIB.T6G(SCH_1):PAGE299_I39@PURE_QUANTA.Q_RES(CHIPS)':
 'A': CDS_PINID='A';
NODE_NAME     R3436 1
 '@T6G_MB_LIB.T6G(SCH_1):PAGE299_I45@PURE_QUANTA.Q_RES(CHIPS)':
 'A': CDS_PINID='A';
NODE_NAME     R3433 1
 '@T6G_MB_LIB.T6G(SCH_1):PAGE299_I49@PURE_QUANTA.Q_RES(CHIPS)':
 'A': CDS_PINID='A';
NODE_NAME     R3432 1
 '@T6G_MB_LIB.T6G(SCH_1):PAGE299_I53@PURE_QUANTA.Q_RES(CHIPS)':
 'A': CDS_PINID='A';
NODE_NAME     R3438 1
 '@T6G_MB_LIB.T6G(SCH_1):PAGE299_I55@PURE_QUANTA.Q_RES(CHIPS)':
 'A': CDS_PINID='A';
NODE_NAME     R3439 1
 '@T6G_MB_LIB.T6G(SCH_1):PAGE299_I59@PURE_QUANTA.Q_RES(CHIPS)':
 'A': CDS_PINID='A';
NODE_NAME     R3429 1
 '@T6G_MB_LIB.T6G(SCH_1):PAGE299_I130@PURE_QUANTA.Q_RES(CHIPS)':
 'A': CDS_PINID='A';
NODE_NAME     R3465 1
 '@T6G_MB_LIB.T6G(SCH_1):PAGE299_I132@PURE_QUANTA.Q_RES(CHIPS)':
 'A': CDS_PINID='A';
NODE_NAME     R3464 1
 '@T6G_MB_LIB.T6G(SCH_1):PAGE299_I134@PURE_QUANTA.Q_RES(CHIPS)':
 'A': CDS_PINID='A';
NODE_NAME     R3475 1
 '@T6G_MB_LIB.T6G(SCH_1):PAGE299_I154@PURE_QUANTA.Q_RES(CHIPS)':
 'A': CDS_PINID='A';
NODE_NAME     R3474 1
 '@T6G_MB_LIB.T6G(SCH_1):PAGE299_I158@PURE_QUANTA.Q_RES(CHIPS)':
 'A': CDS_PINID='A';
NODE_NAME     R3487 1
 '@T6G_MB_LIB.T6G(SCH_1):PAGE299_I166@PURE_QUANTA.Q_RES(CHIPS)':
 'A': CDS_PINID='A';
NODE_NAME     R3498 1
 '@T6G_MB_LIB.T6G(SCH_1):PAGE299_I167@PURE_QUANTA.Q_RES(CHIPS)':
 'A': CDS_PINID='A';
NODE_NAME     R3504 1
 '@T6G_MB_LIB.T6G(SCH_1):PAGE299_I174@PURE_QUANTA.Q_RES(CHIPS)':
 'A': CDS_PINID='A';
NODE_NAME     R3503 1
 '@T6G_MB_LIB.T6G(SCH_1):PAGE299_I177@PURE_QUANTA.Q_RES(CHIPS)':
 'A': CDS_PINID='A';
NODE_NAME     R3525 1
 '@T6G_MB_LIB.T6G(SCH_1):PAGE299_I184@PURE_QUANTA.Q_RES(CHIPS)':
 'A': CDS_PINID='A';
NODE_NAME     R9002 1
 '@T6G_MB_LIB.T6G(SCH_1):PAGE330_I8@PURE_QUANTA.Q_RES(CHIPS)':
 'A': CDS_PINID='A';
NODE_NAME     R4160 1
 '@T6G_MB_LIB.T6G(SCH_1):PAGE331_I4@PURE_QUANTA.Q_RES(CHIPS)':
 'A': CDS_PINID='A';
NODE_NAME     R4162 1
 '@T6G_MB_LIB.T6G(SCH_1):PAGE331_I9@PURE_QUANTA.Q_RES(CHIPS)':
 'A': CDS_PINID='A';
NODE_NAME     R4158 1
 '@T6G_MB_LIB.T6G(SCH_1):PAGE331_I14@PURE_QUANTA.Q_RES(CHIPS)':
 'A': CDS_PINID='A';
NODE_NAME     R4165 1
 '@T6G_MB_LIB.T6G(SCH_1):PAGE331_I18@PURE_QUANTA.Q_RES(CHIPS)':
 'A': CDS_PINID='A';
NODE_NAME     R4166 1
 '@T6G_MB_LIB.T6G(SCH_1):PAGE331_I23@PURE_QUANTA.Q_RES(CHIPS)':
 'A': CDS_PINID='A';
NODE_NAME     R4164 1
 '@T6G_MB_LIB.T6G(SCH_1):PAGE331_I27@PURE_QUANTA.Q_RES(CHIPS)':
 'A': CDS_PINID='A';
NODE_NAME     R4168 1
 '@T6G_MB_LIB.T6G(SCH_1):PAGE331_I35@PURE_QUANTA.Q_RES(CHIPS)':
 'A': CDS_PINID='A';
NODE_NAME     R4169 1
 '@T6G_MB_LIB.T6G(SCH_1):PAGE331_I39@PURE_QUANTA.Q_RES(CHIPS)':
 'A': CDS_PINID='A';
NODE_NAME     R4167 1
 '@T6G_MB_LIB.T6G(SCH_1):PAGE331_I47@PURE_QUANTA.Q_RES(CHIPS)':
 'A': CDS_PINID='A';
NODE_NAME     R4545 1
 '@T6G_MB_LIB.T6G(SCH_1):PAGE331_I57@PURE_QUANTA.Q_RES(CHIPS)':
 'A': CDS_PINID='A';
NODE_NAME     R4543 1
 '@T6G_MB_LIB.T6G(SCH_1):PAGE331_I85@PURE_QUANTA.Q_RES(CHIPS)':
 'A': CDS_PINID='A';
NODE_NAME     U316 5
 '@T6G_MB_LIB.T6G(SCH_1):PAGE331_I86@PURE_QUANTA.74LVC2G17GW(CHIPS)':
 'VCC': CDS_PINID='VCC';
NODE_NAME     R4547 1
 '@T6G_MB_LIB.T6G(SCH_1):PAGE331_I89@PURE_QUANTA.Q_RES(CHIPS)':
 'A': CDS_PINID='A';
NODE_NAME     C8 1
 '@T6G_MB_LIB.T6G(SCH_1):PAGE331_I93@PURE_QUANTA.Q_CAP(CHIPS)':
 'A': CDS_PINID='A';
NODE_NAME     R4549 1
 '@T6G_MB_LIB.T6G(SCH_1):PAGE331_I98@PURE_QUANTA.Q_RES(CHIPS)':
 'A': CDS_PINID='A';
NODE_NAME     R2835 1
 '@T6G_MB_LIB.T6G(SCH_1):PAGE333_I14@PURE_QUANTA.Q_RES(CHIPS)':
 'A': CDS_PINID='A';
NODE_NAME     R2834 1
 '@T6G_MB_LIB.T6G(SCH_1):PAGE333_I18@PURE_QUANTA.Q_RES(CHIPS)':
 'A': CDS_PINID='A';
NODE_NAME     R2836 1
 '@T6G_MB_LIB.T6G(SCH_1):PAGE333_I19@PURE_QUANTA.Q_RES(CHIPS)':
 'A': CDS_PINID='A';
NODE_NAME     R2841 1
 '@T6G_MB_LIB.T6G(SCH_1):PAGE333_I24@PURE_QUANTA.Q_RES(CHIPS)':
 'A': CDS_PINID='A';
NODE_NAME     R2842 1
 '@T6G_MB_LIB.T6G(SCH_1):PAGE333_I30@PURE_QUANTA.Q_RES(CHIPS)':
 'A': CDS_PINID='A';
NODE_NAME     R2828 1
 '@T6G_MB_LIB.T6G(SCH_1):PAGE333_I66@PURE_QUANTA.Q_RES(CHIPS)':
 'A': CDS_PINID='A';
NODE_NAME     R2832 1
 '@T6G_MB_LIB.T6G(SCH_1):PAGE333_I67@PURE_QUANTA.Q_RES(CHIPS)':
 'A': CDS_PINID='A';
NODE_NAME     R2830 1
 '@T6G_MB_LIB.T6G(SCH_1):PAGE333_I68@PURE_QUANTA.Q_RES(CHIPS)':
 'A': CDS_PINID='A';
NODE_NAME     R2837 1
 '@T6G_MB_LIB.T6G(SCH_1):PAGE333_I80@PURE_QUANTA.Q_RES(CHIPS)':
 'A': CDS_PINID='A';
NODE_NAME     R2919 1
 '@T6G_MB_LIB.T6G(SCH_1):PAGE333_I91@PURE_QUANTA.Q_RES(CHIPS)':
 'A': CDS_PINID='A';
NODE_NAME     R2934 1
 '@T6G_MB_LIB.T6G(SCH_1):PAGE333_I101@PURE_QUANTA.Q_RES(CHIPS)':
 'A': CDS_PINID='A';
NODE_NAME     R2935 1
 '@T6G_MB_LIB.T6G(SCH_1):PAGE333_I109@PURE_QUANTA.Q_RES(CHIPS)':
 'A': CDS_PINID='A';
NODE_NAME     R3034 1
 '@T6G_MB_LIB.T6G(SCH_1):PAGE333_I129@PURE_QUANTA.Q_RES(CHIPS)':
 'A': CDS_PINID='A';
NODE_NAME     R3029 1
 '@T6G_MB_LIB.T6G(SCH_1):PAGE333_I144@PURE_QUANTA.Q_RES(CHIPS)':
 'A': CDS_PINID='A';
NODE_NAME     R3321 1
 '@T6G_MB_LIB.T6G(SCH_1):PAGE333_I158@PURE_QUANTA.Q_RES(CHIPS)':
 'A': CDS_PINID='A';
NODE_NAME     R3320 1
 '@T6G_MB_LIB.T6G(SCH_1):PAGE333_I162@PURE_QUANTA.Q_RES(CHIPS)':
 'A': CDS_PINID='A';
NODE_NAME     R3318 1
 '@T6G_MB_LIB.T6G(SCH_1):PAGE333_I171@PURE_QUANTA.Q_RES(CHIPS)':
 'A': CDS_PINID='A';
NODE_NAME     R3512 1
 '@T6G_MB_LIB.T6G(SCH_1):PAGE333_I174@PURE_QUANTA.Q_RES(CHIPS)':
 'A': CDS_PINID='A';
NODE_NAME     R3514 1
 '@T6G_MB_LIB.T6G(SCH_1):PAGE333_I175@PURE_QUANTA.Q_RES(CHIPS)':
 'A': CDS_PINID='A';
NODE_NAME     R3510 1
 '@T6G_MB_LIB.T6G(SCH_1):PAGE333_I176@PURE_QUANTA.Q_RES(CHIPS)':
 'A': CDS_PINID='A';
NODE_NAME     U253 5
 '@T6G_MB_LIB.T6G(SCH_1):PAGE334_I26@PURE_QUANTA.74LVC2G17GW(CHIPS)':
 'VCC': CDS_PINID='VCC';
NODE_NAME     C1958 1
 '@T6G_MB_LIB.T6G(SCH_1):PAGE334_I29@PURE_QUANTA.Q_CAP(CHIPS)':
 'A': CDS_PINID='A';
NODE_NAME     R3456 1
 '@T6G_MB_LIB.T6G(SCH_1):PAGE334_I124@PURE_QUANTA.Q_RES(CHIPS)':
 'A': CDS_PINID='A';
NODE_NAME     R3451 1
 '@T6G_MB_LIB.T6G(SCH_1):PAGE334_I127@PURE_QUANTA.Q_RES(CHIPS)':
 'A': CDS_PINID='A';
NODE_NAME     C1957 1
 '@T6G_MB_LIB.T6G(SCH_1):PAGE334_I148@PURE_QUANTA.Q_CAP(CHIPS)':
 'A': CDS_PINID='A';
NODE_NAME     U252 5
 '@T6G_MB_LIB.T6G(SCH_1):PAGE334_I153@PURE_QUANTA.74LVC2G17GW(CHIPS)':
 'VCC': CDS_PINID='VCC';
NODE_NAME     R3453 1
 '@T6G_MB_LIB.T6G(SCH_1):PAGE334_I164@PURE_QUANTA.Q_RES(CHIPS)':
 'A': CDS_PINID='A';
NODE_NAME     R3448 1
 '@T6G_MB_LIB.T6G(SCH_1):PAGE334_I168@PURE_QUANTA.Q_RES(CHIPS)':
 'A': CDS_PINID='A';
NODE_NAME     U256 5
 '@T6G_MB_LIB.T6G(SCH_1):PAGE334_I173@PURE_QUANTA.74LVC2G17GW(CHIPS)':
 'VCC': CDS_PINID='VCC';
NODE_NAME     C1977 1
 '@T6G_MB_LIB.T6G(SCH_1):PAGE334_I175@PURE_QUANTA.Q_CAP(CHIPS)':
 'A': CDS_PINID='A';
NODE_NAME     R2910 1
 '@T6G_MB_LIB.T6G(SCH_1):PAGE334_I187@PURE_QUANTA.Q_RES(CHIPS)':
 'A': CDS_PINID='A';
NODE_NAME     R2914 1
 '@T6G_MB_LIB.T6G(SCH_1):PAGE334_I192@PURE_QUANTA.Q_RES(CHIPS)':
 'A': CDS_PINID='A';
NODE_NAME     C1963 1
 '@T6G_MB_LIB.T6G(SCH_1):PAGE255_I13@PURE_QUANTA.Q_CAP(CHIPS)':
 'A': CDS_PINID='A';
NODE_NAME     U255 5
 '@T6G_MB_LIB.T6G(SCH_1):PAGE255_I16@PURE_QUANTA.74LVC2G07DW7(CHIPS)':
 'VCC': CDS_PINID='VCC';
NODE_NAME     R3461 1
 '@T6G_MB_LIB.T6G(SCH_1):PAGE255_I35@PURE_QUANTA.Q_RES(CHIPS)':
 'A': CDS_PINID='A';
NODE_NAME     R3488 1
 '@T6G_MB_LIB.T6G(SCH_1):PAGE255_I40@PURE_QUANTA.Q_RES(CHIPS)':
 'A': CDS_PINID='A';
NODE_NAME     R3492 1
 '@T6G_MB_LIB.T6G(SCH_1):PAGE255_I47@PURE_QUANTA.Q_RES(CHIPS)':
 'A': CDS_PINID='A';
NODE_NAME     U257 5
 '@T6G_MB_LIB.T6G(SCH_1):PAGE255_I50@PURE_QUANTA.74LVC2G07DW7(CHIPS)':
 'VCC': CDS_PINID='VCC';
NODE_NAME     R3494 1
 '@T6G_MB_LIB.T6G(SCH_1):PAGE255_I55@PURE_QUANTA.Q_RES(CHIPS)':
 'A': CDS_PINID='A';
NODE_NAME     R3490 1
 '@T6G_MB_LIB.T6G(SCH_1):PAGE255_I57@PURE_QUANTA.Q_RES(CHIPS)':
 'A': CDS_PINID='A';
NODE_NAME     C1979 1
 '@T6G_MB_LIB.T6G(SCH_1):PAGE255_I67@PURE_QUANTA.Q_CAP(CHIPS)':
 'A': CDS_PINID='A';
NODE_NAME     U195 5
 '@T6G_MB_LIB.T6G(SCH_1):PAGE256_I65@PURE_QUANTA.74LVC2G17GW(CHIPS)':
 'VCC': CDS_PINID='VCC';
NODE_NAME     R2815 1
 '@T6G_MB_LIB.T6G(SCH_1):PAGE256_I68@PURE_QUANTA.Q_RES(CHIPS)':
 'A': CDS_PINID='A';
NODE_NAME     R2820 1
 '@T6G_MB_LIB.T6G(SCH_1):PAGE256_I78@PURE_QUANTA.Q_RES(CHIPS)':
 'A': CDS_PINID='A';
NODE_NAME     C1769 1
 '@T6G_MB_LIB.T6G(SCH_1):PAGE256_I89@PURE_QUANTA.Q_CAP(CHIPS)':
 'A': CDS_PINID='A';
NODE_NAME     U196 5
 '@T6G_MB_LIB.T6G(SCH_1):PAGE256_I127@PURE_QUANTA.74LVC2G17GW(CHIPS)':
 'VCC': CDS_PINID='VCC';
NODE_NAME     C1770 1
 '@T6G_MB_LIB.T6G(SCH_1):PAGE256_I140@PURE_QUANTA.Q_CAP(CHIPS)':
 'A': CDS_PINID='A';
NODE_NAME     R2912 1
 '@T6G_MB_LIB.T6G(SCH_1):PAGE256_I147@PURE_QUANTA.Q_RES(CHIPS)':
 'A': CDS_PINID='A';
NODE_NAME     R2911 1
 '@T6G_MB_LIB.T6G(SCH_1):PAGE256_I153@PURE_QUANTA.Q_RES(CHIPS)':
 'A': CDS_PINID='A';
NODE_NAME     R2936 1
 '@T6G_MB_LIB.T6G(SCH_1):PAGE256_I162@PURE_QUANTA.Q_RES(CHIPS)':
 'A': CDS_PINID='A';
NODE_NAME     C1803 1
 '@T6G_MB_LIB.T6G(SCH_1):PAGE256_I166@PURE_QUANTA.Q_CAP(CHIPS)':
 'A': CDS_PINID='A';
NODE_NAME     R3317 1
 '@T6G_MB_LIB.T6G(SCH_1):PAGE256_I190@PURE_QUANTA.Q_RES(CHIPS)':
 'A': CDS_PINID='A';
NODE_NAME     R3506 1
 '@T6G_MB_LIB.T6G(SCH_1):PAGE256_I193@PURE_QUANTA.Q_RES(CHIPS)':
 'A': CDS_PINID='A';
NODE_NAME     U204 5
 '@T6G_MB_LIB.T6G(SCH_1):PAGE256_I195@PURE_QUANTA.74LVC1G126SE7(CHIPS)':
 'VCC': CDS_PINID='VCC';
NODE_NAME     R2909 1
 '@T6G_MB_LIB.T6G(SCH_1):PAGE256_I198@PURE_QUANTA.Q_RES(CHIPS)':
 'A': CDS_PINID='A';
NODE_NAME     R4515 1
 '@T6G_MB_LIB.T6G(SCH_1):PAGE256_I200@PURE_QUANTA.Q_RES(CHIPS)':
 'A': CDS_PINID='A';
NODE_NAME     C1825 1
 '@T6G_MB_LIB.T6G(SCH_1):PAGE307_I17@PURE_QUANTA.Q_CAP(CHIPS)':
 'A': CDS_PINID='A';
NODE_NAME     U222 14
 '@T6G_MB_LIB.T6G(SCH_1):PAGE307_I32@PURE_QUANTA.74CBTLV3126PW(CHIPS)':
 'VCC': CDS_PINID='VCC';
NODE_NAME     C1826 1
 '@T6G_MB_LIB.T6G(SCH_1):PAGE307_I33@PURE_QUANTA.Q_CAP(CHIPS)':
 'A': CDS_PINID='A';
NODE_NAME     C1827 1
 '@T6G_MB_LIB.T6G(SCH_1):PAGE307_I77@PURE_QUANTA.Q_CAP(CHIPS)':
 'A': CDS_PINID='A';
NODE_NAME     U223 14
 '@T6G_MB_LIB.T6G(SCH_1):PAGE307_I78@PURE_QUANTA.74CBTLV3126PW(CHIPS)':
 'VCC': CDS_PINID='VCC';
NODE_NAME     U286 5
 '@T6G_MB_LIB.T6G(SCH_1):PAGE307_I80@PURE_QUANTA.74LVC1G126SE7(CHIPS)':
 'VCC': CDS_PINID='VCC';
NODE_NAME     U67 14
 '@T6G_MB_LIB.T6G(SCH_1):PAGE336_I1@PURE_QUANTA.74CBTLV3126PW(CHIPS)':
 'VCC': CDS_PINID='VCC';
NODE_NAME     U7 14
 '@T6G_MB_LIB.T6G(SCH_1):PAGE336_I2@PURE_QUANTA.74CBTLV3126PW(CHIPS)':
 'VCC': CDS_PINID='VCC';
NODE_NAME     C641 1
 '@T6G_MB_LIB.T6G(SCH_1):PAGE336_I16@PURE_QUANTA.Q_CAP(CHIPS)':
 'A': CDS_PINID='A';
NODE_NAME     C640 1
 '@T6G_MB_LIB.T6G(SCH_1):PAGE336_I47@PURE_QUANTA.Q_CAP(CHIPS)':
 'A': CDS_PINID='A';
NODE_NAME     C639 1
 '@T6G_MB_LIB.T6G(SCH_1):PAGE336_I59@PURE_QUANTA.Q_CAP(CHIPS)':
 'A': CDS_PINID='A';
NODE_NAME     C1840 1
 '@T6G_MB_LIB.T6G(SCH_1):PAGE336_I147@PURE_QUANTA.Q_CAP(CHIPS)':
 'A': CDS_PINID='A';
NODE_NAME     U66 5
 '@T6G_MB_LIB.T6G(SCH_1):PAGE336_I157@PURE_QUANTA.74LVC1G126SE7(CHIPS)':
 'VCC': CDS_PINID='VCC';
NODE_NAME     U224 5
 '@T6G_MB_LIB.T6G(SCH_1):PAGE336_I159@PURE_QUANTA.74LVC1G126SE7(CHIPS)':
 'VCC': CDS_PINID='VCC';
NODE_NAME     C72 1
 '@T6G_MB_LIB.T6G(SCH_1):PAGE337_I40@PURE_QUANTA.Q_CAP(CHIPS)':
 'A': CDS_PINID='A';
NODE_NAME     R53 1
 '@T6G_MB_LIB.T6G(SCH_1):PAGE337_I42@PURE_QUANTA.Q_RES(CHIPS)':
 'A': CDS_PINID='A';
NODE_NAME     C2344 1
 '@T6G_MB_LIB.T6G(SCH_1):PAGE337_I53@PURE_QUANTA.Q_CAP(CHIPS)':
 'A': CDS_PINID='A';
NODE_NAME     R2487 1
 '@T6G_MB_LIB.T6G(SCH_1):PAGE337_I56@PURE_QUANTA.Q_RES(CHIPS)':
 'A': CDS_PINID='A';
NODE_NAME     C1841 1
 '@T6G_MB_LIB.T6G(SCH_1):PAGE342_I12@PURE_QUANTA.Q_CAP(CHIPS)':
 'A': CDS_PINID='A';
NODE_NAME     C1823 1
 '@T6G_MB_LIB.T6G(SCH_1):PAGE342_I31@PURE_QUANTA.Q_CAP(CHIPS)':
 'A': CDS_PINID='A';
NODE_NAME     C1824 1
 '@T6G_MB_LIB.T6G(SCH_1):PAGE342_I41@PURE_QUANTA.Q_CAP(CHIPS)':
 'A': CDS_PINID='A';
NODE_NAME     R3192 1
 '@T6G_MB_LIB.T6G(SCH_1):PAGE342_I44@PURE_QUANTA.Q_RES(CHIPS)':
 'A': CDS_PINID='A';
NODE_NAME     C38 1
 '@T6G_MB_LIB.T6G(SCH_1):PAGE342_I47@PURE_QUANTA.Q_CAP(CHIPS)':
 'A': CDS_PINID='A';
NODE_NAME     R3136 1
 '@T6G_MB_LIB.T6G(SCH_1):PAGE343_I6@PURE_QUANTA.Q_RES(CHIPS)':
 'A': CDS_PINID='A';
NODE_NAME     R3133 1
 '@T6G_MB_LIB.T6G(SCH_1):PAGE343_I14@PURE_QUANTA.Q_RES(CHIPS)':
 'A': CDS_PINID='A';
NODE_NAME     R3135 1
 '@T6G_MB_LIB.T6G(SCH_1):PAGE343_I16@PURE_QUANTA.Q_RES(CHIPS)':
 'A': CDS_PINID='A';
NODE_NAME     U58 5
 '@T6G_MB_LIB.T6G(SCH_1):PAGE343_I28@PURE_QUANTA.74LVC2G07DW7(CHIPS)':
 'VCC': CDS_PINID='VCC';
NODE_NAME     PR3795 1
 '@T6G_MB_LIB.T6G(SCH_1):PAGE343_I56@PURE_QUANTA.Q_RES(CHIPS)':
 'A': CDS_PINID='A';
NODE_NAME     R3147 1
 '@T6G_MB_LIB.T6G(SCH_1):PAGE343_I69@PURE_QUANTA.Q_RES(CHIPS)':
 'A': CDS_PINID='A';
NODE_NAME     R3825 1
 '@T6G_MB_LIB.T6G(SCH_1):PAGE343_I80@PURE_QUANTA.Q_RES(CHIPS)':
 'A': CDS_PINID='A';
NODE_NAME     PU200 A3
 '@T6G_MB_LIB.T6G(SCH_1):PAGE343_I89@PURE_QUANTA.MAX15090BEWIT(CHIPS)':
 'IN_A3': CDS_PINID='IN_A3';
NODE_NAME     PU200 A5
 '@T6G_MB_LIB.T6G(SCH_1):PAGE343_I89@PURE_QUANTA.MAX15090BEWIT(CHIPS)':
 'IN_A5': CDS_PINID='IN_A5';
NODE_NAME     PU200 B3
 '@T6G_MB_LIB.T6G(SCH_1):PAGE343_I89@PURE_QUANTA.MAX15090BEWIT(CHIPS)':
 'IN_B3': CDS_PINID='IN_B3';
NODE_NAME     PU200 B5
 '@T6G_MB_LIB.T6G(SCH_1):PAGE343_I89@PURE_QUANTA.MAX15090BEWIT(CHIPS)':
 'IN_B5': CDS_PINID='IN_B5';
NODE_NAME     PU200 C3
 '@T6G_MB_LIB.T6G(SCH_1):PAGE343_I89@PURE_QUANTA.MAX15090BEWIT(CHIPS)':
 'IN_C3': CDS_PINID='IN_C3';
NODE_NAME     PU200 C5
 '@T6G_MB_LIB.T6G(SCH_1):PAGE343_I89@PURE_QUANTA.MAX15090BEWIT(CHIPS)':
 'IN_C5': CDS_PINID='IN_C5';
NODE_NAME     PU200 D5
 '@T6G_MB_LIB.T6G(SCH_1):PAGE343_I89@PURE_QUANTA.MAX15090BEWIT(CHIPS)':
 'IN_D5': CDS_PINID='IN_D5';
NODE_NAME     R3833 1
 '@T6G_MB_LIB.T6G(SCH_1):PAGE343_I107@PURE_QUANTA.Q_RES(CHIPS)':
 'A': CDS_PINID='A';
NODE_NAME     PR3851 2
 '@T6G_MB_LIB.T6G(SCH_1):PAGE344_I18@PURE_QUANTA.Q_RES(CHIPS)':
 'B': CDS_PINID='B';
NODE_NAME     R3848 1
 '@T6G_MB_LIB.T6G(SCH_1):PAGE344_I27@PURE_QUANTA.Q_RES(CHIPS)':
 'A': CDS_PINID='A';
NODE_NAME     PC2169 1
 '@T6G_MB_LIB.T6G(SCH_1):PAGE344_I48@PURE_QUANTA.Q_CAP(CHIPS)':
 'A': CDS_PINID='A';
NODE_NAME     PU207 1_2
 '@T6G_MB_LIB.T6G(SCH_1):PAGE344_I51@PURE_QUANTA.MP5016GQHLZ(CHIPS)':
 'VCC': CDS_PINID='VCC';
NODE_NAME     U241 8
 '@T6G_MB_LIB.T6G(SCH_1):PAGE258_I1@PURE_QUANTA.74LVC2G08DP(CHIPS)':
 'VCC': CDS_PINID='VCC';
NODE_NAME     U240 8
 '@T6G_MB_LIB.T6G(SCH_1):PAGE258_I11@PURE_QUANTA.74LVC2G08DP(CHIPS)':
 'VCC': CDS_PINID='VCC';
NODE_NAME     U242 8
 '@T6G_MB_LIB.T6G(SCH_1):PAGE258_I13@PURE_QUANTA.74LVC2G08DP(CHIPS)':
 'VCC': CDS_PINID='VCC';
NODE_NAME     U243 5
 '@T6G_MB_LIB.T6G(SCH_1):PAGE258_I15@PURE_QUANTA.NC7SB3157(CHIPS)':
 'VCC': CDS_PINID='VCC';
NODE_NAME     U244 5
 '@T6G_MB_LIB.T6G(SCH_1):PAGE258_I16@PURE_QUANTA.NC7SB3157(CHIPS)':
 'VCC': CDS_PINID='VCC';
NODE_NAME     U246 5
 '@T6G_MB_LIB.T6G(SCH_1):PAGE258_I17@PURE_QUANTA.NC7SB3157(CHIPS)':
 'VCC': CDS_PINID='VCC';
NODE_NAME     U245 5
 '@T6G_MB_LIB.T6G(SCH_1):PAGE258_I18@PURE_QUANTA.NC7SB3157(CHIPS)':
 'VCC': CDS_PINID='VCC';
NODE_NAME     C1875 1
 '@T6G_MB_LIB.T6G(SCH_1):PAGE258_I21@PURE_QUANTA.Q_CAP(CHIPS)':
 'A': CDS_PINID='A';
NODE_NAME     C1874 1
 '@T6G_MB_LIB.T6G(SCH_1):PAGE258_I22@PURE_QUANTA.Q_CAP(CHIPS)':
 'A': CDS_PINID='A';
NODE_NAME     C1880 1
 '@T6G_MB_LIB.T6G(SCH_1):PAGE258_I27@PURE_QUANTA.Q_CAP(CHIPS)':
 'A': CDS_PINID='A';
NODE_NAME     C1879 1
 '@T6G_MB_LIB.T6G(SCH_1):PAGE258_I31@PURE_QUANTA.Q_CAP(CHIPS)':
 'A': CDS_PINID='A';
NODE_NAME     C1877 1
 '@T6G_MB_LIB.T6G(SCH_1):PAGE258_I34@PURE_QUANTA.Q_CAP(CHIPS)':
 'A': CDS_PINID='A';
NODE_NAME     C1878 1
 '@T6G_MB_LIB.T6G(SCH_1):PAGE258_I37@PURE_QUANTA.Q_CAP(CHIPS)':
 'A': CDS_PINID='A';
NODE_NAME     C1876 1
 '@T6G_MB_LIB.T6G(SCH_1):PAGE258_I41@PURE_QUANTA.Q_CAP(CHIPS)':
 'A': CDS_PINID='A';
NODE_NAME     PC2200 1
 '@T6G_MB_LIB.T6G(SCH_1):PAGE323_I9@PURE_QUANTA.Q_CAP(CHIPS)':
 'A': CDS_PINID='A';
NODE_NAME     PU293 1_2
 '@T6G_MB_LIB.T6G(SCH_1):PAGE323_I31@PURE_QUANTA.MP5016GQHLZ(CHIPS)':
 'VCC': CDS_PINID='VCC';
NODE_NAME     R3948 1
 '@T6G_MB_LIB.T6G(SCH_1):PAGE323_I37@PURE_QUANTA.Q_RES(CHIPS)':
 'A': CDS_PINID='A';
NODE_NAME     PR3951 2
 '@T6G_MB_LIB.T6G(SCH_1):PAGE323_I40@PURE_QUANTA.Q_RES(CHIPS)':
 'B': CDS_PINID='B';
NODE_NAME     PC2208 1
 '@T6G_MB_LIB.T6G(SCH_1):PAGE324_I20@PURE_QUANTA.Q_CAP(CHIPS)':
 'A': CDS_PINID='A';
NODE_NAME     PR3963 1
 '@T6G_MB_LIB.T6G(SCH_1):PAGE324_I21@PURE_QUANTA.Q_RES(CHIPS)':
 'A': CDS_PINID='A';
NODE_NAME     PR3967 1
 '@T6G_MB_LIB.T6G(SCH_1):PAGE324_I43@PURE_QUANTA.Q_RES(CHIPS)':
 'A': CDS_PINID='A';
NODE_NAME     R3979 1
 '@T6G_MB_LIB.T6G(SCH_1):PAGE324_I54@PURE_QUANTA.Q_RES(CHIPS)':
 'A': CDS_PINID='A';
NODE_NAME     R3976 1
 '@T6G_MB_LIB.T6G(SCH_1):PAGE324_I76@PURE_QUANTA.Q_RES(CHIPS)':
 'A': CDS_PINID='A';
NODE_NAME     C1305 1
 '@T6G_MB_LIB.T6G(SCH_1):PAGE346_I52@PURE_QUANTA.Q_CAP(CHIPS)':
 'A': CDS_PINID='A';
NODE_NAME     R1700 1
 '@T6G_MB_LIB.T6G(SCH_1):PAGE346_I72@PURE_QUANTA.Q_RES(CHIPS)':
 'A': CDS_PINID='A';
NODE_NAME     C1997 1
 '@T6G_MB_LIB.T6G(SCH_1):PAGE346_I89@PURE_QUANTA.Q_CAP(CHIPS)':
 'A': CDS_PINID='A';
NODE_NAME     U279 8
 '@T6G_MB_LIB.T6G(SCH_1):PAGE346_I93@PURE_QUANTA.PCA9617ADP(CHIPS)':
 'VCCB': CDS_PINID='VCCB';
NODE_NAME     R3529 1
 '@T6G_MB_LIB.T6G(SCH_1):PAGE346_I99@PURE_QUANTA.Q_RES(CHIPS)':
 'A': CDS_PINID='A';
NODE_NAME     R1854 1
 '@T6G_MB_LIB.T6G(SCH_1):PAGE350_I2@PURE_QUANTA.Q_RES(CHIPS)':
 'A': CDS_PINID='A';
NODE_NAME     R1857 1
 '@T6G_MB_LIB.T6G(SCH_1):PAGE350_I18@PURE_QUANTA.Q_RES(CHIPS)':
 'A': CDS_PINID='A';
NODE_NAME     PR4007 2
 '@T6G_MB_LIB.T6G(SCH_1):PAGE350_I40@PURE_QUANTA.Q_RES(CHIPS)':
 'B': CDS_PINID='B';
NODE_NAME     R4015 1
 '@T6G_MB_LIB.T6G(SCH_1):PAGE350_I78@PURE_QUANTA.Q_RES(CHIPS)':
 'A': CDS_PINID='A';
NODE_NAME     C1332 1
 '@T6G_MB_LIB.T6G(SCH_1):PAGE273_I48@PURE_QUANTA.Q_CAP(CHIPS)':
 'A': CDS_PINID='A';
NODE_NAME     C1333 1
 '@T6G_MB_LIB.T6G(SCH_1):PAGE273_I49@PURE_QUANTA.Q_CAP(CHIPS)':
 'A': CDS_PINID='A';
NODE_NAME     Q56 5
 '@T6G_MB_LIB.T6G(SCH_1):PAGE273_I50@PURE_QUANTA.MOSFET_NCH_1D3S(CHIPS)':
 '5': CDS_PINID='\5\';
NODE_NAME     C60 1
 '@T6G_MB_LIB.T6G(SCH_1):PAGE273_I51@PURE_QUANTA.Q_CAP(CHIPS)':
 'A': CDS_PINID='A';
NODE_NAME     U266 9
 '@T6G_MB_LIB.T6G(SCH_1):PAGE295_I30@PURE_QUANTA.ISL28022FRZT(CHIPS)':
 'VCC': CDS_PINID='VCC';
NODE_NAME     C2015 1
 '@T6G_MB_LIB.T6G(SCH_1):PAGE295_I34@PURE_QUANTA.Q_CAP(CHIPS)':
 'A': CDS_PINID='A';
NODE_NAME     R3628 1
 '@T6G_MB_LIB.T6G(SCH_1):PAGE295_I88@PURE_QUANTA.Q_RES(CHIPS)':
 'A': CDS_PINID='A';
NODE_NAME     R3627 1
 '@T6G_MB_LIB.T6G(SCH_1):PAGE295_I89@PURE_QUANTA.Q_RES(CHIPS)':
 'A': CDS_PINID='A';
NODE_NAME     C2067 1
 '@T6G_MB_LIB.T6G(SCH_1):PAGE295_I125@PURE_QUANTA.Q_CAP(CHIPS)':
 'A': CDS_PINID='A';
NODE_NAME     U276 9
 '@T6G_MB_LIB.T6G(SCH_1):PAGE295_I129@PURE_QUANTA.ISL28022FRZT(CHIPS)':
 'VCC': CDS_PINID='VCC';
NODE_NAME     R4093 1
 '@T6G_MB_LIB.T6G(SCH_1):PAGE295_I149@PURE_QUANTA.Q_RES(CHIPS)':
 'A': CDS_PINID='A';
NODE_NAME     R4094 1
 '@T6G_MB_LIB.T6G(SCH_1):PAGE295_I151@PURE_QUANTA.Q_RES(CHIPS)':
 'A': CDS_PINID='A';
NODE_NAME     U5201 12
 '@T6G_MB_LIB.T6G(SCH_1):PAGE358_I84@PURE_QUANTA.TUSB211IRWBR(CHIPS)':
 'VCC': CDS_PINID='VCC';
NODE_NAME     C5229 1
 '@T6G_MB_LIB.T6G(SCH_1):PAGE358_I88@PURE_QUANTA.Q_CAP(CHIPS)':
 'A': CDS_PINID='A';
NODE_NAME     C5234 1
 '@T6G_MB_LIB.T6G(SCH_1):PAGE358_I92@PURE_QUANTA.Q_CAP(CHIPS)':
 'A': CDS_PINID='A';
NODE_NAME     R3660 1
 '@T6G_MB_LIB.T6G(SCH_1):PAGE358_I159@PURE_QUANTA.Q_RES(CHIPS)':
 'A': CDS_PINID='A';
NODE_NAME     R3655 1
 '@T6G_MB_LIB.T6G(SCH_1):PAGE358_I161@PURE_QUANTA.Q_RES(CHIPS)':
 'A': CDS_PINID='A';
NODE_NAME     R3663 1
 '@T6G_MB_LIB.T6G(SCH_1):PAGE358_I186@PURE_QUANTA.Q_RES(CHIPS)':
 'A': CDS_PINID='A';
NODE_NAME     R3656 1
 '@T6G_MB_LIB.T6G(SCH_1):PAGE358_I194@PURE_QUANTA.Q_RES(CHIPS)':
 'A': CDS_PINID='A';
NODE_NAME     R3657 1
 '@T6G_MB_LIB.T6G(SCH_1):PAGE358_I195@PURE_QUANTA.Q_RES(CHIPS)':
 'A': CDS_PINID='A';
NODE_NAME     R3658 1
 '@T6G_MB_LIB.T6G(SCH_1):PAGE358_I196@PURE_QUANTA.Q_RES(CHIPS)':
 'A': CDS_PINID='A';
NODE_NAME     R3659 1
 '@T6G_MB_LIB.T6G(SCH_1):PAGE358_I198@PURE_QUANTA.Q_RES(CHIPS)':
 'A': CDS_PINID='A';
NODE_NAME     C2010 1
 '@T6G_MB_LIB.T6G(SCH_1):PAGE359_I16@PURE_QUANTA.Q_CAP(CHIPS)':
 'A': CDS_PINID='A';
NODE_NAME     R4198 1
 '@T6G_MB_LIB.T6G(SCH_1):PAGE359_I82@PURE_QUANTA.Q_RES(CHIPS)':
 'A': CDS_PINID='A';
NODE_NAME     R4206 1
 '@T6G_MB_LIB.T6G(SCH_1):PAGE359_I86@PURE_QUANTA.Q_RES(CHIPS)':
 'A': CDS_PINID='A';
NODE_NAME     R4190 1
 '@T6G_MB_LIB.T6G(SCH_1):PAGE359_I91@PURE_QUANTA.Q_RES(CHIPS)':
 'A': CDS_PINID='A';
NODE_NAME     R4204 1
 '@T6G_MB_LIB.T6G(SCH_1):PAGE359_I94@PURE_QUANTA.Q_RES(CHIPS)':
 'A': CDS_PINID='A';
NODE_NAME     R4196 1
 '@T6G_MB_LIB.T6G(SCH_1):PAGE359_I95@PURE_QUANTA.Q_RES(CHIPS)':
 'A': CDS_PINID='A';
NODE_NAME     R4188 1
 '@T6G_MB_LIB.T6G(SCH_1):PAGE359_I101@PURE_QUANTA.Q_RES(CHIPS)':
 'A': CDS_PINID='A';
NODE_NAME     C73 1
 '@T6G_MB_LIB.T6G(SCH_1):PAGE359_I104@PURE_QUANTA.Q_CAP(CHIPS)':
 'A': CDS_PINID='A';
NODE_NAME     C32 1
 '@T6G_MB_LIB.T6G(SCH_1):PAGE359_I119@PURE_QUANTA.Q_CAP(CHIPS)':
 'A': CDS_PINID='A';
NODE_NAME     R4186 1
 '@T6G_MB_LIB.T6G(SCH_1):PAGE359_I122@PURE_QUANTA.Q_RES(CHIPS)':
 'A': CDS_PINID='A';
NODE_NAME     R4194 1
 '@T6G_MB_LIB.T6G(SCH_1):PAGE359_I128@PURE_QUANTA.Q_RES(CHIPS)':
 'A': CDS_PINID='A';
NODE_NAME     R4202 1
 '@T6G_MB_LIB.T6G(SCH_1):PAGE359_I129@PURE_QUANTA.Q_RES(CHIPS)':
 'A': CDS_PINID='A';
NODE_NAME     C31 1
 '@T6G_MB_LIB.T6G(SCH_1):PAGE359_I139@PURE_QUANTA.Q_CAP(CHIPS)':
 'A': CDS_PINID='A';
NODE_NAME     R4184 1
 '@T6G_MB_LIB.T6G(SCH_1):PAGE359_I142@PURE_QUANTA.Q_RES(CHIPS)':
 'A': CDS_PINID='A';
NODE_NAME     R4192 1
 '@T6G_MB_LIB.T6G(SCH_1):PAGE359_I148@PURE_QUANTA.Q_RES(CHIPS)':
 'A': CDS_PINID='A';
NODE_NAME     R4200 1
 '@T6G_MB_LIB.T6G(SCH_1):PAGE359_I149@PURE_QUANTA.Q_RES(CHIPS)':
 'A': CDS_PINID='A';
NODE_NAME     U270 8
 '@T6G_MB_LIB.T6G(SCH_1):PAGE359_I164@PURE_QUANTA.LM75BD(CHIPS)':
 'VCC': CDS_PINID='VCC';
NODE_NAME     U271 8
 '@T6G_MB_LIB.T6G(SCH_1):PAGE359_I165@PURE_QUANTA.LM75BD(CHIPS)':
 'VCC': CDS_PINID='VCC';
NODE_NAME     U272 8
 '@T6G_MB_LIB.T6G(SCH_1):PAGE359_I166@PURE_QUANTA.LM75BD(CHIPS)':
 'VCC': CDS_PINID='VCC';
NODE_NAME     U273 8
 '@T6G_MB_LIB.T6G(SCH_1):PAGE359_I167@PURE_QUANTA.LM75BD(CHIPS)':
 'VCC': CDS_PINID='VCC';
NODE_NAME     R4211 1
 '@T6G_MB_LIB.T6G(SCH_1):PAGE359_I168@PURE_QUANTA.Q_RES(CHIPS)':
 'A': CDS_PINID='A';
NODE_NAME     R4209 1
 '@T6G_MB_LIB.T6G(SCH_1):PAGE359_I169@PURE_QUANTA.Q_RES(CHIPS)':
 'A': CDS_PINID='A';
NODE_NAME     R4210 1
 '@T6G_MB_LIB.T6G(SCH_1):PAGE359_I170@PURE_QUANTA.Q_RES(CHIPS)':
 'A': CDS_PINID='A';
NODE_NAME     R4208 1
 '@T6G_MB_LIB.T6G(SCH_1):PAGE359_I171@PURE_QUANTA.Q_RES(CHIPS)':
 'A': CDS_PINID='A';
NODE_NAME     C2013 1
 '@T6G_MB_LIB.T6G(SCH_1):PAGE360_I42@PURE_QUANTA.Q_CAP(CHIPS)':
 'A': CDS_PINID='A';
NODE_NAME     U264 9
 '@T6G_MB_LIB.T6G(SCH_1):PAGE360_I46@PURE_QUANTA.ISL28022FRZT(CHIPS)':
 'VCC': CDS_PINID='VCC';
NODE_NAME     C2014 1
 '@T6G_MB_LIB.T6G(SCH_1):PAGE360_I65@PURE_QUANTA.Q_CAP(CHIPS)':
 'A': CDS_PINID='A';
NODE_NAME     U265 9
 '@T6G_MB_LIB.T6G(SCH_1):PAGE360_I69@PURE_QUANTA.ISL28022FRZT(CHIPS)':
 'VCC': CDS_PINID='VCC';
NODE_NAME     R3623 1
 '@T6G_MB_LIB.T6G(SCH_1):PAGE360_I86@PURE_QUANTA.Q_RES(CHIPS)':
 'A': CDS_PINID='A';
NODE_NAME     R3621 1
 '@T6G_MB_LIB.T6G(SCH_1):PAGE360_I87@PURE_QUANTA.Q_RES(CHIPS)':
 'A': CDS_PINID='A';
NODE_NAME     R3624 1
 '@T6G_MB_LIB.T6G(SCH_1):PAGE360_I89@PURE_QUANTA.Q_RES(CHIPS)':
 'A': CDS_PINID='A';
NODE_NAME     R3622 1
 '@T6G_MB_LIB.T6G(SCH_1):PAGE360_I90@PURE_QUANTA.Q_RES(CHIPS)':
 'A': CDS_PINID='A';
NODE_NAME     U263 9
 '@T6G_MB_LIB.T6G(SCH_1):PAGE360_I94@PURE_QUANTA.ISL28022FRZT(CHIPS)':
 'VCC': CDS_PINID='VCC';
NODE_NAME     C2012 1
 '@T6G_MB_LIB.T6G(SCH_1):PAGE360_I98@PURE_QUANTA.Q_CAP(CHIPS)':
 'A': CDS_PINID='A';
NODE_NAME     R4091 1
 '@T6G_MB_LIB.T6G(SCH_1):PAGE360_I122@PURE_QUANTA.Q_RES(CHIPS)':
 'A': CDS_PINID='A';
NODE_NAME     R4090 1
 '@T6G_MB_LIB.T6G(SCH_1):PAGE360_I124@PURE_QUANTA.Q_RES(CHIPS)':
 'A': CDS_PINID='A';
NODE_NAME     R4092 1
 '@T6G_MB_LIB.T6G(SCH_1):PAGE360_I126@PURE_QUANTA.Q_RES(CHIPS)':
 'A': CDS_PINID='A';
NODE_NAME     U64 8
 '@T6G_MB_LIB.T6G(SCH_1):PAGE361_I35@PURE_QUANTA.M24128BWMN6TP(CHIPS)':
 'VCC': CDS_PINID='VCC';
NODE_NAME     R717 1
 '@T6G_MB_LIB.T6G(SCH_1):PAGE361_I45@PURE_QUANTA.Q_RES(CHIPS)':
 'A': CDS_PINID='A';
NODE_NAME     R713 1
 '@T6G_MB_LIB.T6G(SCH_1):PAGE361_I47@PURE_QUANTA.Q_RES(CHIPS)':
 'A': CDS_PINID='A';
NODE_NAME     C629 1
 '@T6G_MB_LIB.T6G(SCH_1):PAGE361_I55@PURE_QUANTA.Q_CAP(CHIPS)':
 'A': CDS_PINID='A';
NODE_NAME     R721 1
 '@T6G_MB_LIB.T6G(SCH_1):PAGE361_I62@PURE_QUANTA.Q_RES(CHIPS)':
 'A': CDS_PINID='A';
NODE_NAME     R43 1
 '@T6G_MB_LIB.T6G(SCH_1):PAGE361_I93@PURE_QUANTA.Q_RES(CHIPS)':
 'A': CDS_PINID='A';
NODE_NAME     R26 1
 '@T6G_MB_LIB.T6G(SCH_1):PAGE361_I95@PURE_QUANTA.Q_RES(CHIPS)':
 'A': CDS_PINID='A';
NODE_NAME     R2794 1
 '@T6G_MB_LIB.T6G(SCH_1):PAGE363_I396@PURE_QUANTA.Q_RES(CHIPS)':
 'A': CDS_PINID='A';
NODE_NAME     U192 8
 '@T6G_MB_LIB.T6G(SCH_1):PAGE363_I398@PURE_QUANTA.LTC4307CMS8(CHIPS)':
 'VCC': CDS_PINID='VCC';
NODE_NAME     C1751 1
 '@T6G_MB_LIB.T6G(SCH_1):PAGE363_I412@PURE_QUANTA.Q_CAP(CHIPS)':
 'A': CDS_PINID='A';
NODE_NAME     R2805 1
 '@T6G_MB_LIB.T6G(SCH_1):PAGE363_I436@PURE_QUANTA.Q_RES(CHIPS)':
 'A': CDS_PINID='A';
NODE_NAME     R2807 1
 '@T6G_MB_LIB.T6G(SCH_1):PAGE363_I438@PURE_QUANTA.Q_RES(CHIPS)':
 'A': CDS_PINID='A';
NODE_NAME     C1775 1
 '@T6G_MB_LIB.T6G(SCH_1):PAGE364_I14@PURE_QUANTA.Q_CAP(CHIPS)':
 'A': CDS_PINID='A';
NODE_NAME     R2946 1
 '@T6G_MB_LIB.T6G(SCH_1):PAGE364_I25@PURE_QUANTA.Q_RES(CHIPS)':
 'A': CDS_PINID='A';
NODE_NAME     R2940 1
 '@T6G_MB_LIB.T6G(SCH_1):PAGE364_I28@PURE_QUANTA.Q_RES(CHIPS)':
 'A': CDS_PINID='A';
NODE_NAME     U278 5
 '@T6G_MB_LIB.T6G(SCH_1):PAGE364_I31@PURE_QUANTA.74LVC1G08W57(CHIPS)':
 'VCC': CDS_PINID='VCC';
NODE_NAME     U308 5
 '@T6G_MB_LIB.T6G(SCH_1):PAGE364_I37@PURE_QUANTA.74LVC2G07DW7(CHIPS)':
 'VCC': CDS_PINID='VCC';
NODE_NAME     C69 1
 '@T6G_MB_LIB.T6G(SCH_1):PAGE364_I40@PURE_QUANTA.Q_CAP(CHIPS)':
 'A': CDS_PINID='A';
NODE_NAME     R4264 1
 '@T6G_MB_LIB.T6G(SCH_1):PAGE364_I47@PURE_QUANTA.Q_RES(CHIPS)':
 'A': CDS_PINID='A';
NODE_NAME     R4551 1
 '@T6G_MB_LIB.T6G(SCH_1):PAGE364_I51@PURE_QUANTA.Q_RES(CHIPS)':
 'A': CDS_PINID='A';
NODE_NAME     R4553 1
 '@T6G_MB_LIB.T6G(SCH_1):PAGE364_I55@PURE_QUANTA.Q_RES(CHIPS)':
 'A': CDS_PINID='A';
NODE_NAME     R4554 1
 '@T6G_MB_LIB.T6G(SCH_1):PAGE364_I59@PURE_QUANTA.Q_RES(CHIPS)':
 'A': CDS_PINID='A';
NODE_NAME     R6034 1
 '@T6G_MB_LIB.T6G(SCH_1):PAGE348_I18@PURE_QUANTA.Q_RES(CHIPS)':
 'A': CDS_PINID='A';
NODE_NAME     R6017 1
 '@T6G_MB_LIB.T6G(SCH_1):PAGE349_I28@PURE_QUANTA.Q_RES(CHIPS)':
 'A': CDS_PINID='A';
NODE_NAME     R6016 1
 '@T6G_MB_LIB.T6G(SCH_1):PAGE349_I29@PURE_QUANTA.Q_RES(CHIPS)':
 'A': CDS_PINID='A';
NODE_NAME     R1546 1
 '@T6G_MB_LIB.T6G(SCH_1):PAGE349_I30@PURE_QUANTA.Q_RES(CHIPS)':
 'A': CDS_PINID='A';
NODE_NAME     R3243 2
 '@T6G_MB_LIB.T6G(SCH_1):PAGE349_I115@PURE_QUANTA.Q_RES(CHIPS)':
 'B': CDS_PINID='B';
NODE_NAME     R131 1
 '@T6G_MB_LIB.T6G(SCH_1):PAGE349_I116@PURE_QUANTA.Q_RES(CHIPS)':
 'A': CDS_PINID='A';
NODE_NAME     R3240 2
 '@T6G_MB_LIB.T6G(SCH_1):PAGE349_I120@PURE_QUANTA.Q_RES(CHIPS)':
 'B': CDS_PINID='B';
NODE_NAME     R3227 2
 '@T6G_MB_LIB.T6G(SCH_1):PAGE349_I121@PURE_QUANTA.Q_RES(CHIPS)':
 'B': CDS_PINID='B';
NODE_NAME     R3226 2
 '@T6G_MB_LIB.T6G(SCH_1):PAGE349_I122@PURE_QUANTA.Q_RES(CHIPS)':
 'B': CDS_PINID='B';
NODE_NAME     R3004 2
 '@T6G_MB_LIB.T6G(SCH_1):PAGE349_I123@PURE_QUANTA.Q_RES(CHIPS)':
 'B': CDS_PINID='B';
NODE_NAME     R2999 2
 '@T6G_MB_LIB.T6G(SCH_1):PAGE349_I124@PURE_QUANTA.Q_RES(CHIPS)':
 'B': CDS_PINID='B';
NODE_NAME     R2213 2
 '@T6G_MB_LIB.T6G(SCH_1):PAGE349_I125@PURE_QUANTA.Q_RES(CHIPS)':
 'B': CDS_PINID='B';
NODE_NAME     R2212 2
 '@T6G_MB_LIB.T6G(SCH_1):PAGE349_I126@PURE_QUANTA.Q_RES(CHIPS)':
 'B': CDS_PINID='B';
NODE_NAME     R1460 2
 '@T6G_MB_LIB.T6G(SCH_1):PAGE349_I127@PURE_QUANTA.Q_RES(CHIPS)':
 'B': CDS_PINID='B';
NODE_NAME     R332 2
 '@T6G_MB_LIB.T6G(SCH_1):PAGE349_I128@PURE_QUANTA.Q_RES(CHIPS)':
 'B': CDS_PINID='B';
NODE_NAME     R331 2
 '@T6G_MB_LIB.T6G(SCH_1):PAGE349_I129@PURE_QUANTA.Q_RES(CHIPS)':
 'B': CDS_PINID='B';
NODE_NAME     R330 2
 '@T6G_MB_LIB.T6G(SCH_1):PAGE349_I130@PURE_QUANTA.Q_RES(CHIPS)':
 'B': CDS_PINID='B';
NODE_NAME     R6036 2
 '@T6G_MB_LIB.T6G(SCH_1):PAGE349_I131@PURE_QUANTA.Q_RES(CHIPS)':
 'B': CDS_PINID='B';
NODE_NAME     R6037 2
 '@T6G_MB_LIB.T6G(SCH_1):PAGE349_I132@PURE_QUANTA.Q_RES(CHIPS)':
 'B': CDS_PINID='B';
NODE_NAME     R329 2
 '@T6G_MB_LIB.T6G(SCH_1):PAGE349_I133@PURE_QUANTA.Q_RES(CHIPS)':
 'B': CDS_PINID='B';
NODE_NAME     R1386 2
 '@T6G_MB_LIB.T6G(SCH_1):PAGE349_I134@PURE_QUANTA.Q_RES(CHIPS)':
 'B': CDS_PINID='B';
NODE_NAME     R1385 2
 '@T6G_MB_LIB.T6G(SCH_1):PAGE349_I135@PURE_QUANTA.Q_RES(CHIPS)':
 'B': CDS_PINID='B';
NODE_NAME     R1384 2
 '@T6G_MB_LIB.T6G(SCH_1):PAGE349_I136@PURE_QUANTA.Q_RES(CHIPS)':
 'B': CDS_PINID='B';
NODE_NAME     R3062 2
 '@T6G_MB_LIB.T6G(SCH_1):PAGE349_I137@PURE_QUANTA.Q_RES(CHIPS)':
 'B': CDS_PINID='B';
NODE_NAME     R1319 2
 '@T6G_MB_LIB.T6G(SCH_1):PAGE349_I138@PURE_QUANTA.Q_RES(CHIPS)':
 'B': CDS_PINID='B';
NODE_NAME     R888 1
 '@T6G_MB_LIB.T6G(SCH_1):PAGE349_I145@PURE_QUANTA.Q_RES(CHIPS)':
 'A': CDS_PINID='A';
NODE_NAME     R890 1
 '@T6G_MB_LIB.T6G(SCH_1):PAGE349_I147@PURE_QUANTA.Q_RES(CHIPS)':
 'A': CDS_PINID='A';
NODE_NAME     R2693 1
 '@T6G_MB_LIB.T6G(SCH_1):PAGE246_I3@PURE_QUANTA.Q_RES(CHIPS)':
 'A': CDS_PINID='A';
NODE_NAME     R2695 1
 '@T6G_MB_LIB.T6G(SCH_1):PAGE246_I7@PURE_QUANTA.Q_RES(CHIPS)':
 'A': CDS_PINID='A';
NODE_NAME     R2921 1
 '@T6G_MB_LIB.T6G(SCH_1):PAGE246_I35@PURE_QUANTA.Q_RES(CHIPS)':
 'A': CDS_PINID='A';
NODE_NAME     U248 5
 '@T6G_MB_LIB.T6G(SCH_1):PAGE232_I26@PURE_QUANTA.74LVC1G32GW(CHIPS)':
 'VCC': CDS_PINID='VCC';
NODE_NAME     C1882 1
 '@T6G_MB_LIB.T6G(SCH_1):PAGE232_I28@PURE_QUANTA.Q_CAP(CHIPS)':
 'A': CDS_PINID='A';
NODE_NAME     L17 1
 '@T6G_MB_LIB.T6G(SCH_1):PAGE232_I33@PURE_QUANTA.Q_INDUCTOR(CHIPS)':
 '1': CDS_PINID='\1\';
NODE_NAME     R4078 1
 '@T6G_MB_LIB.T6G(SCH_1):PAGE232_I47@PURE_QUANTA.Q_RES(CHIPS)':
 'A': CDS_PINID='A';
NODE_NAME     R4081 1
 '@T6G_MB_LIB.T6G(SCH_1):PAGE232_I56@PURE_QUANTA.Q_RES(CHIPS)':
 'A': CDS_PINID='A';
NODE_NAME     R4080 1
 '@T6G_MB_LIB.T6G(SCH_1):PAGE232_I59@PURE_QUANTA.Q_RES(CHIPS)':
 'A': CDS_PINID='A';
NODE_NAME     C1859 1
 '@T6G_MB_LIB.T6G(SCH_1):PAGE248_I4@PURE_QUANTA.Q_CAP(CHIPS)':
 'A': CDS_PINID='A';
NODE_NAME     U235 1
 '@T6G_MB_LIB.T6G(SCH_1):PAGE248_I6@PURE_QUANTA.PCA9617ADP(CHIPS)':
 'VCCA': CDS_PINID='VCCA';
NODE_NAME     U236 1
 '@T6G_MB_LIB.T6G(SCH_1):PAGE248_I14@PURE_QUANTA.PCA9617ADP(CHIPS)':
 'VCCA': CDS_PINID='VCCA';
NODE_NAME     C1860 1
 '@T6G_MB_LIB.T6G(SCH_1):PAGE248_I15@PURE_QUANTA.Q_CAP(CHIPS)':
 'A': CDS_PINID='A';
NODE_NAME     U200 8
 '@T6G_MB_LIB.T6G(SCH_1):PAGE249_I15@PURE_QUANTA.LTC4307CMS8(CHIPS)':
 'VCC': CDS_PINID='VCC';
NODE_NAME     U176 8
 '@T6G_MB_LIB.T6G(SCH_1):PAGE249_I30@PURE_QUANTA.LTC4307CMS8(CHIPS)':
 'VCC': CDS_PINID='VCC';
NODE_NAME     C1796 1
 '@T6G_MB_LIB.T6G(SCH_1):PAGE249_I32@PURE_QUANTA.Q_CAP(CHIPS)':
 'A': CDS_PINID='A';
NODE_NAME     R3521 1
 '@T6G_MB_LIB.T6G(SCH_1):PAGE249_I36@PURE_QUANTA.Q_RES(CHIPS)':
 'A': CDS_PINID='A';
NODE_NAME     R3522 1
 '@T6G_MB_LIB.T6G(SCH_1):PAGE249_I37@PURE_QUANTA.Q_RES(CHIPS)':
 'A': CDS_PINID='A';
NODE_NAME     U194 8
 '@T6G_MB_LIB.T6G(SCH_1):PAGE249_I42@PURE_QUANTA.LTC4307CMS8(CHIPS)':
 'VCC': CDS_PINID='VCC';
NODE_NAME     U175 8
 '@T6G_MB_LIB.T6G(SCH_1):PAGE249_I49@PURE_QUANTA.LTC4307CMS8(CHIPS)':
 'VCC': CDS_PINID='VCC';
NODE_NAME     C1707 1
 '@T6G_MB_LIB.T6G(SCH_1):PAGE249_I52@PURE_QUANTA.Q_CAP(CHIPS)':
 'A': CDS_PINID='A';
NODE_NAME     R2667 1
 '@T6G_MB_LIB.T6G(SCH_1):PAGE249_I54@PURE_QUANTA.Q_RES(CHIPS)':
 'A': CDS_PINID='A';
NODE_NAME     R2669 1
 '@T6G_MB_LIB.T6G(SCH_1):PAGE249_I57@PURE_QUANTA.Q_RES(CHIPS)':
 'A': CDS_PINID='A';
NODE_NAME     C1708 1
 '@T6G_MB_LIB.T6G(SCH_1):PAGE249_I61@PURE_QUANTA.Q_CAP(CHIPS)':
 'A': CDS_PINID='A';
NODE_NAME     R2668 1
 '@T6G_MB_LIB.T6G(SCH_1):PAGE249_I62@PURE_QUANTA.Q_RES(CHIPS)':
 'A': CDS_PINID='A';
NODE_NAME     R2670 1
 '@T6G_MB_LIB.T6G(SCH_1):PAGE249_I63@PURE_QUANTA.Q_RES(CHIPS)':
 'A': CDS_PINID='A';
NODE_NAME     C1766 1
 '@T6G_MB_LIB.T6G(SCH_1):PAGE249_I78@PURE_QUANTA.Q_CAP(CHIPS)':
 'A': CDS_PINID='A';
NODE_NAME     R3523 1
 '@T6G_MB_LIB.T6G(SCH_1):PAGE249_I80@PURE_QUANTA.Q_RES(CHIPS)':
 'A': CDS_PINID='A';
NODE_NAME     R3524 1
 '@T6G_MB_LIB.T6G(SCH_1):PAGE249_I81@PURE_QUANTA.Q_RES(CHIPS)':
 'A': CDS_PINID='A';
NODE_NAME     C611 1
 '@T6G_MB_LIB.T6G(SCH_1):PAGE137_I6@PURE_QUANTA.Q_CAP(CHIPS)':
 'A': CDS_PINID='A';
NODE_NAME     R200 1
 '@T6G_MB_LIB.T6G(SCH_1):PAGE137_I13@PURE_QUANTA.Q_RES(CHIPS)':
 'A': CDS_PINID='A';
NODE_NAME     C23 1
 '@T6G_MB_LIB.T6G(SCH_1):PAGE137_I26@PURE_QUANTA.Q_CAP(CHIPS)':
 'A': CDS_PINID='A';
NODE_NAME     U5 1
 '@T6G_MB_LIB.T6G(SCH_1):PAGE137_I48@PURE_QUANTA.PCA9617ADP(CHIPS)':
 'VCCA': CDS_PINID='VCCA';
NODE_NAME     R3703 1
 '@T6G_MB_LIB.T6G(SCH_1):PAGE251_I7@PURE_QUANTA.Q_RES(CHIPS)':
 'A': CDS_PINID='A';
NODE_NAME     R3706 1
 '@T6G_MB_LIB.T6G(SCH_1):PAGE251_I8@PURE_QUANTA.Q_RES(CHIPS)':
 'A': CDS_PINID='A';
NODE_NAME     R3708 1
 '@T6G_MB_LIB.T6G(SCH_1):PAGE251_I10@PURE_QUANTA.Q_RES(CHIPS)':
 'A': CDS_PINID='A';
NODE_NAME     R3705 1
 '@T6G_MB_LIB.T6G(SCH_1):PAGE251_I27@PURE_QUANTA.Q_RES(CHIPS)':
 'A': CDS_PINID='A';
NODE_NAME     C2056 1
 '@T6G_MB_LIB.T6G(SCH_1):PAGE251_I38@PURE_QUANTA.Q_CAP(CHIPS)':
 'A': CDS_PINID='A';
NODE_NAME     R4270 1
 '@T6G_MB_LIB.T6G(SCH_1):PAGE251_I40@PURE_QUANTA.Q_RES(CHIPS)':
 'A': CDS_PINID='A';
NODE_NAME     R4269 1
 '@T6G_MB_LIB.T6G(SCH_1):PAGE251_I41@PURE_QUANTA.Q_RES(CHIPS)':
 'A': CDS_PINID='A';
NODE_NAME     R3732 1
 '@T6G_MB_LIB.T6G(SCH_1):PAGE251_I42@PURE_QUANTA.Q_RES(CHIPS)':
 'A': CDS_PINID='A';
NODE_NAME     R3731 1
 '@T6G_MB_LIB.T6G(SCH_1):PAGE251_I43@PURE_QUANTA.Q_RES(CHIPS)':
 'A': CDS_PINID='A';
NODE_NAME     R3729 1
 '@T6G_MB_LIB.T6G(SCH_1):PAGE251_I44@PURE_QUANTA.Q_RES(CHIPS)':
 'A': CDS_PINID='A';
NODE_NAME     R3730 1
 '@T6G_MB_LIB.T6G(SCH_1):PAGE251_I45@PURE_QUANTA.Q_RES(CHIPS)':
 'A': CDS_PINID='A';
NODE_NAME     R3728 1
 '@T6G_MB_LIB.T6G(SCH_1):PAGE251_I47@PURE_QUANTA.Q_RES(CHIPS)':
 'A': CDS_PINID='A';
NODE_NAME     R3727 1
 '@T6G_MB_LIB.T6G(SCH_1):PAGE251_I48@PURE_QUANTA.Q_RES(CHIPS)':
 'A': CDS_PINID='A';
NODE_NAME     R3726 1
 '@T6G_MB_LIB.T6G(SCH_1):PAGE251_I49@PURE_QUANTA.Q_RES(CHIPS)':
 'A': CDS_PINID='A';
NODE_NAME     R3725 1
 '@T6G_MB_LIB.T6G(SCH_1):PAGE251_I50@PURE_QUANTA.Q_RES(CHIPS)':
 'A': CDS_PINID='A';
NODE_NAME     R3724 1
 '@T6G_MB_LIB.T6G(SCH_1):PAGE251_I52@PURE_QUANTA.Q_RES(CHIPS)':
 'A': CDS_PINID='A';
NODE_NAME     R3723 1
 '@T6G_MB_LIB.T6G(SCH_1):PAGE251_I53@PURE_QUANTA.Q_RES(CHIPS)':
 'A': CDS_PINID='A';
NODE_NAME     U39 24
 '@T6G_MB_LIB.T6G(SCH_1):PAGE251_I74@PURE_QUANTA.TCA9548APWR(CHIPS)':
 'VCC': CDS_PINID='VCC';
NODE_NAME     R316 1
 '@T6G_MB_LIB.T6G(SCH_1):PAGE252_I7@PURE_QUANTA.Q_RES(CHIPS)':
 'A': CDS_PINID='A';
NODE_NAME     R318 1
 '@T6G_MB_LIB.T6G(SCH_1):PAGE252_I8@PURE_QUANTA.Q_RES(CHIPS)':
 'A': CDS_PINID='A';
NODE_NAME     R320 1
 '@T6G_MB_LIB.T6G(SCH_1):PAGE252_I10@PURE_QUANTA.Q_RES(CHIPS)':
 'A': CDS_PINID='A';
NODE_NAME     R1822 1
 '@T6G_MB_LIB.T6G(SCH_1):PAGE252_I21@PURE_QUANTA.Q_RES(CHIPS)':
 'A': CDS_PINID='A';
NODE_NAME     U36 24
 '@T6G_MB_LIB.T6G(SCH_1):PAGE252_I33@PURE_QUANTA.TCA9548APWR(CHIPS)':
 'VCC': CDS_PINID='VCC';
NODE_NAME     C106 1
 '@T6G_MB_LIB.T6G(SCH_1):PAGE252_I34@PURE_QUANTA.Q_CAP(CHIPS)':
 'A': CDS_PINID='A';
NODE_NAME     R1089 1
 '@T6G_MB_LIB.T6G(SCH_1):PAGE252_I37@PURE_QUANTA.Q_RES(CHIPS)':
 'A': CDS_PINID='A';
NODE_NAME     R1090 1
 '@T6G_MB_LIB.T6G(SCH_1):PAGE252_I38@PURE_QUANTA.Q_RES(CHIPS)':
 'A': CDS_PINID='A';
NODE_NAME     R67 1
 '@T6G_MB_LIB.T6G(SCH_1):PAGE252_I39@PURE_QUANTA.Q_RES(CHIPS)':
 'A': CDS_PINID='A';
NODE_NAME     R66 1
 '@T6G_MB_LIB.T6G(SCH_1):PAGE252_I40@PURE_QUANTA.Q_RES(CHIPS)':
 'A': CDS_PINID='A';
NODE_NAME     R2984 1
 '@T6G_MB_LIB.T6G(SCH_1):PAGE252_I41@PURE_QUANTA.Q_RES(CHIPS)':
 'A': CDS_PINID='A';
NODE_NAME     R2985 1
 '@T6G_MB_LIB.T6G(SCH_1):PAGE252_I42@PURE_QUANTA.Q_RES(CHIPS)':
 'A': CDS_PINID='A';
NODE_NAME     R3536 1
 '@T6G_MB_LIB.T6G(SCH_1):PAGE252_I43@PURE_QUANTA.Q_RES(CHIPS)':
 'A': CDS_PINID='A';
NODE_NAME     R3535 1
 '@T6G_MB_LIB.T6G(SCH_1):PAGE252_I44@PURE_QUANTA.Q_RES(CHIPS)':
 'A': CDS_PINID='A';
NODE_NAME     R3583 1
 '@T6G_MB_LIB.T6G(SCH_1):PAGE252_I45@PURE_QUANTA.Q_RES(CHIPS)':
 'A': CDS_PINID='A';
NODE_NAME     R3582 1
 '@T6G_MB_LIB.T6G(SCH_1):PAGE252_I46@PURE_QUANTA.Q_RES(CHIPS)':
 'A': CDS_PINID='A';
NODE_NAME     R3395 1
 '@T6G_MB_LIB.T6G(SCH_1):PAGE252_I47@PURE_QUANTA.Q_RES(CHIPS)':
 'A': CDS_PINID='A';
NODE_NAME     R3396 1
 '@T6G_MB_LIB.T6G(SCH_1):PAGE252_I48@PURE_QUANTA.Q_RES(CHIPS)':
 'A': CDS_PINID='A';
NODE_NAME     R2205 1
 '@T6G_MB_LIB.T6G(SCH_1):PAGE252_I49@PURE_QUANTA.Q_RES(CHIPS)':
 'A': CDS_PINID='A';
NODE_NAME     R2204 1
 '@T6G_MB_LIB.T6G(SCH_1):PAGE252_I50@PURE_QUANTA.Q_RES(CHIPS)':
 'A': CDS_PINID='A';
NODE_NAME     U134 5
 '@T6G_MB_LIB.T6G(SCH_1):PAGE297_I4@PURE_QUANTA.74LVC2G07DW7(CHIPS)':
 'VCC': CDS_PINID='VCC';
NODE_NAME     R3771 1
 '@T6G_MB_LIB.T6G(SCH_1):PAGE297_I7@PURE_QUANTA.Q_RES(CHIPS)':
 'A': CDS_PINID='A';
NODE_NAME     C1592 1
 '@T6G_MB_LIB.T6G(SCH_1):PAGE297_I36@PURE_QUANTA.Q_CAP(CHIPS)':
 'A': CDS_PINID='A';
NODE_NAME     R2125 1
 '@T6G_MB_LIB.T6G(SCH_1):PAGE297_I40@PURE_QUANTA.Q_RES(CHIPS)':
 'A': CDS_PINID='A';
NODE_NAME     U259 5
 '@T6G_MB_LIB.T6G(SCH_1):PAGE345_I5@PURE_QUANTA.SN74LVC2G07DCKR(CHIPS)':
 'VCC': CDS_PINID='VCC';
NODE_NAME     C2007 1
 '@T6G_MB_LIB.T6G(SCH_1):PAGE345_I6@PURE_QUANTA.Q_CAP(CHIPS)':
 'A': CDS_PINID='A';
NODE_NAME     R2121 1
 '@T6G_MB_LIB.T6G(SCH_1):PAGE345_I10@PURE_QUANTA.Q_RES(CHIPS)':
 'A': CDS_PINID='A';
NODE_NAME     R178 1
 '@T6G_MB_LIB.T6G(SCH_1):PAGE345_I24@PURE_QUANTA.Q_RES(CHIPS)':
 'A': CDS_PINID='A';
NODE_NAME     R155 1
 '@T6G_MB_LIB.T6G(SCH_1):PAGE345_I32@PURE_QUANTA.Q_RES(CHIPS)':
 'A': CDS_PINID='A';
NODE_NAME     R3296 1
 '@T6G_MB_LIB.T6G(SCH_1):PAGE345_I51@PURE_QUANTA.Q_RES(CHIPS)':
 'A': CDS_PINID='A';
NODE_NAME     U239 5
 '@T6G_MB_LIB.T6G(SCH_1):PAGE345_I53@PURE_QUANTA.74LVC1G126SE7(CHIPS)':
 'VCC': CDS_PINID='VCC';
NODE_NAME     C1873 1
 '@T6G_MB_LIB.T6G(SCH_1):PAGE345_I56@PURE_QUANTA.Q_CAP(CHIPS)':
 'A': CDS_PINID='A';
NODE_NAME     R3298 1
 '@T6G_MB_LIB.T6G(SCH_1):PAGE345_I58@PURE_QUANTA.Q_RES(CHIPS)':
 'A': CDS_PINID='A';
NODE_NAME     R1396 2
 '@T6G_MB_LIB.T6G(SCH_1):PAGE345_I66@PURE_QUANTA.Q_RES(CHIPS)':
 'B': CDS_PINID='B';
NODE_NAME     R3271 1
 '@T6G_MB_LIB.T6G(SCH_1):PAGE110_I5@PURE_QUANTA.Q_RES(CHIPS)':
 'A': CDS_PINID='A';
NODE_NAME     R3269 1
 '@T6G_MB_LIB.T6G(SCH_1):PAGE110_I14@PURE_QUANTA.Q_RES(CHIPS)':
 'A': CDS_PINID='A';
NODE_NAME     R3277 1
 '@T6G_MB_LIB.T6G(SCH_1):PAGE110_I19@PURE_QUANTA.Q_RES(CHIPS)':
 'A': CDS_PINID='A';
NODE_NAME     R3280 1
 '@T6G_MB_LIB.T6G(SCH_1):PAGE110_I26@PURE_QUANTA.Q_RES(CHIPS)':
 'A': CDS_PINID='A';
NODE_NAME     R3275 1
 '@T6G_MB_LIB.T6G(SCH_1):PAGE110_I32@PURE_QUANTA.Q_RES(CHIPS)':
 'A': CDS_PINID='A';
NODE_NAME     R3283 1
 '@T6G_MB_LIB.T6G(SCH_1):PAGE110_I37@PURE_QUANTA.Q_RES(CHIPS)':
 'A': CDS_PINID='A';
NODE_NAME     R3286 1
 '@T6G_MB_LIB.T6G(SCH_1):PAGE110_I45@PURE_QUANTA.Q_RES(CHIPS)':
 'A': CDS_PINID='A';
NODE_NAME     C1867 1
 '@T6G_MB_LIB.T6G(SCH_1):PAGE110_I60@PURE_QUANTA.Q_CAP(CHIPS)':
 'A': CDS_PINID='A';
NODE_NAME     C1863 1
 '@T6G_MB_LIB.T6G(SCH_1):PAGE110_I61@PURE_QUANTA.Q_CAP(CHIPS)':
 'A': CDS_PINID='A';
NODE_NAME     C1864 1
 '@T6G_MB_LIB.T6G(SCH_1):PAGE110_I62@PURE_QUANTA.Q_CAP(CHIPS)':
 'A': CDS_PINID='A';
NODE_NAME     U237 1
 '@T6G_MB_LIB.T6G(SCH_1):PAGE110_I63@PURE_QUANTA.PI3EQX12902AZLEX(CHIPS)':
 'VDD1': CDS_PINID='VDD1';
NODE_NAME     U237 10
 '@T6G_MB_LIB.T6G(SCH_1):PAGE110_I63@PURE_QUANTA.PI3EQX12902AZLEX(CHIPS)':
 'VDD2': CDS_PINID='VDD2';
NODE_NAME     U237 16
 '@T6G_MB_LIB.T6G(SCH_1):PAGE110_I63@PURE_QUANTA.PI3EQX12902AZLEX(CHIPS)':
 'VDD3': CDS_PINID='VDD3';
NODE_NAME     U237 25
 '@T6G_MB_LIB.T6G(SCH_1):PAGE110_I63@PURE_QUANTA.PI3EQX12902AZLEX(CHIPS)':
 'VDD4': CDS_PINID='VDD4';
NODE_NAME     C1865 1
 '@T6G_MB_LIB.T6G(SCH_1):PAGE110_I64@PURE_QUANTA.Q_CAP(CHIPS)':
 'A': CDS_PINID='A';
NODE_NAME     C1866 1
 '@T6G_MB_LIB.T6G(SCH_1):PAGE110_I65@PURE_QUANTA.Q_CAP(CHIPS)':
 'A': CDS_PINID='A';
NODE_NAME     R3289 1
 '@T6G_MB_LIB.T6G(SCH_1):PAGE110_I77@PURE_QUANTA.Q_RES(CHIPS)':
 'A': CDS_PINID='A';
NODE_NAME     R3292 1
 '@T6G_MB_LIB.T6G(SCH_1):PAGE110_I89@PURE_QUANTA.Q_RES(CHIPS)':
 'A': CDS_PINID='A';
NODE_NAME     R3266 1
 '@T6G_MB_LIB.T6G(SCH_1):PAGE110_I93@PURE_QUANTA.Q_RES(CHIPS)':
 'A': CDS_PINID='A';
NODE_NAME     R4604 1
 '@T6G_MB_LIB.T6G(SCH_1):PAGE368_I5@PURE_QUANTA.Q_RES(CHIPS)':
 'A': CDS_PINID='A';
NODE_NAME     R4605 1
 '@T6G_MB_LIB.T6G(SCH_1):PAGE368_I11@PURE_QUANTA.Q_RES(CHIPS)':
 'A': CDS_PINID='A';
NODE_NAME     R3075 2
 '@T6G_MB_LIB.T6G(SCH_1):PAGE254_I15@PURE_QUANTA.Q_RES(CHIPS)':
 'B': CDS_PINID='B';
NODE_NAME     R638 2
 '@T6G_MB_LIB.T6G(SCH_1):PAGE82_I35@PURE_QUANTA.Q_RES(CHIPS)':
 'B': CDS_PINID='B';
NODE_NAME     R1195 2
 '@T6G_MB_LIB.T6G(SCH_1):PAGE82_I36@PURE_QUANTA.Q_RES(CHIPS)':
 'B': CDS_PINID='B';
NODE_NAME     R6061 2
 '@T6G_MB_LIB.T6G(SCH_1):PAGE82_I39@PURE_QUANTA.Q_RES(CHIPS)':
 'B': CDS_PINID='B';
NODE_NAME     R6062 2
 '@T6G_MB_LIB.T6G(SCH_1):PAGE82_I40@PURE_QUANTA.Q_RES(CHIPS)':
 'B': CDS_PINID='B';
NODE_NAME     R993 2
 '@T6G_MB_LIB.T6G(SCH_1):PAGE82_I53@PURE_QUANTA.Q_RES(CHIPS)':
 'B': CDS_PINID='B';
NODE_NAME     R1314 2
 '@T6G_MB_LIB.T6G(SCH_1):PAGE82_I54@PURE_QUANTA.Q_RES(CHIPS)':
 'B': CDS_PINID='B';
NODE_NAME     R1527 2
 '@T6G_MB_LIB.T6G(SCH_1):PAGE82_I56@PURE_QUANTA.Q_RES(CHIPS)':
 'B': CDS_PINID='B';
NODE_NAME     R1189 2
 '@T6G_MB_LIB.T6G(SCH_1):PAGE82_I57@PURE_QUANTA.Q_RES(CHIPS)':
 'B': CDS_PINID='B';
NODE_NAME     R1190 2
 '@T6G_MB_LIB.T6G(SCH_1):PAGE82_I58@PURE_QUANTA.Q_RES(CHIPS)':
 'B': CDS_PINID='B';
NODE_NAME     R1187 2
 '@T6G_MB_LIB.T6G(SCH_1):PAGE82_I59@PURE_QUANTA.Q_RES(CHIPS)':
 'B': CDS_PINID='B';
NODE_NAME     R1186 2
 '@T6G_MB_LIB.T6G(SCH_1):PAGE82_I60@PURE_QUANTA.Q_RES(CHIPS)':
 'B': CDS_PINID='B';
NODE_NAME     R1188 2
 '@T6G_MB_LIB.T6G(SCH_1):PAGE82_I61@PURE_QUANTA.Q_RES(CHIPS)':
 'B': CDS_PINID='B';
NODE_NAME     R1185 2
 '@T6G_MB_LIB.T6G(SCH_1):PAGE82_I62@PURE_QUANTA.Q_RES(CHIPS)':
 'B': CDS_PINID='B';
NODE_NAME     C358 1
 '@T6G_MB_LIB.T6G(SCH_1):PAGE82_I105@PURE_QUANTA.Q_CAP(CHIPS)':
 'A': CDS_PINID='A';
NODE_NAME     C357 1
 '@T6G_MB_LIB.T6G(SCH_1):PAGE82_I106@PURE_QUANTA.Q_CAP(CHIPS)':
 'A': CDS_PINID='A';
NODE_NAME     C356 1
 '@T6G_MB_LIB.T6G(SCH_1):PAGE82_I107@PURE_QUANTA.Q_CAP(CHIPS)':
 'A': CDS_PINID='A';
NODE_NAME     C355 1
 '@T6G_MB_LIB.T6G(SCH_1):PAGE82_I108@PURE_QUANTA.Q_CAP(CHIPS)':
 'A': CDS_PINID='A';
NODE_NAME     C1176 1
 '@T6G_MB_LIB.T6G(SCH_1):PAGE82_I109@PURE_QUANTA.Q_CAP(CHIPS)':
 'A': CDS_PINID='A';
NODE_NAME     C1175 1
 '@T6G_MB_LIB.T6G(SCH_1):PAGE82_I110@PURE_QUANTA.Q_CAP(CHIPS)':
 'A': CDS_PINID='A';
NODE_NAME     C1174 1
 '@T6G_MB_LIB.T6G(SCH_1):PAGE82_I111@PURE_QUANTA.Q_CAP(CHIPS)':
 'A': CDS_PINID='A';
NODE_NAME     C1172 1
 '@T6G_MB_LIB.T6G(SCH_1):PAGE82_I112@PURE_QUANTA.Q_CAP(CHIPS)':
 'A': CDS_PINID='A';
NODE_NAME     C1173 1
 '@T6G_MB_LIB.T6G(SCH_1):PAGE82_I113@PURE_QUANTA.Q_CAP(CHIPS)':
 'A': CDS_PINID='A';
NODE_NAME     C1171 1
 '@T6G_MB_LIB.T6G(SCH_1):PAGE82_I114@PURE_QUANTA.Q_CAP(CHIPS)':
 'A': CDS_PINID='A';
NODE_NAME     R1906 1
 '@T6G_MB_LIB.T6G(SCH_1):PAGE338_I9@PURE_QUANTA.Q_RES(CHIPS)':
 'A': CDS_PINID='A';
NODE_NAME     R1905 1
 '@T6G_MB_LIB.T6G(SCH_1):PAGE338_I15@PURE_QUANTA.Q_RES(CHIPS)':
 'A': CDS_PINID='A';
NODE_NAME     R1908 1
 '@T6G_MB_LIB.T6G(SCH_1):PAGE338_I24@PURE_QUANTA.Q_RES(CHIPS)':
 'A': CDS_PINID='A';
NODE_NAME     U8 5
 '@T6G_MB_LIB.T6G(SCH_1):PAGE338_I26@PURE_QUANTA.74LVC2G07DW7(CHIPS)':
 'VCC': CDS_PINID='VCC';
NODE_NAME     R1907 1
 '@T6G_MB_LIB.T6G(SCH_1):PAGE338_I28@PURE_QUANTA.Q_RES(CHIPS)':
 'A': CDS_PINID='A';
NODE_NAME     U211 5
 '@T6G_MB_LIB.T6G(SCH_1):PAGE338_I29@PURE_QUANTA.74LVC2G07DW7(CHIPS)':
 'VCC': CDS_PINID='VCC';
NODE_NAME     C593 1
 '@T6G_MB_LIB.T6G(SCH_1):PAGE338_I30@PURE_QUANTA.Q_CAP(CHIPS)':
 'A': CDS_PINID='A';
NODE_NAME     C592 1
 '@T6G_MB_LIB.T6G(SCH_1):PAGE338_I33@PURE_QUANTA.Q_CAP(CHIPS)':
 'A': CDS_PINID='A';
NODE_NAME     PC5328 1
 '@T6G_MB_LIB.T6G(SCH_1):PAGE338_I62@PURE_QUANTA.Q_CAP(CHIPS)':
 'A': CDS_PINID='A';
NODE_NAME     PR3789 1
 '@T6G_MB_LIB.T6G(SCH_1):PAGE338_I66@PURE_QUANTA.Q_RES(CHIPS)':
 'A': CDS_PINID='A';
NODE_NAME     PR3798 1
 '@T6G_MB_LIB.T6G(SCH_1):PAGE338_I68@PURE_QUANTA.Q_RES(CHIPS)':
 'A': CDS_PINID='A';
NODE_NAME     R1150 1
 '@T6G_MB_LIB.T6G(SCH_1):PAGE338_I71@PURE_QUANTA.Q_RES(CHIPS)':
 'A': CDS_PINID='A';
NODE_NAME     R3799 1
 '@T6G_MB_LIB.T6G(SCH_1):PAGE338_I83@PURE_QUANTA.Q_RES(CHIPS)':
 'A': CDS_PINID='A';
NODE_NAME     R3797 1
 '@T6G_MB_LIB.T6G(SCH_1):PAGE338_I85@PURE_QUANTA.Q_RES(CHIPS)':
 'A': CDS_PINID='A';
NODE_NAME     R3796 1
 '@T6G_MB_LIB.T6G(SCH_1):PAGE338_I101@PURE_QUANTA.Q_RES(CHIPS)':
 'A': CDS_PINID='A';
NODE_NAME     PU202 A3
 '@T6G_MB_LIB.T6G(SCH_1):PAGE338_I113@PURE_QUANTA.MAX15090BEWIT(CHIPS)':
 'IN_A3': CDS_PINID='IN_A3';
NODE_NAME     PU202 A5
 '@T6G_MB_LIB.T6G(SCH_1):PAGE338_I113@PURE_QUANTA.MAX15090BEWIT(CHIPS)':
 'IN_A5': CDS_PINID='IN_A5';
NODE_NAME     PU202 B3
 '@T6G_MB_LIB.T6G(SCH_1):PAGE338_I113@PURE_QUANTA.MAX15090BEWIT(CHIPS)':
 'IN_B3': CDS_PINID='IN_B3';
NODE_NAME     PU202 B5
 '@T6G_MB_LIB.T6G(SCH_1):PAGE338_I113@PURE_QUANTA.MAX15090BEWIT(CHIPS)':
 'IN_B5': CDS_PINID='IN_B5';
NODE_NAME     PU202 C3
 '@T6G_MB_LIB.T6G(SCH_1):PAGE338_I113@PURE_QUANTA.MAX15090BEWIT(CHIPS)':
 'IN_C3': CDS_PINID='IN_C3';
NODE_NAME     PU202 C5
 '@T6G_MB_LIB.T6G(SCH_1):PAGE338_I113@PURE_QUANTA.MAX15090BEWIT(CHIPS)':
 'IN_C5': CDS_PINID='IN_C5';
NODE_NAME     PU202 D5
 '@T6G_MB_LIB.T6G(SCH_1):PAGE338_I113@PURE_QUANTA.MAX15090BEWIT(CHIPS)':
 'IN_D5': CDS_PINID='IN_D5';
NODE_NAME     R1338 1
 '@T6G_MB_LIB.T6G(SCH_1):PAGE83_I29@PURE_QUANTA.Q_RES(CHIPS)':
 'A': CDS_PINID='A';
NODE_NAME     R6042 1
 '@T6G_MB_LIB.T6G(SCH_1):PAGE144_I62@PURE_QUANTA.Q_RES(CHIPS)':
 'A': CDS_PINID='A';
NODE_NAME     R1357 1
 '@T6G_MB_LIB.T6G(SCH_1):PAGE144_I74@PURE_QUANTA.Q_RES(CHIPS)':
 'A': CDS_PINID='A';
NODE_NAME     R1356 1
 '@T6G_MB_LIB.T6G(SCH_1):PAGE144_I77@PURE_QUANTA.Q_RES(CHIPS)':
 'A': CDS_PINID='A';
NODE_NAME     R3977 1
 '@T6G_MB_LIB.T6G(SCH_1):PAGE324_I52@PURE_QUANTA.Q_RES(CHIPS)':
 'A': CDS_PINID='A';
NODE_NAME     R3978 1
 '@T6G_MB_LIB.T6G(SCH_1):PAGE324_I86@PURE_QUANTA.Q_RES(CHIPS)':
 'A': CDS_PINID='A';
NODE_NAME     PU295 A3
 '@T6G_MB_LIB.T6G(SCH_1):PAGE324_I88@PURE_QUANTA.MAX15090BEWIT(CHIPS)':
 'IN_A3': CDS_PINID='IN_A3';
NODE_NAME     PU295 A5
 '@T6G_MB_LIB.T6G(SCH_1):PAGE324_I88@PURE_QUANTA.MAX15090BEWIT(CHIPS)':
 'IN_A5': CDS_PINID='IN_A5';
NODE_NAME     PU295 B3
 '@T6G_MB_LIB.T6G(SCH_1):PAGE324_I88@PURE_QUANTA.MAX15090BEWIT(CHIPS)':
 'IN_B3': CDS_PINID='IN_B3';
NODE_NAME     PU295 B5
 '@T6G_MB_LIB.T6G(SCH_1):PAGE324_I88@PURE_QUANTA.MAX15090BEWIT(CHIPS)':
 'IN_B5': CDS_PINID='IN_B5';
NODE_NAME     PU295 C3
 '@T6G_MB_LIB.T6G(SCH_1):PAGE324_I88@PURE_QUANTA.MAX15090BEWIT(CHIPS)':
 'IN_C3': CDS_PINID='IN_C3';
NODE_NAME     PU295 C5
 '@T6G_MB_LIB.T6G(SCH_1):PAGE324_I88@PURE_QUANTA.MAX15090BEWIT(CHIPS)':
 'IN_C5': CDS_PINID='IN_C5';
NODE_NAME     PU295 D5
 '@T6G_MB_LIB.T6G(SCH_1):PAGE324_I88@PURE_QUANTA.MAX15090BEWIT(CHIPS)':
 'IN_D5': CDS_PINID='IN_D5';
NODE_NAME     PR3839 2
 '@T6G_MB_LIB.T6G(SCH_1):PAGE339_I74@PURE_QUANTA.Q_RES(CHIPS)':
 'B': CDS_PINID='B';
NODE_NAME     R4532 1
 '@T6G_MB_LIB.T6G(SCH_1):PAGE339_I75@PURE_QUANTA.Q_RES(CHIPS)':
 'A': CDS_PINID='A';
NODE_NAME     PC2159 1
 '@T6G_MB_LIB.T6G(SCH_1):PAGE339_I111@PURE_QUANTA.Q_CAP(CHIPS)':
 'A': CDS_PINID='A';
NODE_NAME     PU205 1_2
 '@T6G_MB_LIB.T6G(SCH_1):PAGE339_I113@PURE_QUANTA.MP5016GQHLZ(CHIPS)':
 'VCC': CDS_PINID='VCC';
NODE_NAME     R1303 2
 '@T6G_MB_LIB.T6G(SCH_1):PAGE84_I5@PURE_QUANTA.Q_RES(CHIPS)':
 'B': CDS_PINID='B';
NODE_NAME     J57 1
 '@T6G_MB_LIB.T6G(SCH_1):PAGE84_I41@PURE_QUANTA.CONN8_HBB1081L200D8H(CHIPS)':
 '1': CDS_PINID='\1\';
NODE_NAME     C20 1
 '@T6G_MB_LIB.T6G(SCH_1):PAGE84_I42@PURE_QUANTA.Q_CAP(CHIPS)':
 'A': CDS_PINID='A';
NODE_NAME     PR836 2
 '@T6G_MB_LIB.T6G(SCH_1):PAGE245_I46@PURE_QUANTA.Q_RES(CHIPS)':
 'B': CDS_PINID='B';
NODE_NAME     PR831 2
 '@T6G_MB_LIB.T6G(SCH_1):PAGE245_I54@PURE_QUANTA.Q_RES(CHIPS)':
 'B': CDS_PINID='B';
NODE_NAME     PC1599 1
 '@T6G_MB_LIB.T6G(SCH_1):PAGE245_I60@PURE_QUANTA.Q_CAP(CHIPS)':
 'A': CDS_PINID='A';
NODE_NAME     PR285 1
 '@T6G_MB_LIB.T6G(SCH_1):PAGE168_I18@PURE_QUANTA.Q_RES(CHIPS)':
 'A': CDS_PINID='A';
NODE_NAME     PQ13 S
 '@T6G_MB_LIB.T6G(SCH_1):PAGE168_I19@PURE_QUANTA.MOSFET_PCH_GDS_ESD_PROTECTED(CHIPS)':
 'S': CDS_PINID='S';
NODE_NAME     R8298 1
 '@T6G_MB_LIB.T6G(SCH_1):PAGE168_I28@PURE_QUANTA.Q_RES(CHIPS)':
 'A': CDS_PINID='A';
NODE_NAME     PR316 2
 '@T6G_MB_LIB.T6G(SCH_1):PAGE168_I133@PURE_QUANTA.Q_RES(CHIPS)':
 'B': CDS_PINID='B';
NODE_NAME     PQ10 S
 '@T6G_MB_LIB.T6G(SCH_1):PAGE175_I13@PURE_QUANTA.MOSFET_PCH_GDS_ESD_PROTECTED(CHIPS)':
 'S': CDS_PINID='S';
NODE_NAME     PR55 1
 '@T6G_MB_LIB.T6G(SCH_1):PAGE175_I17@PURE_QUANTA.Q_RES(CHIPS)':
 'A': CDS_PINID='A';
NODE_NAME     R8065 1
 '@T6G_MB_LIB.T6G(SCH_1):PAGE175_I54@PURE_QUANTA.Q_RES(CHIPS)':
 'A': CDS_PINID='A';
NODE_NAME     R8056 1
 '@T6G_MB_LIB.T6G(SCH_1):PAGE175_I90@PURE_QUANTA.Q_RES(CHIPS)':
 'A': CDS_PINID='A';
NODE_NAME     PR76 2
 '@T6G_MB_LIB.T6G(SCH_1):PAGE175_I126@PURE_QUANTA.Q_RES(CHIPS)':
 'B': CDS_PINID='B';
NODE_NAME     PR443 2
 '@T6G_MB_LIB.T6G(SCH_1):PAGE176_I27@PURE_QUANTA.Q_RES(CHIPS)':
 'B': CDS_PINID='B';
NODE_NAME     R8458 1
 '@T6G_MB_LIB.T6G(SCH_1):PAGE182_I9@PURE_QUANTA.Q_RES(CHIPS)':
 'A': CDS_PINID='A';
NODE_NAME     R117 1
 '@T6G_MB_LIB.T6G(SCH_1):PAGE182_I38@PURE_QUANTA.Q_RES(CHIPS)':
 'A': CDS_PINID='A';
NODE_NAME     PR130 2
 '@T6G_MB_LIB.T6G(SCH_1):PAGE182_I85@PURE_QUANTA.Q_RES(CHIPS)':
 'B': CDS_PINID='B';
NODE_NAME     PR413 2
 '@T6G_MB_LIB.T6G(SCH_1):PAGE183_I86@PURE_QUANTA.Q_RES(CHIPS)':
 'B': CDS_PINID='B';
NODE_NAME     PR477 1
 '@T6G_MB_LIB.T6G(SCH_1):PAGE184_I12@PURE_QUANTA.Q_RES(CHIPS)':
 'A': CDS_PINID='A';
NODE_NAME     R8465 1
 '@T6G_MB_LIB.T6G(SCH_1):PAGE184_I29@PURE_QUANTA.Q_RES(CHIPS)':
 'A': CDS_PINID='A';
NODE_NAME     PR152 1
 '@T6G_MB_LIB.T6G(SCH_1):PAGE185_I17@PURE_QUANTA.Q_RES(CHIPS)':
 'A': CDS_PINID='A';
NODE_NAME     PQ11 S
 '@T6G_MB_LIB.T6G(SCH_1):PAGE185_I18@PURE_QUANTA.MOSFET_PCH_GDS_ESD_PROTECTED(CHIPS)':
 'S': CDS_PINID='S';
NODE_NAME     R8165 1
 '@T6G_MB_LIB.T6G(SCH_1):PAGE185_I27@PURE_QUANTA.Q_RES(CHIPS)':
 'A': CDS_PINID='A';
NODE_NAME     R8167 1
 '@T6G_MB_LIB.T6G(SCH_1):PAGE185_I78@PURE_QUANTA.Q_RES(CHIPS)':
 'A': CDS_PINID='A';
NODE_NAME     PR183 2
 '@T6G_MB_LIB.T6G(SCH_1):PAGE185_I129@PURE_QUANTA.Q_RES(CHIPS)':
 'B': CDS_PINID='B';
NODE_NAME     PR336 2
 '@T6G_MB_LIB.T6G(SCH_1):PAGE186_I41@PURE_QUANTA.Q_RES(CHIPS)':
 'B': CDS_PINID='B';
NODE_NAME     PQ12 S
 '@T6G_MB_LIB.T6G(SCH_1):PAGE192_I13@PURE_QUANTA.MOSFET_PCH_GDS_ESD_PROTECTED(CHIPS)':
 'S': CDS_PINID='S';
NODE_NAME     PR232 1
 '@T6G_MB_LIB.T6G(SCH_1):PAGE192_I17@PURE_QUANTA.Q_RES(CHIPS)':
 'A': CDS_PINID='A';
NODE_NAME     R8242 1
 '@T6G_MB_LIB.T6G(SCH_1):PAGE192_I51@PURE_QUANTA.Q_RES(CHIPS)':
 'A': CDS_PINID='A';
NODE_NAME     R8233 1
 '@T6G_MB_LIB.T6G(SCH_1):PAGE192_I89@PURE_QUANTA.Q_RES(CHIPS)':
 'A': CDS_PINID='A';
NODE_NAME     PR253 2
 '@T6G_MB_LIB.T6G(SCH_1):PAGE192_I124@PURE_QUANTA.Q_RES(CHIPS)':
 'B': CDS_PINID='B';
NODE_NAME     PR341 2
 '@T6G_MB_LIB.T6G(SCH_1):PAGE193_I90@PURE_QUANTA.Q_RES(CHIPS)':
 'B': CDS_PINID='B';
NODE_NAME     R8146 1
 '@T6G_MB_LIB.T6G(SCH_1):PAGE199_I9@PURE_QUANTA.Q_RES(CHIPS)':
 'A': CDS_PINID='A';
NODE_NAME     R8380 1
 '@T6G_MB_LIB.T6G(SCH_1):PAGE199_I37@PURE_QUANTA.Q_RES(CHIPS)':
 'A': CDS_PINID='A';
NODE_NAME     PR393 2
 '@T6G_MB_LIB.T6G(SCH_1):PAGE199_I84@PURE_QUANTA.Q_RES(CHIPS)':
 'B': CDS_PINID='B';
NODE_NAME     PR394 2
 '@T6G_MB_LIB.T6G(SCH_1):PAGE200_I41@PURE_QUANTA.Q_RES(CHIPS)':
 'B': CDS_PINID='B';
NODE_NAME     U18 K10
 '@T6G_MB_LIB.T6G(SCH_1):PAGE81_I141@PURE_QUANTA.LCMXO3LF9400C5BG484C(CHIPS)':
 'VCC1': CDS_PINID='VCC1';
NODE_NAME     U18 K11
 '@T6G_MB_LIB.T6G(SCH_1):PAGE81_I141@PURE_QUANTA.LCMXO3LF9400C5BG484C(CHIPS)':
 'VCC2': CDS_PINID='VCC2';
NODE_NAME     U18 K12
 '@T6G_MB_LIB.T6G(SCH_1):PAGE81_I141@PURE_QUANTA.LCMXO3LF9400C5BG484C(CHIPS)':
 'VCC3': CDS_PINID='VCC3';
NODE_NAME     U18 K13
 '@T6G_MB_LIB.T6G(SCH_1):PAGE81_I141@PURE_QUANTA.LCMXO3LF9400C5BG484C(CHIPS)':
 'VCC4': CDS_PINID='VCC4';
NODE_NAME     U18 L11
 '@T6G_MB_LIB.T6G(SCH_1):PAGE81_I141@PURE_QUANTA.LCMXO3LF9400C5BG484C(CHIPS)':
 'VCC5': CDS_PINID='VCC5';
NODE_NAME     U18 L12
 '@T6G_MB_LIB.T6G(SCH_1):PAGE81_I141@PURE_QUANTA.LCMXO3LF9400C5BG484C(CHIPS)':
 'VCC6': CDS_PINID='VCC6';
NODE_NAME     U18 M11
 '@T6G_MB_LIB.T6G(SCH_1):PAGE81_I141@PURE_QUANTA.LCMXO3LF9400C5BG484C(CHIPS)':
 'VCC7': CDS_PINID='VCC7';
NODE_NAME     U18 M12
 '@T6G_MB_LIB.T6G(SCH_1):PAGE81_I141@PURE_QUANTA.LCMXO3LF9400C5BG484C(CHIPS)':
 'VCC8': CDS_PINID='VCC8';
NODE_NAME     U18 N10
 '@T6G_MB_LIB.T6G(SCH_1):PAGE81_I141@PURE_QUANTA.LCMXO3LF9400C5BG484C(CHIPS)':
 'VCC9': CDS_PINID='VCC9';
NODE_NAME     U18 N11
 '@T6G_MB_LIB.T6G(SCH_1):PAGE81_I141@PURE_QUANTA.LCMXO3LF9400C5BG484C(CHIPS)':
 'VCC10': CDS_PINID='VCC10';
NODE_NAME     U18 N12
 '@T6G_MB_LIB.T6G(SCH_1):PAGE81_I141@PURE_QUANTA.LCMXO3LF9400C5BG484C(CHIPS)':
 'VCC11': CDS_PINID='VCC11';
NODE_NAME     U18 N13
 '@T6G_MB_LIB.T6G(SCH_1):PAGE81_I141@PURE_QUANTA.LCMXO3LF9400C5BG484C(CHIPS)':
 'VCC12': CDS_PINID='VCC12';
NODE_NAME     U18 C7
 '@T6G_MB_LIB.T6G(SCH_1):PAGE81_I141@PURE_QUANTA.LCMXO3LF9400C5BG484C(CHIPS)':
 'VCCIO0_1': CDS_PINID='VCCIO0_1';
NODE_NAME     U18 C12
 '@T6G_MB_LIB.T6G(SCH_1):PAGE81_I141@PURE_QUANTA.LCMXO3LF9400C5BG484C(CHIPS)':
 'VCCIO0_2': CDS_PINID='VCCIO0_2';
NODE_NAME     U18 C16
 '@T6G_MB_LIB.T6G(SCH_1):PAGE81_I141@PURE_QUANTA.LCMXO3LF9400C5BG484C(CHIPS)':
 'VCCIO0_3': CDS_PINID='VCCIO0_3';
NODE_NAME     U18 G10
 '@T6G_MB_LIB.T6G(SCH_1):PAGE81_I141@PURE_QUANTA.LCMXO3LF9400C5BG484C(CHIPS)':
 'VCCIO0_4': CDS_PINID='VCCIO0_4';
NODE_NAME     U18 G13
 '@T6G_MB_LIB.T6G(SCH_1):PAGE81_I141@PURE_QUANTA.LCMXO3LF9400C5BG484C(CHIPS)':
 'VCCIO0_5': CDS_PINID='VCCIO0_5';
NODE_NAME     U18 H9
 '@T6G_MB_LIB.T6G(SCH_1):PAGE81_I141@PURE_QUANTA.LCMXO3LF9400C5BG484C(CHIPS)':
 'VCCIO0_6': CDS_PINID='VCCIO0_6';
NODE_NAME     U18 H11
 '@T6G_MB_LIB.T6G(SCH_1):PAGE81_I141@PURE_QUANTA.LCMXO3LF9400C5BG484C(CHIPS)':
 'VCCIO0_7': CDS_PINID='VCCIO0_7';
NODE_NAME     U18 H12
 '@T6G_MB_LIB.T6G(SCH_1):PAGE81_I141@PURE_QUANTA.LCMXO3LF9400C5BG484C(CHIPS)':
 'VCCIO0_8': CDS_PINID='VCCIO0_8';
NODE_NAME     U18 H14
 '@T6G_MB_LIB.T6G(SCH_1):PAGE81_I141@PURE_QUANTA.LCMXO3LF9400C5BG484C(CHIPS)':
 'VCCIO0_9': CDS_PINID='VCCIO0_9';
NODE_NAME     U18 R9
 '@T6G_MB_LIB.T6G(SCH_1):PAGE81_I141@PURE_QUANTA.LCMXO3LF9400C5BG484C(CHIPS)':
 'VCCIO2_1': CDS_PINID='VCCIO2_1';
NODE_NAME     U18 R10
 '@T6G_MB_LIB.T6G(SCH_1):PAGE81_I141@PURE_QUANTA.LCMXO3LF9400C5BG484C(CHIPS)':
 'VCCIO2_2': CDS_PINID='VCCIO2_2';
NODE_NAME     U18 R11
 '@T6G_MB_LIB.T6G(SCH_1):PAGE81_I141@PURE_QUANTA.LCMXO3LF9400C5BG484C(CHIPS)':
 'VCCIO2_3': CDS_PINID='VCCIO2_3';
NODE_NAME     U18 R12
 '@T6G_MB_LIB.T6G(SCH_1):PAGE81_I141@PURE_QUANTA.LCMXO3LF9400C5BG484C(CHIPS)':
 'VCCIO2_4': CDS_PINID='VCCIO2_4';
NODE_NAME     U18 R13
 '@T6G_MB_LIB.T6G(SCH_1):PAGE81_I141@PURE_QUANTA.LCMXO3LF9400C5BG484C(CHIPS)':
 'VCCIO2_5': CDS_PINID='VCCIO2_5';
NODE_NAME     U18 R14
 '@T6G_MB_LIB.T6G(SCH_1):PAGE81_I141@PURE_QUANTA.LCMXO3LF9400C5BG484C(CHIPS)':
 'VCCIO2_6': CDS_PINID='VCCIO2_6';
NODE_NAME     U18 W7
 '@T6G_MB_LIB.T6G(SCH_1):PAGE81_I141@PURE_QUANTA.LCMXO3LF9400C5BG484C(CHIPS)':
 'VCCIO2_7': CDS_PINID='VCCIO2_7';
NODE_NAME     U18 W11
 '@T6G_MB_LIB.T6G(SCH_1):PAGE81_I141@PURE_QUANTA.LCMXO3LF9400C5BG484C(CHIPS)':
 'VCCIO2_8': CDS_PINID='VCCIO2_8';
NODE_NAME     U18 W16
 '@T6G_MB_LIB.T6G(SCH_1):PAGE81_I141@PURE_QUANTA.LCMXO3LF9400C5BG484C(CHIPS)':
 'VCCIO2_9': CDS_PINID='VCCIO2_9';
NODE_NAME     U18 N8
 '@T6G_MB_LIB.T6G(SCH_1):PAGE81_I141@PURE_QUANTA.LCMXO3LF9400C5BG484C(CHIPS)':
 'VCCIO3_1': CDS_PINID='VCCIO3_1';
NODE_NAME     U18 P8
 '@T6G_MB_LIB.T6G(SCH_1):PAGE81_I141@PURE_QUANTA.LCMXO3LF9400C5BG484C(CHIPS)':
 'VCCIO3_2': CDS_PINID='VCCIO3_2';
NODE_NAME     U18 V3
 '@T6G_MB_LIB.T6G(SCH_1):PAGE81_I141@PURE_QUANTA.LCMXO3LF9400C5BG484C(CHIPS)':
 'VCCIO3_3': CDS_PINID='VCCIO3_3';
NODE_NAME     U18 L8
 '@T6G_MB_LIB.T6G(SCH_1):PAGE81_I141@PURE_QUANTA.LCMXO3LF9400C5BG484C(CHIPS)':
 'VCCIO4_1': CDS_PINID='VCCIO4_1';
NODE_NAME     U18 M8
 '@T6G_MB_LIB.T6G(SCH_1):PAGE81_I141@PURE_QUANTA.LCMXO3LF9400C5BG484C(CHIPS)':
 'VCCIO4_2': CDS_PINID='VCCIO4_2';
NODE_NAME     U18 M3
 '@T6G_MB_LIB.T6G(SCH_1):PAGE81_I141@PURE_QUANTA.LCMXO3LF9400C5BG484C(CHIPS)':
 'VCCIO4_3': CDS_PINID='VCCIO4_3';
NODE_NAME     R639 2
 '@T6G_MB_LIB.T6G(SCH_1):PAGE82_I33@PURE_QUANTA.Q_RES(CHIPS)':
 'B': CDS_PINID='B';
NODE_NAME     R1071 2
 '@T6G_MB_LIB.T6G(SCH_1):PAGE82_I38@PURE_QUANTA.Q_RES(CHIPS)':
 'B': CDS_PINID='B';
NODE_NAME     R757 2
 '@T6G_MB_LIB.T6G(SCH_1):PAGE82_I41@PURE_QUANTA.Q_RES(CHIPS)':
 'B': CDS_PINID='B';
NODE_NAME     C362 1
 '@T6G_MB_LIB.T6G(SCH_1):PAGE82_I102@PURE_QUANTA.Q_CAP(CHIPS)':
 'A': CDS_PINID='A';
NODE_NAME     C360 1
 '@T6G_MB_LIB.T6G(SCH_1):PAGE82_I103@PURE_QUANTA.Q_CAP(CHIPS)':
 'A': CDS_PINID='A';
NODE_NAME     C361 1
 '@T6G_MB_LIB.T6G(SCH_1):PAGE82_I104@PURE_QUANTA.Q_CAP(CHIPS)':
 'A': CDS_PINID='A';
NODE_NAME     C359 1
 '@T6G_MB_LIB.T6G(SCH_1):PAGE82_I135@PURE_QUANTA.Q_CAP(CHIPS)':
 'A': CDS_PINID='A';
NODE_NAME     R1266 1
 '@T6G_MB_LIB.T6G(SCH_1):PAGE84_I45@PURE_QUANTA.Q_RES(CHIPS)':
 'A': CDS_PINID='A';
NODE_NAME     R1194 1
 '@T6G_MB_LIB.T6G(SCH_1):PAGE84_I46@PURE_QUANTA.Q_RES(CHIPS)':
 'A': CDS_PINID='A';
NODE_NAME     R6024 1
 '@T6G_MB_LIB.T6G(SCH_1):PAGE349_I20@PURE_QUANTA.Q_RES(CHIPS)':
 'A': CDS_PINID='A';
NODE_NAME     R6023 1
 '@T6G_MB_LIB.T6G(SCH_1):PAGE349_I21@PURE_QUANTA.Q_RES(CHIPS)':
 'A': CDS_PINID='A';
NODE_NAME     R6021 1
 '@T6G_MB_LIB.T6G(SCH_1):PAGE349_I22@PURE_QUANTA.Q_RES(CHIPS)':
 'A': CDS_PINID='A';
NODE_NAME     R6022 1
 '@T6G_MB_LIB.T6G(SCH_1):PAGE349_I23@PURE_QUANTA.Q_RES(CHIPS)':
 'A': CDS_PINID='A';
NODE_NAME     R6020 1
 '@T6G_MB_LIB.T6G(SCH_1):PAGE349_I24@PURE_QUANTA.Q_RES(CHIPS)':
 'A': CDS_PINID='A';
NODE_NAME     R6019 1
 '@T6G_MB_LIB.T6G(SCH_1):PAGE349_I25@PURE_QUANTA.Q_RES(CHIPS)':
 'A': CDS_PINID='A';
NODE_NAME     R6018 1
 '@T6G_MB_LIB.T6G(SCH_1):PAGE349_I27@PURE_QUANTA.Q_RES(CHIPS)':
 'A': CDS_PINID='A';
NODE_NAME     R3242 2
 '@T6G_MB_LIB.T6G(SCH_1):PAGE349_I119@PURE_QUANTA.Q_RES(CHIPS)':
 'B': CDS_PINID='B';
NODE_NAME     R3241 2
 '@T6G_MB_LIB.T6G(SCH_1):PAGE349_I149@PURE_QUANTA.Q_RES(CHIPS)':
 'B': CDS_PINID='B';
NODE_NAME     R3836 1
 '@T6G_MB_LIB.T6G(SCH_1):PAGE350_I43@PURE_QUANTA.Q_RES(CHIPS)':
 'A': CDS_PINID='A';
NODE_NAME     R4013 1
 '@T6G_MB_LIB.T6G(SCH_1):PAGE350_I76@PURE_QUANTA.Q_RES(CHIPS)':
 'A': CDS_PINID='A';
NODE_NAME     R1138 1
 '@T6G_MB_LIB.T6G(SCH_1):PAGE337_I1@PURE_QUANTA.Q_RES(CHIPS)':
 'A': CDS_PINID='A';
NODE_NAME     C1274 1
 '@T6G_MB_LIB.T6G(SCH_1):PAGE337_I3@PURE_QUANTA.Q_CAP(CHIPS)':
 'A': CDS_PINID='A';
NODE_NAME     OSC1 4
 '@T6G_MB_LIB.T6G(SCH_1):PAGE337_I4@PURE_QUANTA.Q_OSC4P(CHIPS)':
 'VDD': CDS_PINID='VDD';
NODE_NAME     U8082 5
 '@T6G_MB_LIB.T6G(SCH_1):PAGE337_I8@PURE_QUANTA.74LVC1G126SE7(CHIPS)':
 'VCC': CDS_PINID='VCC';
NODE_NAME     U90 6
 '@T6G_MB_LIB.T6G(SCH_1):PAGE337_I16@PURE_QUANTA.PI6CV304LE(CHIPS)':
 'VDD': CDS_PINID='VDD';
NODE_NAME     C1275 1
 '@T6G_MB_LIB.T6G(SCH_1):PAGE337_I19@PURE_QUANTA.Q_CAP(CHIPS)':
 'A': CDS_PINID='A';
NODE_NAME     U157 5
 '@T6G_MB_LIB.T6G(SCH_1):PAGE337_I25@PURE_QUANTA.74LVC1G07GV(CHIPS)':
 'VCC': CDS_PINID='VCC';
NODE_NAME     C36 1
 '@T6G_MB_LIB.T6G(SCH_1):PAGE337_I33@PURE_QUANTA.Q_CAP(CHIPS)':
 'A': CDS_PINID='A';
NODE_NAME     R2488 1
 '@T6G_MB_LIB.T6G(SCH_1):PAGE337_I35@PURE_QUANTA.Q_RES(CHIPS)':
 'A': CDS_PINID='A';
NODE_NAME     U104 5
 '@T6G_MB_LIB.T6G(SCH_1):PAGE337_I38@PURE_QUANTA.74LVC1G07GV(CHIPS)':
 'VCC': CDS_PINID='VCC';
NODE_NAME     C1663 1
 '@T6G_MB_LIB.T6G(SCH_1):PAGE337_I47@PURE_QUANTA.Q_CAP(CHIPS)':
 'A': CDS_PINID='A';
NODE_NAME     U225 5
 '@T6G_MB_LIB.T6G(SCH_1):PAGE342_I9@PURE_QUANTA.74LVC1G126SE7(CHIPS)':
 'VCC': CDS_PINID='VCC';
NODE_NAME     U217 5
 '@T6G_MB_LIB.T6G(SCH_1):PAGE342_I14@PURE_QUANTA.74LVC1G126SE7(CHIPS)':
 'VCC': CDS_PINID='VCC';
NODE_NAME     C1822 1
 '@T6G_MB_LIB.T6G(SCH_1):PAGE342_I16@PURE_QUANTA.Q_CAP(CHIPS)':
 'A': CDS_PINID='A';
NODE_NAME     R3184 1
 '@T6G_MB_LIB.T6G(SCH_1):PAGE342_I18@PURE_QUANTA.Q_RES(CHIPS)':
 'A': CDS_PINID='A';
NODE_NAME     U218 5
 '@T6G_MB_LIB.T6G(SCH_1):PAGE342_I22@PURE_QUANTA.74LVC1G07GV(CHIPS)':
 'VCC': CDS_PINID='VCC';
NODE_NAME     U219 5
 '@T6G_MB_LIB.T6G(SCH_1):PAGE342_I32@PURE_QUANTA.74LVC1G07GV(CHIPS)':
 'VCC': CDS_PINID='VCC';
NODE_NAME     R3190 1
 '@T6G_MB_LIB.T6G(SCH_1):PAGE342_I34@PURE_QUANTA.Q_RES(CHIPS)':
 'A': CDS_PINID='A';
NODE_NAME     R3134 1
 '@T6G_MB_LIB.T6G(SCH_1):PAGE343_I4@PURE_QUANTA.Q_RES(CHIPS)':
 'A': CDS_PINID='A';
NODE_NAME     U59 5
 '@T6G_MB_LIB.T6G(SCH_1):PAGE343_I22@PURE_QUANTA.74LVC2G07DW7(CHIPS)':
 'VCC': CDS_PINID='VCC';
NODE_NAME     C1810 1
 '@T6G_MB_LIB.T6G(SCH_1):PAGE343_I23@PURE_QUANTA.Q_CAP(CHIPS)':
 'A': CDS_PINID='A';
NODE_NAME     C1809 1
 '@T6G_MB_LIB.T6G(SCH_1):PAGE343_I29@PURE_QUANTA.Q_CAP(CHIPS)':
 'A': CDS_PINID='A';
NODE_NAME     PC2140 1
 '@T6G_MB_LIB.T6G(SCH_1):PAGE343_I55@PURE_QUANTA.Q_CAP(CHIPS)':
 'A': CDS_PINID='A';
NODE_NAME     R3816 1
 '@T6G_MB_LIB.T6G(SCH_1):PAGE343_I79@PURE_QUANTA.Q_RES(CHIPS)':
 'A': CDS_PINID='A';
NODE_NAME     PR3782 1
 '@T6G_MB_LIB.T6G(SCH_1):PAGE343_I91@PURE_QUANTA.Q_RES(CHIPS)':
 'A': CDS_PINID='A';
NODE_NAME     R994 1
 '@T6G_MB_LIB.T6G(SCH_1):PAGE132_I7@PURE_QUANTA.Q_RES(CHIPS)':
 'A': CDS_PINID='A';
NODE_NAME     R1009 1
 '@T6G_MB_LIB.T6G(SCH_1):PAGE132_I10@PURE_QUANTA.Q_RES(CHIPS)':
 'A': CDS_PINID='A';
NODE_NAME     R6070 1
 '@T6G_MB_LIB.T6G(SCH_1):PAGE349_I161@PURE_QUANTA.Q_RES(CHIPS)':
 'A': CDS_PINID='A';
NODE_NAME     R2907 1
 '@T6G_MB_LIB.T6G(SCH_1):PAGE369_I28@PURE_QUANTA.Q_RES(CHIPS)':
 'A': CDS_PINID='A';
NODE_NAME     R3667 1
 '@T6G_MB_LIB.T6G(SCH_1):PAGE369_I66@PURE_QUANTA.Q_RES(CHIPS)':
 'A': CDS_PINID='A';
NODE_NAME     R3669 1
 '@T6G_MB_LIB.T6G(SCH_1):PAGE369_I68@PURE_QUANTA.Q_RES(CHIPS)':
 'A': CDS_PINID='A';
NODE_NAME     L16 1
 '@T6G_MB_LIB.T6G(SCH_1):PAGE369_I69@PURE_QUANTA.Q_INDUCTOR(CHIPS)':
 '1': CDS_PINID='\1\';
NODE_NAME     L15 2
 '@T6G_MB_LIB.T6G(SCH_1):PAGE369_I167@PURE_QUANTA.Q_INDUCTOR(CHIPS)':
 '2': CDS_PINID='\2\';
NODE_NAME     R2344 1
 '@T6G_MB_LIB.T6G(SCH_1):PAGE84_I67@PURE_QUANTA.Q_RES(CHIPS)':
 'A': CDS_PINID='A';
NODE_NAME     R2346 1
 '@T6G_MB_LIB.T6G(SCH_1):PAGE84_I70@PURE_QUANTA.Q_RES(CHIPS)':
 'A': CDS_PINID='A';
NODE_NAME     R3071 2
 '@T6G_MB_LIB.T6G(SCH_1):PAGE254_I21@PURE_QUANTA.Q_RES(CHIPS)':
 'B': CDS_PINID='B';
NODE_NAME     R6085 1
 '@T6G_MB_LIB.T6G(SCH_1):PAGE80_I298@PURE_QUANTA.Q_RES(CHIPS)':
 'A': CDS_PINID='A';
NODE_NAME     R3069 2
 '@T6G_MB_LIB.T6G(SCH_1):PAGE254_I32@PURE_QUANTA.Q_RES(CHIPS)':
 'B': CDS_PINID='B';
NODE_NAME     C10 1
 '@T6G_MB_LIB.T6G(SCH_1):PAGE337_I61@PURE_QUANTA.Q_CAP(CHIPS)':
 'A': CDS_PINID='A';
NODE_NAME     U75 5
 '@T6G_MB_LIB.T6G(SCH_1):PAGE337_I64@PURE_QUANTA.74LVC1G17GW(CHIPS)':
 'VCC': CDS_PINID='VCC';
NODE_NAME     C1821 1
 '@T6G_MB_LIB.T6G(SCH_1):PAGE342_I55@PURE_QUANTA.Q_CAP(CHIPS)':
 'A': CDS_PINID='A';
NODE_NAME     U207 5
 '@T6G_MB_LIB.T6G(SCH_1):PAGE342_I58@PURE_QUANTA.74LVC1G17GW(CHIPS)':
 'VCC': CDS_PINID='VCC';
NODE_NAME     R3074 2
 '@T6G_MB_LIB.T6G(SCH_1):PAGE254_I41@PURE_QUANTA.Q_RES(CHIPS)':
 'B': CDS_PINID='B';
NODE_NAME     R3088 2
 '@T6G_MB_LIB.T6G(SCH_1):PAGE374_I12@PURE_QUANTA.Q_RES(CHIPS)':
 'B': CDS_PINID='B';
NODE_NAME     R3089 2
 '@T6G_MB_LIB.T6G(SCH_1):PAGE374_I15@PURE_QUANTA.Q_RES(CHIPS)':
 'B': CDS_PINID='B';
NODE_NAME     R3087 2
 '@T6G_MB_LIB.T6G(SCH_1):PAGE374_I16@PURE_QUANTA.Q_RES(CHIPS)':
 'B': CDS_PINID='B';
NODE_NAME     R3086 2
 '@T6G_MB_LIB.T6G(SCH_1):PAGE374_I20@PURE_QUANTA.Q_RES(CHIPS)':
 'B': CDS_PINID='B';
NODE_NAME     R3091 2
 '@T6G_MB_LIB.T6G(SCH_1):PAGE374_I37@PURE_QUANTA.Q_RES(CHIPS)':
 'B': CDS_PINID='B';
NODE_NAME     R3090 2
 '@T6G_MB_LIB.T6G(SCH_1):PAGE374_I38@PURE_QUANTA.Q_RES(CHIPS)':
 'B': CDS_PINID='B';
NODE_NAME     R3092 2
 '@T6G_MB_LIB.T6G(SCH_1):PAGE374_I41@PURE_QUANTA.Q_RES(CHIPS)':
 'B': CDS_PINID='B';
NODE_NAME     R3095 2
 '@T6G_MB_LIB.T6G(SCH_1):PAGE375_I15@PURE_QUANTA.Q_RES(CHIPS)':
 'B': CDS_PINID='B';
NODE_NAME     R3096 2
 '@T6G_MB_LIB.T6G(SCH_1):PAGE375_I16@PURE_QUANTA.Q_RES(CHIPS)':
 'B': CDS_PINID='B';
NODE_NAME     R3094 2
 '@T6G_MB_LIB.T6G(SCH_1):PAGE375_I18@PURE_QUANTA.Q_RES(CHIPS)':
 'B': CDS_PINID='B';
NODE_NAME     R3093 2
 '@T6G_MB_LIB.T6G(SCH_1):PAGE375_I20@PURE_QUANTA.Q_RES(CHIPS)':
 'B': CDS_PINID='B';
NODE_NAME     R3097 2
 '@T6G_MB_LIB.T6G(SCH_1):PAGE375_I38@PURE_QUANTA.Q_RES(CHIPS)':
 'B': CDS_PINID='B';
NODE_NAME     R3099 2
 '@T6G_MB_LIB.T6G(SCH_1):PAGE375_I40@PURE_QUANTA.Q_RES(CHIPS)':
 'B': CDS_PINID='B';
NODE_NAME     R6138 1
 '@T6G_MB_LIB.T6G(SCH_1):PAGE83_I39@PURE_QUANTA.Q_RES(CHIPS)':
 'A': CDS_PINID='A';
NODE_NAME     R6139 1
 '@T6G_MB_LIB.T6G(SCH_1):PAGE83_I55@PURE_QUANTA.Q_RES(CHIPS)':
 'A': CDS_PINID='A';
NODE_NAME     R6140 1
 '@T6G_MB_LIB.T6G(SCH_1):PAGE83_I56@PURE_QUANTA.Q_RES(CHIPS)':
 'A': CDS_PINID='A';
NODE_NAME     R9008 1
 '@T6G_MB_LIB.T6G(SCH_1):PAGE330_I17@PURE_QUANTA.Q_RES(CHIPS)':
 'A': CDS_PINID='A';
NODE_NAME     U6000 15
 '@T6G_MB_LIB.T6G(SCH_1):PAGE111_I1@PURE_QUANTA.DS125BR111RTWR(CHIPS)':
 'VIN': CDS_PINID='VIN';
NODE_NAME     C6009 1
 '@T6G_MB_LIB.T6G(SCH_1):PAGE111_I3@PURE_QUANTA.Q_CAP(CHIPS)':
 'A': CDS_PINID='A';
NODE_NAME     C6010 1
 '@T6G_MB_LIB.T6G(SCH_1):PAGE111_I5@PURE_QUANTA.Q_CAP(CHIPS)':
 'A': CDS_PINID='A';
NODE_NAME     R6163 1
 '@T6G_MB_LIB.T6G(SCH_1):PAGE111_I39@PURE_QUANTA.Q_RES(CHIPS)':
 'A': CDS_PINID='A';
NODE_NAME     R6165 1
 '@T6G_MB_LIB.T6G(SCH_1):PAGE111_I41@PURE_QUANTA.Q_RES(CHIPS)':
 'A': CDS_PINID='A';
NODE_NAME     R6173 1
 '@T6G_MB_LIB.T6G(SCH_1):PAGE111_I44@PURE_QUANTA.Q_RES(CHIPS)':
 'A': CDS_PINID='A';
NODE_NAME     R6171 1
 '@T6G_MB_LIB.T6G(SCH_1):PAGE111_I48@PURE_QUANTA.Q_RES(CHIPS)':
 'A': CDS_PINID='A';
NODE_NAME     R6169 1
 '@T6G_MB_LIB.T6G(SCH_1):PAGE111_I53@PURE_QUANTA.Q_RES(CHIPS)':
 'A': CDS_PINID='A';
NODE_NAME     R6167 1
 '@T6G_MB_LIB.T6G(SCH_1):PAGE111_I57@PURE_QUANTA.Q_RES(CHIPS)':
 'A': CDS_PINID='A';
NODE_NAME     R6175 1
 '@T6G_MB_LIB.T6G(SCH_1):PAGE111_I63@PURE_QUANTA.Q_RES(CHIPS)':
 'A': CDS_PINID='A';
NODE_NAME     R6177 1
 '@T6G_MB_LIB.T6G(SCH_1):PAGE111_I77@PURE_QUANTA.Q_RES(CHIPS)':
 'A': CDS_PINID='A';
NODE_NAME     R6179 1
 '@T6G_MB_LIB.T6G(SCH_1):PAGE111_I78@PURE_QUANTA.Q_RES(CHIPS)':
 'A': CDS_PINID='A';
NODE_NAME     R3925 2
 '@T6G_MB_LIB.T6G(SCH_1):PAGE267_I34@PURE_QUANTA.Q_RES(CHIPS)':
 'B': CDS_PINID='B';
NODE_NAME     C1787 1
 '@T6G_MB_LIB.T6G(SCH_1):PAGE371_I6@PURE_QUANTA.Q_CAP(CHIPS)':
 'A': CDS_PINID='A';
NODE_NAME     U143 1
 '@T6G_MB_LIB.T6G(SCH_1):PAGE371_I8@PURE_QUANTA.NCT7718W(CHIPS)':
 'VDD': CDS_PINID='VDD';
NODE_NAME     R1449 1
 '@T6G_MB_LIB.T6G(SCH_1):PAGE264_I26@PURE_QUANTA.Q_RES(CHIPS)':
 'A': CDS_PINID='A';
NODE_NAME     R1450 1
 '@T6G_MB_LIB.T6G(SCH_1):PAGE264_I39@PURE_QUANTA.Q_RES(CHIPS)':
 'A': CDS_PINID='A';
NODE_NAME     R6181 1
 '@T6G_MB_LIB.T6G(SCH_1):PAGE148_I381@PURE_QUANTA.Q_RES(CHIPS)':
 'A': CDS_PINID='A';
NODE_NAME     R6182 1
 '@T6G_MB_LIB.T6G(SCH_1):PAGE148_I384@PURE_QUANTA.Q_RES(CHIPS)':
 'A': CDS_PINID='A';
NODE_NAME     U6 10
 '@T6G_MB_LIB.T6G(SCH_1):PAGE138_I67@PURE_QUANTA.PI3CSW12ZUAEX(CHIPS)':
 'VDD': CDS_PINID='VDD';
NODE_NAME     C25 1
 '@T6G_MB_LIB.T6G(SCH_1):PAGE138_I69@PURE_QUANTA.Q_CAP(CHIPS)':
 'A': CDS_PINID='A';
NODE_NAME     R6186 2
 '@T6G_MB_LIB.T6G(SCH_1):PAGE82_I146@PURE_QUANTA.Q_RES(CHIPS)':
 'B': CDS_PINID='B';
NODE_NAME     R6188 2
 '@T6G_MB_LIB.T6G(SCH_1):PAGE82_I152@PURE_QUANTA.Q_RES(CHIPS)':
 'B': CDS_PINID='B';
NODE_NAME     PJ38 12
 '@T6G_MB_LIB.T6G(SCH_1):PAGE371_I42@PURE_QUANTA.SCONN21_9193031121LF(CHIPS)':
 '12': CDS_PINID='\12\';
NODE_NAME     U96 8
 '@T6G_MB_LIB.T6G(SCH_1):PAGE137_I51@PURE_QUANTA.PCA9617ADP(CHIPS)':
 'VCCB': CDS_PINID='VCCB';
NODE_NAME     U6001 56
 '@T6G_MB_LIB.T6G(SCH_1):PAGE154_I1@PURE_QUANTA.CYUSB330468LTXI(CHIPS)':
 'AVDD33_2': CDS_PINID='AVDD33_2';
NODE_NAME     U6001 61
 '@T6G_MB_LIB.T6G(SCH_1):PAGE154_I1@PURE_QUANTA.CYUSB330468LTXI(CHIPS)':
 'AVDD33_3': CDS_PINID='AVDD33_3';
NODE_NAME     U6001 66
 '@T6G_MB_LIB.T6G(SCH_1):PAGE154_I1@PURE_QUANTA.CYUSB330468LTXI(CHIPS)':
 'AVDD33_4': CDS_PINID='AVDD33_4';
NODE_NAME     U6001 28
 '@T6G_MB_LIB.T6G(SCH_1):PAGE154_I1@PURE_QUANTA.CYUSB330468LTXI(CHIPS)':
 'VDD_IO': CDS_PINID='VDD_IO';
NODE_NAME     R6204 1
 '@T6G_MB_LIB.T6G(SCH_1):PAGE153_I41@PURE_QUANTA.Q_RES(CHIPS)':
 'A': CDS_PINID='A';
NODE_NAME     R6205 1
 '@T6G_MB_LIB.T6G(SCH_1):PAGE153_I43@PURE_QUANTA.Q_RES(CHIPS)':
 'A': CDS_PINID='A';
NODE_NAME     R6206 1
 '@T6G_MB_LIB.T6G(SCH_1):PAGE153_I44@PURE_QUANTA.Q_RES(CHIPS)':
 'A': CDS_PINID='A';
NODE_NAME     R6207 1
 '@T6G_MB_LIB.T6G(SCH_1):PAGE153_I45@PURE_QUANTA.Q_RES(CHIPS)':
 'A': CDS_PINID='A';
NODE_NAME     L6000 1
 '@T6G_MB_LIB.T6G(SCH_1):PAGE154_I3@PURE_QUANTA.Q_INDUCTOR(CHIPS)':
 '1': CDS_PINID='\1\';
NODE_NAME     C6040 1
 '@T6G_MB_LIB.T6G(SCH_1):PAGE154_I5@PURE_QUANTA.Q_CAP(CHIPS)':
 'A': CDS_PINID='A';
NODE_NAME     C6041 1
 '@T6G_MB_LIB.T6G(SCH_1):PAGE154_I7@PURE_QUANTA.Q_CAP(CHIPS)':
 'A': CDS_PINID='A';
NODE_NAME     C6046 1
 '@T6G_MB_LIB.T6G(SCH_1):PAGE154_I14@PURE_QUANTA.Q_CAP(CHIPS)':
 'A': CDS_PINID='A';
NODE_NAME     C6047 1
 '@T6G_MB_LIB.T6G(SCH_1):PAGE154_I15@PURE_QUANTA.Q_CAP(CHIPS)':
 'A': CDS_PINID='A';
NODE_NAME     C6048 1
 '@T6G_MB_LIB.T6G(SCH_1):PAGE154_I17@PURE_QUANTA.Q_CAP(CHIPS)':
 'A': CDS_PINID='A';
NODE_NAME     C6049 1
 '@T6G_MB_LIB.T6G(SCH_1):PAGE154_I19@PURE_QUANTA.Q_CAP(CHIPS)':
 'A': CDS_PINID='A';
NODE_NAME     C6050 1
 '@T6G_MB_LIB.T6G(SCH_1):PAGE154_I20@PURE_QUANTA.Q_CAP(CHIPS)':
 'A': CDS_PINID='A';
NODE_NAME     C6051 1
 '@T6G_MB_LIB.T6G(SCH_1):PAGE154_I21@PURE_QUANTA.Q_CAP(CHIPS)':
 'A': CDS_PINID='A';
NODE_NAME     C6053 1
 '@T6G_MB_LIB.T6G(SCH_1):PAGE154_I22@PURE_QUANTA.Q_CAP(CHIPS)':
 'A': CDS_PINID='A';
NODE_NAME     C6052 1
 '@T6G_MB_LIB.T6G(SCH_1):PAGE154_I23@PURE_QUANTA.Q_CAP(CHIPS)':
 'A': CDS_PINID='A';
NODE_NAME     U6003 8
 '@T6G_MB_LIB.T6G(SCH_1):PAGE153_I64@PURE_QUANTA.M24128BWMN6TP(CHIPS)':
 'VCC': CDS_PINID='VCC';
NODE_NAME     R6222 1
 '@T6G_MB_LIB.T6G(SCH_1):PAGE153_I65@PURE_QUANTA.Q_RES(CHIPS)':
 'A': CDS_PINID='A';
NODE_NAME     R6218 1
 '@T6G_MB_LIB.T6G(SCH_1):PAGE153_I69@PURE_QUANTA.Q_RES(CHIPS)':
 'A': CDS_PINID='A';
NODE_NAME     R6220 1
 '@T6G_MB_LIB.T6G(SCH_1):PAGE153_I70@PURE_QUANTA.Q_RES(CHIPS)':
 'A': CDS_PINID='A';
NODE_NAME     C6083 1
 '@T6G_MB_LIB.T6G(SCH_1):PAGE153_I75@PURE_QUANTA.Q_CAP(CHIPS)':
 'A': CDS_PINID='A';
NODE_NAME     R6226 1
 '@T6G_MB_LIB.T6G(SCH_1):PAGE153_I85@PURE_QUANTA.Q_RES(CHIPS)':
 'A': CDS_PINID='A';
NODE_NAME     R6227 1
 '@T6G_MB_LIB.T6G(SCH_1):PAGE153_I86@PURE_QUANTA.Q_RES(CHIPS)':
 'A': CDS_PINID='A';
NODE_NAME     R6230 1
 '@T6G_MB_LIB.T6G(SCH_1):PAGE371_I45@PURE_QUANTA.Q_RES(CHIPS)':
 'A': CDS_PINID='A';
NODE_NAME     R6231 1
 '@T6G_MB_LIB.T6G(SCH_1):PAGE371_I46@PURE_QUANTA.Q_RES(CHIPS)':
 'A': CDS_PINID='A';
NODE_NAME     R6236 1
 '@T6G_MB_LIB.T6G(SCH_1):PAGE371_I63@PURE_QUANTA.Q_RES(CHIPS)':
 'A': CDS_PINID='A';
NODE_NAME     R6239 1
 '@T6G_MB_LIB.T6G(SCH_1):PAGE371_I70@PURE_QUANTA.Q_RES(CHIPS)':
 'A': CDS_PINID='A';
NODE_NAME     R6242 1
 '@T6G_MB_LIB.T6G(SCH_1):PAGE315_I2@PURE_QUANTA.Q_RES(CHIPS)':
 'A': CDS_PINID='A';
NODE_NAME     R6243 1
 '@T6G_MB_LIB.T6G(SCH_1):PAGE315_I32@PURE_QUANTA.Q_RES(CHIPS)':
 'A': CDS_PINID='A';
NODE_NAME     R6244 1
 '@T6G_MB_LIB.T6G(SCH_1):PAGE380_I19@PURE_QUANTA.Q_RES(CHIPS)':
 'A': CDS_PINID='A';
NODE_NAME     R6245 1
 '@T6G_MB_LIB.T6G(SCH_1):PAGE380_I38@PURE_QUANTA.Q_RES(CHIPS)':
 'A': CDS_PINID='A';
NODE_NAME     R6246 2
 '@T6G_MB_LIB.T6G(SCH_1):PAGE254_I45@PURE_QUANTA.Q_RES(CHIPS)':
 'B': CDS_PINID='B';
NODE_NAME     L6003 1
 '@T6G_MB_LIB.T6G(SCH_1):PAGE157_I17@PURE_QUANTA.Q_INDUCTOR(CHIPS)':
 '1': CDS_PINID='\1\';
NODE_NAME     C6087 1
 '@T6G_MB_LIB.T6G(SCH_1):PAGE271_I22@PURE_QUANTA.Q_CAP(CHIPS)':
 'A': CDS_PINID='A';
NODE_NAME     R6247 1
 '@T6G_MB_LIB.T6G(SCH_1):PAGE271_I25@PURE_QUANTA.Q_RES(CHIPS)':
 'A': CDS_PINID='A';
NODE_NAME     U6005 9
 '@T6G_MB_LIB.T6G(SCH_1):PAGE271_I28@PURE_QUANTA.ISL28022FRZT(CHIPS)':
 'VCC': CDS_PINID='VCC';
NODE_NAME     R6211 1
 '@T6G_MB_LIB.T6G(SCH_1):PAGE252_I89@PURE_QUANTA.Q_RES(CHIPS)':
 'A': CDS_PINID='A';
NODE_NAME     R6212 1
 '@T6G_MB_LIB.T6G(SCH_1):PAGE252_I90@PURE_QUANTA.Q_RES(CHIPS)':
 'A': CDS_PINID='A';
NODE_NAME     R6283 1
 '@T6G_MB_LIB.T6G(SCH_1):PAGE157_I63@PURE_QUANTA.Q_RES(CHIPS)':
 'A': CDS_PINID='A';
NODE_NAME     R6292 1
 '@T6G_MB_LIB.T6G(SCH_1):PAGE157_I77@PURE_QUANTA.Q_RES(CHIPS)':
 'A': CDS_PINID='A';
NODE_NAME     R6294 1
 '@T6G_MB_LIB.T6G(SCH_1):PAGE157_I81@PURE_QUANTA.Q_RES(CHIPS)':
 'A': CDS_PINID='A';
NODE_NAME     R6327 1
 '@T6G_MB_LIB.T6G(SCH_1):PAGE155_I91@PURE_QUANTA.Q_RES(CHIPS)':
 'A': CDS_PINID='A';
NODE_NAME     R52 1
 '@T6G_MB_LIB.T6G(SCH_1):PAGE361_I103@PURE_QUANTA.Q_RES(CHIPS)':
 'A': CDS_PINID='A';
NODE_NAME     C1 1
 '@T6G_MB_LIB.T6G(SCH_1):PAGE361_I110@PURE_QUANTA.Q_CAP(CHIPS)':
 'A': CDS_PINID='A';
NODE_NAME     R24 1
 '@T6G_MB_LIB.T6G(SCH_1):PAGE361_I113@PURE_QUANTA.Q_RES(CHIPS)':
 'A': CDS_PINID='A';
NODE_NAME     R4 1
 '@T6G_MB_LIB.T6G(SCH_1):PAGE361_I114@PURE_QUANTA.Q_RES(CHIPS)':
 'A': CDS_PINID='A';
NODE_NAME     U1 8
 '@T6G_MB_LIB.T6G(SCH_1):PAGE361_I97@PURE_QUANTA.M24128BWMN6TP(CHIPS)':
 'VCC': CDS_PINID='VCC';
NODE_NAME     R60 1
 '@T6G_MB_LIB.T6G(SCH_1):PAGE361_I101@PURE_QUANTA.Q_RES(CHIPS)':
 'A': CDS_PINID='A';
NODE_NAME     R68 1
 '@T6G_MB_LIB.T6G(SCH_1):PAGE361_I120@PURE_QUANTA.Q_RES(CHIPS)':
 'A': CDS_PINID='A';
NODE_NAME     R134 2
 '@T6G_MB_LIB.T6G(SCH_1):PAGE82_I156@PURE_QUANTA.Q_RES(CHIPS)':
 'B': CDS_PINID='B';
NODE_NAME     R135 2
 '@T6G_MB_LIB.T6G(SCH_1):PAGE82_I157@PURE_QUANTA.Q_RES(CHIPS)':
 'B': CDS_PINID='B';
NODE_NAME     C11 1
 '@T6G_MB_LIB.T6G(SCH_1):PAGE138_I89@PURE_QUANTA.Q_CAP(CHIPS)':
 'A': CDS_PINID='A';
NODE_NAME     C2 1
 '@T6G_MB_LIB.T6G(SCH_1):PAGE137_I59@PURE_QUANTA.Q_CAP(CHIPS)':
 'A': CDS_PINID='A';
NODE_NAME     R201 1
 '@T6G_MB_LIB.T6G(SCH_1):PAGE137_I62@PURE_QUANTA.Q_RES(CHIPS)':
 'A': CDS_PINID='A';
NODE_NAME     R6213 1
 '@T6G_MB_LIB.T6G(SCH_1):PAGE153_I87@PURE_QUANTA.Q_RES(CHIPS)':
 'A': CDS_PINID='A';
NODE_NAME     R6215 1
 '@T6G_MB_LIB.T6G(SCH_1):PAGE153_I89@PURE_QUANTA.Q_RES(CHIPS)':
 'A': CDS_PINID='A';
NODE_NAME     R354 1
 '@T6G_MB_LIB.T6G(SCH_1):PAGE371_I76@PURE_QUANTA.Q_RES(CHIPS)':
 'A': CDS_PINID='A';
NODE_NAME     R355 1
 '@T6G_MB_LIB.T6G(SCH_1):PAGE371_I79@PURE_QUANTA.Q_RES(CHIPS)':
 'A': CDS_PINID='A';
NODE_NAME     R64 2
 '@T6G_MB_LIB.T6G(SCH_1):PAGE82_I166@PURE_QUANTA.Q_RES(CHIPS)':
 'B': CDS_PINID='B';
NODE_NAME     R2230 1
 '@T6G_MB_LIB.T6G(SCH_1):PAGE372_I43@PURE_QUANTA.Q_RES(CHIPS)':
 'A': CDS_PINID='A';
NODE_NAME     R2233 1
 '@T6G_MB_LIB.T6G(SCH_1):PAGE372_I45@PURE_QUANTA.Q_RES(CHIPS)':
 'A': CDS_PINID='A';
NODE_NAME     R4620 1
 '@T6G_MB_LIB.T6G(SCH_1):PAGE372_I46@PURE_QUANTA.Q_RES(CHIPS)':
 'A': CDS_PINID='A';
NODE_NAME     R6136 1
 '@T6G_MB_LIB.T6G(SCH_1):PAGE83_I117@PURE_QUANTA.Q_RES(CHIPS)':
 'A': CDS_PINID='A';
NODE_NAME     R6137 1
 '@T6G_MB_LIB.T6G(SCH_1):PAGE83_I121@PURE_QUANTA.Q_RES(CHIPS)':
 'A': CDS_PINID='A';
NODE_NAME     R6273 1
 '@T6G_MB_LIB.T6G(SCH_1):PAGE155_I104@PURE_QUANTA.Q_RES(CHIPS)':
 'A': CDS_PINID='A';
NODE_NAME     R6315 1
 '@T6G_MB_LIB.T6G(SCH_1):PAGE155_I140@PURE_QUANTA.Q_RES(CHIPS)':
 'A': CDS_PINID='A';
NODE_NAME     R6277 1
 '@T6G_MB_LIB.T6G(SCH_1):PAGE157_I130@PURE_QUANTA.Q_RES(CHIPS)':
 'A': CDS_PINID='A';
NODE_NAME     R6282 1
 '@T6G_MB_LIB.T6G(SCH_1):PAGE157_I138@PURE_QUANTA.Q_RES(CHIPS)':
 'A': CDS_PINID='A';
NODE_NAME     R6258 1
 '@T6G_MB_LIB.T6G(SCH_1):PAGE155_I164@PURE_QUANTA.Q_RES(CHIPS)':
 'A': CDS_PINID='A';
NODE_NAME     R6303 1
 '@T6G_MB_LIB.T6G(SCH_1):PAGE155_I169@PURE_QUANTA.Q_RES(CHIPS)':
 'A': CDS_PINID='A';
NODE_NAME     R6301 1
 '@T6G_MB_LIB.T6G(SCH_1):PAGE155_I179@PURE_QUANTA.Q_RES(CHIPS)':
 'A': CDS_PINID='A';
NODE_NAME     R6297 1
 '@T6G_MB_LIB.T6G(SCH_1):PAGE155_I185@PURE_QUANTA.Q_RES(CHIPS)':
 'A': CDS_PINID='A';
NODE_NAME     R6298 1
 '@T6G_MB_LIB.T6G(SCH_1):PAGE155_I187@PURE_QUANTA.Q_RES(CHIPS)':
 'A': CDS_PINID='A';
NODE_NAME     R6308 1
 '@T6G_MB_LIB.T6G(SCH_1):PAGE157_I153@PURE_QUANTA.Q_RES(CHIPS)':
 'A': CDS_PINID='A';
NODE_NAME     R6306 1
 '@T6G_MB_LIB.T6G(SCH_1):PAGE157_I155@PURE_QUANTA.Q_RES(CHIPS)':
 'A': CDS_PINID='A';
NODE_NAME     R6289 1
 '@T6G_MB_LIB.T6G(SCH_1):PAGE155_I195@PURE_QUANTA.Q_RES(CHIPS)':
 'A': CDS_PINID='A';
NODE_NAME     R6287 1
 '@T6G_MB_LIB.T6G(SCH_1):PAGE155_I197@PURE_QUANTA.Q_RES(CHIPS)':
 'A': CDS_PINID='A';
NODE_NAME     R6312 1
 '@T6G_MB_LIB.T6G(SCH_1):PAGE155_I205@PURE_QUANTA.Q_RES(CHIPS)':
 'A': CDS_PINID='A';
NODE_NAME     R496 1
 '@T6G_MB_LIB.T6G(SCH_1):PAGE273_I93@PURE_QUANTA.Q_RES(CHIPS)':
 'A': CDS_PINID='A';
NODE_NAME     R492 1
 '@T6G_MB_LIB.T6G(SCH_1):PAGE273_I99@PURE_QUANTA.Q_RES(CHIPS)':
 'A': CDS_PINID='A';
NODE_NAME     R552 1
 '@T6G_MB_LIB.T6G(SCH_1):PAGE273_I104@PURE_QUANTA.Q_RES(CHIPS)':
 'A': CDS_PINID='A';
NODE_NAME     R1492 1
 '@T6G_MB_LIB.T6G(SCH_1):PAGE273_I120@PURE_QUANTA.Q_RES(CHIPS)':
 'A': CDS_PINID='A';
NODE_NAME     U320 5
 '@T6G_MB_LIB.T6G(SCH_1):PAGE337_I82@PURE_QUANTA.74LVC1G66GV(CHIPS)':
 'VCC': CDS_PINID='VCC';
NODE_NAME     U321 5
 '@T6G_MB_LIB.T6G(SCH_1):PAGE342_I76@PURE_QUANTA.74LVC1G66GV(CHIPS)':
 'VCC': CDS_PINID='VCC';
NODE_NAME     R9009 1
 '@T6G_MB_LIB.T6G(SCH_1):PAGE330_I23@PURE_QUANTA.Q_RES(CHIPS)':
 'A': CDS_PINID='A';
NODE_NAME     R9004 1
 '@T6G_MB_LIB.T6G(SCH_1):PAGE330_I26@PURE_QUANTA.Q_RES(CHIPS)':
 'A': CDS_PINID='A';
NODE_NAME     R8017 1
 '@T6G_MB_LIB.T6G(SCH_1):PAGE144_I85@PURE_QUANTA.Q_RES(CHIPS)':
 'A': CDS_PINID='A';
NODE_NAME     R8019 1
 '@T6G_MB_LIB.T6G(SCH_1):PAGE144_I89@PURE_QUANTA.Q_RES(CHIPS)':
 'A': CDS_PINID='A';
NODE_NAME     R8029 2
 '@T6G_MB_LIB.T6G(SCH_1):PAGE375_I55@PURE_QUANTA.Q_RES(CHIPS)':
 'B': CDS_PINID='B';
NODE_NAME     R8028 1
 '@T6G_MB_LIB.T6G(SCH_1):PAGE375_I62@PURE_QUANTA.Q_RES(CHIPS)':
 'A': CDS_PINID='A';
NODE_NAME     R6071 1
 '@T6G_MB_LIB.T6G(SCH_1):PAGE348_I214@PURE_QUANTA.Q_RES(CHIPS)':
 'A': CDS_PINID='A';
NODE_NAME     R2920 1
 '@T6G_MB_LIB.T6G(SCH_1):PAGE333_I177@PURE_QUANTA.Q_RES(CHIPS)':
 'A': CDS_PINID='A';
NODE_NAME     R3030 1
 '@T6G_MB_LIB.T6G(SCH_1):PAGE333_I178@PURE_QUANTA.Q_RES(CHIPS)':
 'A': CDS_PINID='A';
NODE_NAME     R3035 1
 '@T6G_MB_LIB.T6G(SCH_1):PAGE333_I179@PURE_QUANTA.Q_RES(CHIPS)':
 'A': CDS_PINID='A';
NODE_NAME     R2933 1
 '@T6G_MB_LIB.T6G(SCH_1):PAGE333_I180@PURE_QUANTA.Q_RES(CHIPS)':
 'A': CDS_PINID='A';
NODE_NAME     R4546 1
 '@T6G_MB_LIB.T6G(SCH_1):PAGE331_I110@PURE_QUANTA.Q_RES(CHIPS)':
 'A': CDS_PINID='A';
NODE_NAME     R8037 1
 '@T6G_MB_LIB.T6G(SCH_1):PAGE85_I540@PURE_QUANTA.Q_RES(CHIPS)':
 'A': CDS_PINID='A';
NODE_NAME     R8038 1
 '@T6G_MB_LIB.T6G(SCH_1):PAGE91_I243@PURE_QUANTA.Q_RES(CHIPS)':
 'A': CDS_PINID='A';
NODE_NAME     R8039 1
 '@T6G_MB_LIB.T6G(SCH_1):PAGE97_I245@PURE_QUANTA.Q_RES(CHIPS)':
 'A': CDS_PINID='A';
NODE_NAME     R8040 1
 '@T6G_MB_LIB.T6G(SCH_1):PAGE103_I245@PURE_QUANTA.Q_RES(CHIPS)':
 'A': CDS_PINID='A';
NODE_NAME     R8082 1
 '@T6G_MB_LIB.T6G(SCH_1):PAGE85_I547@PURE_QUANTA.Q_RES(CHIPS)':
 'A': CDS_PINID='A';
NODE_NAME     D8003 2
 '@T6G_MB_LIB.T6G(SCH_1):PAGE85_I549@PURE_QUANTA.SCHOTTKY_12(CHIPS)':
 'C': CDS_PINID='C';
NODE_NAME     R8085 1
 '@T6G_MB_LIB.T6G(SCH_1):PAGE91_I249@PURE_QUANTA.Q_RES(CHIPS)':
 'A': CDS_PINID='A';
NODE_NAME     D8004 2
 '@T6G_MB_LIB.T6G(SCH_1):PAGE91_I251@PURE_QUANTA.SCHOTTKY_12(CHIPS)':
 'C': CDS_PINID='C';
NODE_NAME     R8088 1
 '@T6G_MB_LIB.T6G(SCH_1):PAGE97_I251@PURE_QUANTA.Q_RES(CHIPS)':
 'A': CDS_PINID='A';
NODE_NAME     D8005 2
 '@T6G_MB_LIB.T6G(SCH_1):PAGE97_I253@PURE_QUANTA.SCHOTTKY_12(CHIPS)':
 'C': CDS_PINID='C';
NODE_NAME     R8091 1
 '@T6G_MB_LIB.T6G(SCH_1):PAGE103_I251@PURE_QUANTA.Q_RES(CHIPS)':
 'A': CDS_PINID='A';
NODE_NAME     D8006 2
 '@T6G_MB_LIB.T6G(SCH_1):PAGE103_I253@PURE_QUANTA.SCHOTTKY_12(CHIPS)':
 'C': CDS_PINID='C';
NODE_NAME     U8004 5
 '@T6G_MB_LIB.T6G(SCH_1):PAGE365_I16@PURE_QUANTA.74LVC2G07DW7(CHIPS)':
 'VCC': CDS_PINID='VCC';
NODE_NAME     C8013 1
 '@T6G_MB_LIB.T6G(SCH_1):PAGE365_I23@PURE_QUANTA.Q_CAP(CHIPS)':
 'A': CDS_PINID='A';
NODE_NAME     R8103 1
 '@T6G_MB_LIB.T6G(SCH_1):PAGE365_I27@PURE_QUANTA.Q_RES(CHIPS)':
 'A': CDS_PINID='A';
NODE_NAME     R8107 1
 '@T6G_MB_LIB.T6G(SCH_1):PAGE371_I81@PURE_QUANTA.Q_RES(CHIPS)':
 'A': CDS_PINID='A';
NODE_NAME     R8111 1
 '@T6G_MB_LIB.T6G(SCH_1):PAGE371_I98@PURE_QUANTA.Q_RES(CHIPS)':
 'A': CDS_PINID='A';
NODE_NAME     R8113 1
 '@T6G_MB_LIB.T6G(SCH_1):PAGE372_I52@PURE_QUANTA.Q_RES(CHIPS)':
 'A': CDS_PINID='A';
NODE_NAME     R8119 1
 '@T6G_MB_LIB.T6G(SCH_1):PAGE372_I69@PURE_QUANTA.Q_RES(CHIPS)':
 'A': CDS_PINID='A';
NODE_NAME     R8120 1
 '@T6G_MB_LIB.T6G(SCH_1):PAGE372_I72@PURE_QUANTA.Q_RES(CHIPS)':
 'A': CDS_PINID='A';
NODE_NAME     R4489 1
 '@T6G_MB_LIB.T6G(SCH_1):PAGE160_I3@PURE_QUANTA.Q_RES(CHIPS)':
 'A': CDS_PINID='A';
NODE_NAME     L20 1
 '@T6G_MB_LIB.T6G(SCH_1):PAGE160_I24@PURE_QUANTA.Q_INDUCTOR(CHIPS)':
 '1': CDS_PINID='\1\';
NODE_NAME     L19 1
 '@T6G_MB_LIB.T6G(SCH_1):PAGE160_I26@PURE_QUANTA.Q_INDUCTOR(CHIPS)':
 '1': CDS_PINID='\1\';
NODE_NAME     R4491 1
 '@T6G_MB_LIB.T6G(SCH_1):PAGE160_I31@PURE_QUANTA.Q_RES(CHIPS)':
 'A': CDS_PINID='A';
NODE_NAME     L1 1
 '@T6G_MB_LIB.T6G(SCH_1):PAGE379_I2@PURE_QUANTA.Q_INDUCTOR(CHIPS)':
 '1': CDS_PINID='\1\';
NODE_NAME     R580 1
 '@T6G_MB_LIB.T6G(SCH_1):PAGE379_I17@PURE_QUANTA.Q_RES(CHIPS)':
 'A': CDS_PINID='A';
NODE_NAME     L2 1
 '@T6G_MB_LIB.T6G(SCH_1):PAGE379_I32@PURE_QUANTA.Q_INDUCTOR(CHIPS)':
 '1': CDS_PINID='\1\';
NODE_NAME     R578 1
 '@T6G_MB_LIB.T6G(SCH_1):PAGE379_I65@PURE_QUANTA.Q_RES(CHIPS)':
 'A': CDS_PINID='A';
NODE_NAME     PR6501 1
 '@T6G_MB_LIB.T6G(SCH_1):PAGE469_I13@PURE_QUANTA.Q_RES(CHIPS)':
 'A': CDS_PINID='A';
NODE_NAME     R6505 1
 '@T6G_MB_LIB.T6G(SCH_1):PAGE469_I28@PURE_QUANTA.Q_RES(CHIPS)':
 'A': CDS_PINID='A';
NODE_NAME     PR6521 1
 '@T6G_MB_LIB.T6G(SCH_1):PAGE470_I13@PURE_QUANTA.Q_RES(CHIPS)':
 'A': CDS_PINID='A';
NODE_NAME     R644 1
 '@T6G_MB_LIB.T6G(SCH_1):PAGE470_I29@PURE_QUANTA.Q_RES(CHIPS)':
 'A': CDS_PINID='A';
NODE_NAME     R655 1
 '@T6G_MB_LIB.T6G(SCH_1):PAGE475_I127@PURE_QUANTA.Q_RES(CHIPS)':
 'A': CDS_PINID='A';
NODE_NAME     R652 1
 '@T6G_MB_LIB.T6G(SCH_1):PAGE475_I128@PURE_QUANTA.Q_RES(CHIPS)':
 'A': CDS_PINID='A';
NODE_NAME     PR6608 2
 '@T6G_MB_LIB.T6G(SCH_1):PAGE475_I131@PURE_QUANTA.Q_RES(CHIPS)':
 'B': CDS_PINID='B';
NODE_NAME     PR6615 1
 '@T6G_MB_LIB.T6G(SCH_1):PAGE475_I135@PURE_QUANTA.Q_RES(CHIPS)':
 'A': CDS_PINID='A';
NODE_NAME     PR6805 1
 '@T6G_MB_LIB.T6G(SCH_1):PAGE475_I166@PURE_QUANTA.Q_RES(CHIPS)':
 'A': CDS_PINID='A';
NODE_NAME     PR6803 1
 '@T6G_MB_LIB.T6G(SCH_1):PAGE475_I167@PURE_QUANTA.Q_RES(CHIPS)':
 'A': CDS_PINID='A';
NODE_NAME     PR6817 1
 '@T6G_MB_LIB.T6G(SCH_1):PAGE475_I169@PURE_QUANTA.Q_RES(CHIPS)':
 'A': CDS_PINID='A';
NODE_NAME     R649 1
 '@T6G_MB_LIB.T6G(SCH_1):PAGE475_I207@PURE_QUANTA.Q_RES(CHIPS)':
 'A': CDS_PINID='A';
NODE_NAME     PR6551 1
 '@T6G_MB_LIB.T6G(SCH_1):PAGE476_I185@PURE_QUANTA.Q_RES(CHIPS)':
 'A': CDS_PINID='A';
NODE_NAME     R665 1
 '@T6G_MB_LIB.T6G(SCH_1):PAGE477_I14@PURE_QUANTA.Q_RES(CHIPS)':
 'A': CDS_PINID='A';
NODE_NAME     R663 1
 '@T6G_MB_LIB.T6G(SCH_1):PAGE477_I15@PURE_QUANTA.Q_RES(CHIPS)':
 'A': CDS_PINID='A';
NODE_NAME     PR6818 1
 '@T6G_MB_LIB.T6G(SCH_1):PAGE477_I32@PURE_QUANTA.Q_RES(CHIPS)':
 'A': CDS_PINID='A';
NODE_NAME     PR6804 1
 '@T6G_MB_LIB.T6G(SCH_1):PAGE477_I36@PURE_QUANTA.Q_RES(CHIPS)':
 'A': CDS_PINID='A';
NODE_NAME     PR6806 1
 '@T6G_MB_LIB.T6G(SCH_1):PAGE477_I37@PURE_QUANTA.Q_RES(CHIPS)':
 'A': CDS_PINID='A';
NODE_NAME     PR6538 2
 '@T6G_MB_LIB.T6G(SCH_1):PAGE477_I83@PURE_QUANTA.Q_RES(CHIPS)':
 'B': CDS_PINID='B';
NODE_NAME     PR6812 1
 '@T6G_MB_LIB.T6G(SCH_1):PAGE477_I86@PURE_QUANTA.Q_RES(CHIPS)':
 'A': CDS_PINID='A';
NODE_NAME     R660 1
 '@T6G_MB_LIB.T6G(SCH_1):PAGE477_I89@PURE_QUANTA.Q_RES(CHIPS)':
 'A': CDS_PINID='A';
NODE_NAME     PR6620 1
 '@T6G_MB_LIB.T6G(SCH_1):PAGE478_I56@PURE_QUANTA.Q_RES(CHIPS)':
 'A': CDS_PINID='A';
NODE_NAME     R5101 1
 '@T6G_MB_LIB.T6G(SCH_1):PAGE156_I97@PURE_QUANTA.Q_RES(CHIPS)':
 'A': CDS_PINID='A';
NODE_NAME     R9000 1
 '@T6G_MB_LIB.T6G(SCH_1):PAGE363_I472@PURE_QUANTA.Q_RES(CHIPS)':
 'A': CDS_PINID='A';
NODE_NAME     R2923 1
 '@T6G_MB_LIB.T6G(SCH_1):PAGE246_I37@PURE_QUANTA.Q_RES(CHIPS)':
 'A': CDS_PINID='A';
NODE_NAME     C1713 1
 '@T6G_MB_LIB.T6G(SCH_1):PAGE246_I61@PURE_QUANTA.Q_CAP(CHIPS)':
 'A': CDS_PINID='A';
NODE_NAME     U181 24
 '@T6G_MB_LIB.T6G(SCH_1):PAGE246_I83@PURE_QUANTA.PCA9539RPW(CHIPS)':
 'VDD': CDS_PINID='VDD';
NODE_NAME     R4153 1
 '@T6G_MB_LIB.T6G(SCH_1):PAGE332_I4@PURE_QUANTA.Q_RES(CHIPS)':
 'A': CDS_PINID='A';
NODE_NAME     R4155 1
 '@T6G_MB_LIB.T6G(SCH_1):PAGE332_I8@PURE_QUANTA.Q_RES(CHIPS)':
 'A': CDS_PINID='A';
NODE_NAME     R4121 1
 '@T6G_MB_LIB.T6G(SCH_1):PAGE332_I14@PURE_QUANTA.Q_RES(CHIPS)':
 'A': CDS_PINID='A';
NODE_NAME     R4123 1
 '@T6G_MB_LIB.T6G(SCH_1):PAGE332_I18@PURE_QUANTA.Q_RES(CHIPS)':
 'A': CDS_PINID='A';
NODE_NAME     R4119 1
 '@T6G_MB_LIB.T6G(SCH_1):PAGE332_I23@PURE_QUANTA.Q_RES(CHIPS)':
 'A': CDS_PINID='A';
NODE_NAME     R4126 1
 '@T6G_MB_LIB.T6G(SCH_1):PAGE332_I27@PURE_QUANTA.Q_RES(CHIPS)':
 'A': CDS_PINID='A';
NODE_NAME     R4127 1
 '@T6G_MB_LIB.T6G(SCH_1):PAGE332_I35@PURE_QUANTA.Q_RES(CHIPS)':
 'A': CDS_PINID='A';
NODE_NAME     R4125 1
 '@T6G_MB_LIB.T6G(SCH_1):PAGE332_I39@PURE_QUANTA.Q_RES(CHIPS)':
 'A': CDS_PINID='A';
NODE_NAME     R4156 1
 '@T6G_MB_LIB.T6G(SCH_1):PAGE332_I48@PURE_QUANTA.Q_RES(CHIPS)':
 'A': CDS_PINID='A';
NODE_NAME     R4562 1
 '@T6G_MB_LIB.T6G(SCH_1):PAGE332_I55@PURE_QUANTA.Q_RES(CHIPS)':
 'A': CDS_PINID='A';
NODE_NAME     R4560 1
 '@T6G_MB_LIB.T6G(SCH_1):PAGE332_I62@PURE_QUANTA.Q_RES(CHIPS)':
 'A': CDS_PINID='A';
NODE_NAME     R4129 1
 '@T6G_MB_LIB.T6G(SCH_1):PAGE332_I66@PURE_QUANTA.Q_RES(CHIPS)':
 'A': CDS_PINID='A';
NODE_NAME     R4130 1
 '@T6G_MB_LIB.T6G(SCH_1):PAGE332_I70@PURE_QUANTA.Q_RES(CHIPS)':
 'A': CDS_PINID='A';
NODE_NAME     R4133 1
 '@T6G_MB_LIB.T6G(SCH_1):PAGE332_I82@PURE_QUANTA.Q_RES(CHIPS)':
 'A': CDS_PINID='A';
NODE_NAME     R4138 1
 '@T6G_MB_LIB.T6G(SCH_1):PAGE332_I88@PURE_QUANTA.Q_RES(CHIPS)':
 'A': CDS_PINID='A';
NODE_NAME     R4135 1
 '@T6G_MB_LIB.T6G(SCH_1):PAGE332_I93@PURE_QUANTA.Q_RES(CHIPS)':
 'A': CDS_PINID='A';
NODE_NAME     R4131 1
 '@T6G_MB_LIB.T6G(SCH_1):PAGE332_I97@PURE_QUANTA.Q_RES(CHIPS)':
 'A': CDS_PINID='A';
NODE_NAME     R4139 1
 '@T6G_MB_LIB.T6G(SCH_1):PAGE332_I99@PURE_QUANTA.Q_RES(CHIPS)':
 'A': CDS_PINID='A';
NODE_NAME     R4128 1
 '@T6G_MB_LIB.T6G(SCH_1):PAGE332_I104@PURE_QUANTA.Q_RES(CHIPS)':
 'A': CDS_PINID='A';
NODE_NAME     R4137 1
 '@T6G_MB_LIB.T6G(SCH_1):PAGE332_I107@PURE_QUANTA.Q_RES(CHIPS)':
 'A': CDS_PINID='A';
NODE_NAME     R4561 1
 '@T6G_MB_LIB.T6G(SCH_1):PAGE332_I110@PURE_QUANTA.Q_RES(CHIPS)':
 'A': CDS_PINID='A';
NODE_NAME     R4141 1
 '@T6G_MB_LIB.T6G(SCH_1):PAGE332_I114@PURE_QUANTA.Q_RES(CHIPS)':
 'A': CDS_PINID='A';
NODE_NAME     R4142 1
 '@T6G_MB_LIB.T6G(SCH_1):PAGE332_I122@PURE_QUANTA.Q_RES(CHIPS)':
 'A': CDS_PINID='A';
NODE_NAME     R4140 1
 '@T6G_MB_LIB.T6G(SCH_1):PAGE332_I131@PURE_QUANTA.Q_RES(CHIPS)':
 'A': CDS_PINID='A';
NODE_NAME     R4058 1
 '@T6G_MB_LIB.T6G(SCH_1):PAGE330_I13@PURE_QUANTA.Q_RES(CHIPS)':
 'A': CDS_PINID='A';
NODE_NAME     R9006 1
 '@T6G_MB_LIB.T6G(SCH_1):PAGE330_I15@PURE_QUANTA.Q_RES(CHIPS)':
 'A': CDS_PINID='A';
NODE_NAME     R9005 1
 '@T6G_MB_LIB.T6G(SCH_1):PAGE330_I32@PURE_QUANTA.Q_RES(CHIPS)':
 'A': CDS_PINID='A';
NODE_NAME     R9014 1
 '@T6G_MB_LIB.T6G(SCH_1):PAGE330_I51@PURE_QUANTA.Q_RES(CHIPS)':
 'A': CDS_PINID='A';
NODE_NAME     R8002 1
 '@T6G_MB_LIB.T6G(SCH_1):PAGE330_I55@PURE_QUANTA.Q_RES(CHIPS)':
 'A': CDS_PINID='A';
NODE_NAME     R8003 1
 '@T6G_MB_LIB.T6G(SCH_1):PAGE330_I57@PURE_QUANTA.Q_RES(CHIPS)':
 'A': CDS_PINID='A';
NODE_NAME     R9016 1
 '@T6G_MB_LIB.T6G(SCH_1):PAGE330_I61@PURE_QUANTA.Q_RES(CHIPS)':
 'A': CDS_PINID='A';
NODE_NAME     R9017 1
 '@T6G_MB_LIB.T6G(SCH_1):PAGE330_I72@PURE_QUANTA.Q_RES(CHIPS)':
 'A': CDS_PINID='A';
NODE_NAME     R9020 1
 '@T6G_MB_LIB.T6G(SCH_1):PAGE371_I108@PURE_QUANTA.Q_RES(CHIPS)':
 'A': CDS_PINID='A';
NODE_NAME     R643 1
 '@T6G_MB_LIB.T6G(SCH_1):PAGE475_I212@PURE_QUANTA.Q_RES(CHIPS)':
 'A': CDS_PINID='A';
NODE_NAME     R656 1
 '@T6G_MB_LIB.T6G(SCH_1):PAGE477_I92@PURE_QUANTA.Q_RES(CHIPS)':
 'A': CDS_PINID='A';
NODE_NAME     R4476 1
 '@T6G_MB_LIB.T6G(SCH_1):PAGE160_I73@PURE_QUANTA.Q_RES(CHIPS)':
 'A': CDS_PINID='A';
NODE_NAME     R560 1
 '@T6G_MB_LIB.T6G(SCH_1):PAGE379_I81@PURE_QUANTA.Q_RES(CHIPS)':
 'A': CDS_PINID='A';
NODE_NAME     R3773 1
 '@T6G_MB_LIB.T6G(SCH_1):PAGE297_I106@PURE_QUANTA.Q_RES(CHIPS)':
 'A': CDS_PINID='A';
NODE_NAME     R4173 1
 '@T6G_MB_LIB.T6G(SCH_1):PAGE256_I204@PURE_QUANTA.Q_RES(CHIPS)':
 'A': CDS_PINID='A';
NODE_NAME     R9026 1
 '@T6G_MB_LIB.T6G(SCH_1):PAGE84_I112@PURE_QUANTA.Q_RES(CHIPS)':
 'A': CDS_PINID='A';
NODE_NAME     R9027 1
 '@T6G_MB_LIB.T6G(SCH_1):PAGE84_I114@PURE_QUANTA.Q_RES(CHIPS)':
 'A': CDS_PINID='A';
NODE_NAME     R1304 2
 '@T6G_MB_LIB.T6G(SCH_1):PAGE82_I171@PURE_QUANTA.Q_RES(CHIPS)':
 'B': CDS_PINID='B';
NODE_NAME     R4521 1
 '@T6G_MB_LIB.T6G(SCH_1):PAGE232_I73@PURE_QUANTA.Q_RES(CHIPS)':
 'A': CDS_PINID='A';
NODE_NAME     R3322 1
 '@T6G_MB_LIB.T6G(SCH_1):PAGE232_I74@PURE_QUANTA.Q_RES(CHIPS)':
 'A': CDS_PINID='A';
NODE_NAME     R2950 1
 '@T6G_MB_LIB.T6G(SCH_1):PAGE363_I475@PURE_QUANTA.Q_RES(CHIPS)':
 'A': CDS_PINID='A';
NODE_NAME     R3459 1
 '@T6G_MB_LIB.T6G(SCH_1):PAGE255_I75@PURE_QUANTA.Q_RES(CHIPS)':
 'A': CDS_PINID='A';
NODE_NAME     R9043 1
 '@T6G_MB_LIB.T6G(SCH_1):PAGE299_I192@PURE_QUANTA.Q_RES(CHIPS)':
 'A': CDS_PINID='A';
NODE_NAME     R9044 1
 '@T6G_MB_LIB.T6G(SCH_1):PAGE299_I195@PURE_QUANTA.Q_RES(CHIPS)':
 'A': CDS_PINID='A';
NODE_NAME     R9032 1
 '@T6G_MB_LIB.T6G(SCH_1):PAGE340_I2@PURE_QUANTA.Q_RES(CHIPS)':
 'A': CDS_PINID='A';
NODE_NAME     U9001 5
 '@T6G_MB_LIB.T6G(SCH_1):PAGE340_I25@PURE_QUANTA.74LVC1G08W57(CHIPS)':
 'VCC': CDS_PINID='VCC';
NODE_NAME     C9007 1
 '@T6G_MB_LIB.T6G(SCH_1):PAGE340_I27@PURE_QUANTA.Q_CAP(CHIPS)':
 'A': CDS_PINID='A';
NODE_NAME     R577 1
 '@T6G_MB_LIB.T6G(SCH_1):PAGE338_I118@PURE_QUANTA.Q_RES(CHIPS)':
 'A': CDS_PINID='A';
NODE_NAME     R1128 1
 '@T6G_MB_LIB.T6G(SCH_1):PAGE340_I34@PURE_QUANTA.Q_RES(CHIPS)':
 'A': CDS_PINID='A';
NODE_NAME     U23 5
 '@T6G_MB_LIB.T6G(SCH_1):PAGE340_I36@PURE_QUANTA.74LVC1G08W57(CHIPS)':
 'VCC': CDS_PINID='VCC';
NODE_NAME     C1059 1
 '@T6G_MB_LIB.T6G(SCH_1):PAGE340_I40@PURE_QUANTA.Q_CAP(CHIPS)':
 'A': CDS_PINID='A';
NODE_NAME     R1131 1
 '@T6G_MB_LIB.T6G(SCH_1):PAGE340_I44@PURE_QUANTA.Q_RES(CHIPS)':
 'A': CDS_PINID='A';
NODE_NAME     U28 5
 '@T6G_MB_LIB.T6G(SCH_1):PAGE340_I51@PURE_QUANTA.SN74LVC1G07DBVR(CHIPS)':
 'VCC': CDS_PINID='VCC';
NODE_NAME     C1058 1
 '@T6G_MB_LIB.T6G(SCH_1):PAGE340_I53@PURE_QUANTA.Q_CAP(CHIPS)':
 'A': CDS_PINID='A';
NODE_NAME     R1133 1
 '@T6G_MB_LIB.T6G(SCH_1):PAGE340_I61@PURE_QUANTA.Q_RES(CHIPS)':
 'A': CDS_PINID='A';
NODE_NAME     R1144 1
 '@T6G_MB_LIB.T6G(SCH_1):PAGE340_I64@PURE_QUANTA.Q_RES(CHIPS)':
 'A': CDS_PINID='A';
NODE_NAME     U30 5
 '@T6G_MB_LIB.T6G(SCH_1):PAGE340_I66@PURE_QUANTA.SN74LVC1G07DBVR(CHIPS)':
 'VCC': CDS_PINID='VCC';
NODE_NAME     C1060 1
 '@T6G_MB_LIB.T6G(SCH_1):PAGE340_I69@PURE_QUANTA.Q_CAP(CHIPS)':
 'A': CDS_PINID='A';
NODE_NAME     U9002 5
 '@T6G_MB_LIB.T6G(SCH_1):PAGE340_I74@PURE_QUANTA.74LVC1G32GW(CHIPS)':
 'VCC': CDS_PINID='VCC';
NODE_NAME     C9008 1
 '@T6G_MB_LIB.T6G(SCH_1):PAGE340_I75@PURE_QUANTA.Q_CAP(CHIPS)':
 'A': CDS_PINID='A';
NODE_NAME     R1145 1
 '@T6G_MB_LIB.T6G(SCH_1):PAGE340_I76@PURE_QUANTA.Q_RES(CHIPS)':
 'A': CDS_PINID='A';
NODE_NAME     C1061 1
 '@T6G_MB_LIB.T6G(SCH_1):PAGE257_I5@PURE_QUANTA.Q_CAP(CHIPS)':
 'A': CDS_PINID='A';
NODE_NAME     R1176 1
 '@T6G_MB_LIB.T6G(SCH_1):PAGE257_I10@PURE_QUANTA.Q_RES(CHIPS)':
 'A': CDS_PINID='A';
NODE_NAME     C1065 1
 '@T6G_MB_LIB.T6G(SCH_1):PAGE257_I14@PURE_QUANTA.Q_CAP(CHIPS)':
 'A': CDS_PINID='A';
NODE_NAME     R1167 1
 '@T6G_MB_LIB.T6G(SCH_1):PAGE257_I19@PURE_QUANTA.Q_RES(CHIPS)':
 'A': CDS_PINID='A';
NODE_NAME     R1149 1
 '@T6G_MB_LIB.T6G(SCH_1):PAGE257_I25@PURE_QUANTA.Q_RES(CHIPS)':
 'A': CDS_PINID='A';
NODE_NAME     U31 5
 '@T6G_MB_LIB.T6G(SCH_1):PAGE257_I31@PURE_QUANTA.74LVC1G08W57(CHIPS)':
 'VCC': CDS_PINID='VCC';
NODE_NAME     R1165 1
 '@T6G_MB_LIB.T6G(SCH_1):PAGE257_I32@PURE_QUANTA.Q_RES(CHIPS)':
 'A': CDS_PINID='A';
NODE_NAME     C1062 1
 '@T6G_MB_LIB.T6G(SCH_1):PAGE257_I36@PURE_QUANTA.Q_CAP(CHIPS)':
 'A': CDS_PINID='A';
NODE_NAME     U37 5
 '@T6G_MB_LIB.T6G(SCH_1):PAGE257_I40@PURE_QUANTA.74LVC1G32GW(CHIPS)':
 'VCC': CDS_PINID='VCC';
NODE_NAME     U34 5
 '@T6G_MB_LIB.T6G(SCH_1):PAGE257_I45@PURE_QUANTA.SN74LVC1G07DBVR(CHIPS)':
 'VCC': CDS_PINID='VCC';
NODE_NAME     C1064 1
 '@T6G_MB_LIB.T6G(SCH_1):PAGE257_I46@PURE_QUANTA.Q_CAP(CHIPS)':
 'A': CDS_PINID='A';
NODE_NAME     R1172 1
 '@T6G_MB_LIB.T6G(SCH_1):PAGE257_I51@PURE_QUANTA.Q_RES(CHIPS)':
 'A': CDS_PINID='A';
NODE_NAME     C1063 1
 '@T6G_MB_LIB.T6G(SCH_1):PAGE257_I55@PURE_QUANTA.Q_CAP(CHIPS)':
 'A': CDS_PINID='A';
NODE_NAME     R1171 1
 '@T6G_MB_LIB.T6G(SCH_1):PAGE257_I60@PURE_QUANTA.Q_RES(CHIPS)':
 'A': CDS_PINID='A';
NODE_NAME     U35 5
 '@T6G_MB_LIB.T6G(SCH_1):PAGE257_I63@PURE_QUANTA.74LVC1G08W57(CHIPS)':
 'VCC': CDS_PINID='VCC';
NODE_NAME     U33 5
 '@T6G_MB_LIB.T6G(SCH_1):PAGE257_I64@PURE_QUANTA.SN74LVC1G07DBVR(CHIPS)':
 'VCC': CDS_PINID='VCC';
NODE_NAME     R1192 1
 '@T6G_MB_LIB.T6G(SCH_1):PAGE343_I118@PURE_QUANTA.Q_RES(CHIPS)':
 'A': CDS_PINID='A';
NODE_NAME     U45 10
 '@T6G_MB_LIB.T6G(SCH_1):PAGE376_I22@PURE_QUANTA.PI3CSW12ZUAEX(CHIPS)':
 'VDD': CDS_PINID='VDD';
NODE_NAME     C1069 1
 '@T6G_MB_LIB.T6G(SCH_1):PAGE376_I24@PURE_QUANTA.Q_CAP(CHIPS)':
 'A': CDS_PINID='A';
NODE_NAME     U42 10
 '@T6G_MB_LIB.T6G(SCH_1):PAGE376_I31@PURE_QUANTA.PI3CSW12ZUAEX(CHIPS)':
 'VDD': CDS_PINID='VDD';
NODE_NAME     C1067 1
 '@T6G_MB_LIB.T6G(SCH_1):PAGE376_I37@PURE_QUANTA.Q_CAP(CHIPS)':
 'A': CDS_PINID='A';
NODE_NAME     U41 10
 '@T6G_MB_LIB.T6G(SCH_1):PAGE376_I46@PURE_QUANTA.PI3CSW12ZUAEX(CHIPS)':
 'VDD': CDS_PINID='VDD';
NODE_NAME     C1066 1
 '@T6G_MB_LIB.T6G(SCH_1):PAGE376_I48@PURE_QUANTA.Q_CAP(CHIPS)':
 'A': CDS_PINID='A';
NODE_NAME     U43 10
 '@T6G_MB_LIB.T6G(SCH_1):PAGE376_I61@PURE_QUANTA.PI3CSW12ZUAEX(CHIPS)':
 'VDD': CDS_PINID='VDD';
NODE_NAME     C1068 1
 '@T6G_MB_LIB.T6G(SCH_1):PAGE376_I65@PURE_QUANTA.Q_CAP(CHIPS)':
 'A': CDS_PINID='A';
NODE_NAME     U48 10
 '@T6G_MB_LIB.T6G(SCH_1):PAGE376_I76@PURE_QUANTA.PI3CSW12ZUAEX(CHIPS)':
 'VDD': CDS_PINID='VDD';
NODE_NAME     C1073 1
 '@T6G_MB_LIB.T6G(SCH_1):PAGE376_I80@PURE_QUANTA.Q_CAP(CHIPS)':
 'A': CDS_PINID='A';
NODE_NAME     C1072 1
 '@T6G_MB_LIB.T6G(SCH_1):PAGE376_I84@PURE_QUANTA.Q_CAP(CHIPS)':
 'A': CDS_PINID='A';
NODE_NAME     U49 10
 '@T6G_MB_LIB.T6G(SCH_1):PAGE376_I85@PURE_QUANTA.PI3CSW12ZUAEX(CHIPS)':
 'VDD': CDS_PINID='VDD';
NODE_NAME     C1070 1
 '@T6G_MB_LIB.T6G(SCH_1):PAGE376_I99@PURE_QUANTA.Q_CAP(CHIPS)':
 'A': CDS_PINID='A';
NODE_NAME     C1071 1
 '@T6G_MB_LIB.T6G(SCH_1):PAGE376_I105@PURE_QUANTA.Q_CAP(CHIPS)':
 'A': CDS_PINID='A';
NODE_NAME     U46 10
 '@T6G_MB_LIB.T6G(SCH_1):PAGE376_I108@PURE_QUANTA.PI3CSW12ZUAEX(CHIPS)':
 'VDD': CDS_PINID='VDD';
NODE_NAME     U47 10
 '@T6G_MB_LIB.T6G(SCH_1):PAGE376_I121@PURE_QUANTA.PI3CSW12ZUAEX(CHIPS)':
 'VDD': CDS_PINID='VDD';
NODE_NAME     R1239 1
 '@T6G_MB_LIB.T6G(SCH_1):PAGE263_I59@PURE_QUANTA.Q_RES(CHIPS)':
 'A': CDS_PINID='A';
NODE_NAME     R1241 1
 '@T6G_MB_LIB.T6G(SCH_1):PAGE263_I60@PURE_QUANTA.Q_RES(CHIPS)':
 'A': CDS_PINID='A';
NODE_NAME     L25 1
 '@T6G_MB_LIB.T6G(SCH_1):PAGE263_I69@PURE_QUANTA.Q_INDUCTOR(CHIPS)':
 '1': CDS_PINID='\1\';
NODE_NAME     L24 2
 '@T6G_MB_LIB.T6G(SCH_1):PAGE263_I168@PURE_QUANTA.Q_INDUCTOR(CHIPS)':
 '2': CDS_PINID='\2\';
NODE_NAME     R1320 1
 '@T6G_MB_LIB.T6G(SCH_1):PAGE466_I17@PURE_QUANTA.Q_RES(CHIPS)':
 'A': CDS_PINID='A';
NODE_NAME     C1097 1
 '@T6G_MB_LIB.T6G(SCH_1):PAGE466_I19@PURE_QUANTA.Q_CAP(CHIPS)':
 'A': CDS_PINID='A';
NODE_NAME     U55 9
 '@T6G_MB_LIB.T6G(SCH_1):PAGE466_I28@PURE_QUANTA.ISL28022FRZT(CHIPS)':
 'VCC': CDS_PINID='VCC';
NODE_NAME     U56 9
 '@T6G_MB_LIB.T6G(SCH_1):PAGE466_I29@PURE_QUANTA.ISL28022FRZT(CHIPS)':
 'VCC': CDS_PINID='VCC';
NODE_NAME     C1106 1
 '@T6G_MB_LIB.T6G(SCH_1):PAGE466_I36@PURE_QUANTA.Q_CAP(CHIPS)':
 'A': CDS_PINID='A';
NODE_NAME     R1322 1
 '@T6G_MB_LIB.T6G(SCH_1):PAGE466_I39@PURE_QUANTA.Q_RES(CHIPS)':
 'A': CDS_PINID='A';
NODE_NAME     U52 9
 '@T6G_MB_LIB.T6G(SCH_1):PAGE466_I57@PURE_QUANTA.ISL28022FRZT(CHIPS)':
 'VCC': CDS_PINID='VCC';
NODE_NAME     C1096 1
 '@T6G_MB_LIB.T6G(SCH_1):PAGE466_I66@PURE_QUANTA.Q_CAP(CHIPS)':
 'A': CDS_PINID='A';
NODE_NAME     R1327 1
 '@T6G_MB_LIB.T6G(SCH_1):PAGE466_I85@PURE_QUANTA.Q_RES(CHIPS)':
 'A': CDS_PINID='A';
NODE_NAME     R1328 1
 '@T6G_MB_LIB.T6G(SCH_1):PAGE466_I87@PURE_QUANTA.Q_RES(CHIPS)':
 'A': CDS_PINID='A';
NODE_NAME     R1326 1
 '@T6G_MB_LIB.T6G(SCH_1):PAGE466_I90@PURE_QUANTA.Q_RES(CHIPS)':
 'A': CDS_PINID='A';
NODE_NAME     R1317 1
 '@T6G_MB_LIB.T6G(SCH_1):PAGE466_I95@PURE_QUANTA.Q_RES(CHIPS)':
 'A': CDS_PINID='A';
NODE_NAME     R1316 1
 '@T6G_MB_LIB.T6G(SCH_1):PAGE251_I83@PURE_QUANTA.Q_RES(CHIPS)':
 'A': CDS_PINID='A';
NODE_NAME     R1341 1
 '@T6G_MB_LIB.T6G(SCH_1):PAGE251_I84@PURE_QUANTA.Q_RES(CHIPS)':
 'A': CDS_PINID='A';
NODE_NAME     U4 10
 '@T6G_MB_LIB.T6G(SCH_1):PAGE138_I114@PURE_QUANTA.PI3CSW12ZUAEX(CHIPS)':
 'VDD': CDS_PINID='VDD';
NODE_NAME     U2 8
 '@T6G_MB_LIB.T6G(SCH_1):PAGE137_I99@PURE_QUANTA.PCA9617ADP(CHIPS)':
 'VCCB': CDS_PINID='VCCB';
NODE_NAME     R3783 1
 '@T6G_MB_LIB.T6G(SCH_1):PAGE338_I131@PURE_QUANTA.Q_RES(CHIPS)':
 'A': CDS_PINID='A';
NODE_NAME     R3826 1
 '@T6G_MB_LIB.T6G(SCH_1):PAGE343_I128@PURE_QUANTA.Q_RES(CHIPS)':
 'A': CDS_PINID='A';
NODE_NAME     R4452 1
 '@T6G_MB_LIB.T6G(SCH_1):PAGE153_I93@PURE_QUANTA.Q_RES(CHIPS)':
 'A': CDS_PINID='A';
NODE_NAME     R6320 1
 '@T6G_MB_LIB.T6G(SCH_1):PAGE155_I212@PURE_QUANTA.Q_RES(CHIPS)':
 'A': CDS_PINID='A';
NODE_NAME     R6329 1
 '@T6G_MB_LIB.T6G(SCH_1):PAGE155_I213@PURE_QUANTA.Q_RES(CHIPS)':
 'A': CDS_PINID='A';
NODE_NAME     R8125 1
 '@T6G_MB_LIB.T6G(SCH_1):PAGE372_I104@PURE_QUANTA.Q_RES(CHIPS)':
 'A': CDS_PINID='A';
NODE_NAME     R3470 1
 '@T6G_MB_LIB.T6G(SCH_1):PAGE299_I202@PURE_QUANTA.Q_RES(CHIPS)':
 'A': CDS_PINID='A';
NODE_NAME     R8106 1
 '@T6G_MB_LIB.T6G(SCH_1):PAGE365_I31@PURE_QUANTA.Q_RES(CHIPS)':
 'A': CDS_PINID='A';
NODE_NAME     R1481 1
 '@T6G_MB_LIB.T6G(SCH_1):PAGE146_I21@PURE_QUANTA.Q_RES(CHIPS)':
 'A': CDS_PINID='A';
NODE_NAME     R1052 1
 '@T6G_MB_LIB.T6G(SCH_1):PAGE146_I38@PURE_QUANTA.Q_RES(CHIPS)':
 'A': CDS_PINID='A';
NODE_NAME     U9050 5
 '@T6G_MB_LIB.T6G(SCH_1):PAGE340_I91@PURE_QUANTA.74LVC1G08W57(CHIPS)':
 'VCC': CDS_PINID='VCC';
NODE_NAME     C9050 1
 '@T6G_MB_LIB.T6G(SCH_1):PAGE340_I94@PURE_QUANTA.Q_CAP(CHIPS)':
 'A': CDS_PINID='A';
NODE_NAME     U9051 5
 '@T6G_MB_LIB.T6G(SCH_1):PAGE257_I78@PURE_QUANTA.74LVC1G08W57(CHIPS)':
 'VCC': CDS_PINID='VCC';
NODE_NAME     C9051 1
 '@T6G_MB_LIB.T6G(SCH_1):PAGE257_I81@PURE_QUANTA.Q_CAP(CHIPS)':
 'A': CDS_PINID='A';
NODE_NAME     R9024 1
 '@T6G_MB_LIB.T6G(SCH_1):PAGE371_I113@PURE_QUANTA.Q_RES(CHIPS)':
 'A': CDS_PINID='A';
NET_NAME
'P3V3_AUX_ADC'
 '@T6G_MB_LIB.T6G(SCH_1):P3V3_AUX_ADC':
 C_SIGNAL='@t6g_mb_lib.t6g(sch_1):p3v3_aux_adc';
NODE_NAME     R1785 1
 '@T6G_MB_LIB.T6G(SCH_1):PAGE369_I26@PURE_QUANTA.Q_RES(CHIPS)':
 'A': CDS_PINID='A';
NODE_NAME     R3682 1
 '@T6G_MB_LIB.T6G(SCH_1):PAGE369_I27@PURE_QUANTA.Q_RES(CHIPS)':
 'A': CDS_PINID='A';
NODE_NAME     R2907 2
 '@T6G_MB_LIB.T6G(SCH_1):PAGE369_I28@PURE_QUANTA.Q_RES(CHIPS)':
 'B': CDS_PINID='B';
NODE_NAME     R3681 1
 '@T6G_MB_LIB.T6G(SCH_1):PAGE369_I30@PURE_QUANTA.Q_RES(CHIPS)':
 'A': CDS_PINID='A';
NET_NAME
'P3V3_AUX_ADC_MAM'
 '@T6G_MB_LIB.T6G(SCH_1):P3V3_AUX_ADC_MAM':
 C_SIGNAL='@t6g_mb_lib.t6g(sch_1):p3v3_aux_adc_mam';
NODE_NAME     R3681 2
 '@T6G_MB_LIB.T6G(SCH_1):PAGE369_I30@PURE_QUANTA.Q_RES(CHIPS)':
 'B': CDS_PINID='B';
NODE_NAME     C2042 1
 '@T6G_MB_LIB.T6G(SCH_1):PAGE369_I99@PURE_QUANTA.Q_CAP(CHIPS)':
 'A': CDS_PINID='A';
NODE_NAME     U193 10
 '@T6G_MB_LIB.T6G(SCH_1):PAGE369_I169@PURE_QUANTA.MAX11617EEET(CHIPS)':
 'AIN5': CDS_PINID='AIN5';
NET_NAME
'P3V3_AUX_ADC_TIC'
 '@T6G_MB_LIB.T6G(SCH_1):P3V3_AUX_ADC_TIC':
 C_SIGNAL='@t6g_mb_lib.t6g(sch_1):p3v3_aux_adc_tic';
NODE_NAME     R3682 2
 '@T6G_MB_LIB.T6G(SCH_1):PAGE369_I27@PURE_QUANTA.Q_RES(CHIPS)':
 'B': CDS_PINID='B';
NODE_NAME     C2047 1
 '@T6G_MB_LIB.T6G(SCH_1):PAGE369_I98@PURE_QUANTA.Q_CAP(CHIPS)':
 'A': CDS_PINID='A';
NODE_NAME     U269 11
 '@T6G_MB_LIB.T6G(SCH_1):PAGE369_I142@PURE_QUANTA.ADC128D818CIMTXNOPB(CHIPS)':
 'IN5': CDS_PINID='IN5';
NET_NAME
'P3V3_AUX_CPU0_USB2_AVDD33'
 '@T6G_MB_LIB.T6G(SCH_1):P3V3_AUX_CPU0_USB2_AVDD33':
 C_SIGNAL='@t6g_mb_lib.t6g(sch_1):p3v3_aux_cpu0_usb2_avdd33',
 CDS_GLOBAL_NET='TRUE';
NODE_NAME     L6003 2
 '@T6G_MB_LIB.T6G(SCH_1):PAGE157_I17@PURE_QUANTA.Q_INDUCTOR(CHIPS)':
 '2': CDS_PINID='\2\';
NODE_NAME     C6092 1
 '@T6G_MB_LIB.T6G(SCH_1):PAGE157_I21@PURE_QUANTA.Q_CAP(CHIPS)':
 'A': CDS_PINID='A';
NODE_NAME     C6094 1
 '@T6G_MB_LIB.T6G(SCH_1):PAGE157_I22@PURE_QUANTA.Q_CAP(CHIPS)':
 'A': CDS_PINID='A';
NODE_NAME     C6095 1
 '@T6G_MB_LIB.T6G(SCH_1):PAGE157_I23@PURE_QUANTA.Q_CAP(CHIPS)':
 'A': CDS_PINID='A';
NODE_NAME     C6093 1
 '@T6G_MB_LIB.T6G(SCH_1):PAGE157_I24@PURE_QUANTA.Q_CAP(CHIPS)':
 'A': CDS_PINID='A';
NODE_NAME     C6098 1
 '@T6G_MB_LIB.T6G(SCH_1):PAGE157_I25@PURE_QUANTA.Q_CAP(CHIPS)':
 'A': CDS_PINID='A';
NODE_NAME     C6097 1
 '@T6G_MB_LIB.T6G(SCH_1):PAGE157_I26@PURE_QUANTA.Q_CAP(CHIPS)':
 'A': CDS_PINID='A';
NODE_NAME     C6096 1
 '@T6G_MB_LIB.T6G(SCH_1):PAGE157_I27@PURE_QUANTA.Q_CAP(CHIPS)':
 'A': CDS_PINID='A';
NODE_NAME     C6101 1
 '@T6G_MB_LIB.T6G(SCH_1):PAGE157_I28@PURE_QUANTA.Q_CAP(CHIPS)':
 'A': CDS_PINID='A';
NODE_NAME     C6100 1
 '@T6G_MB_LIB.T6G(SCH_1):PAGE157_I29@PURE_QUANTA.Q_CAP(CHIPS)':
 'A': CDS_PINID='A';
NODE_NAME     C6099 1
 '@T6G_MB_LIB.T6G(SCH_1):PAGE157_I30@PURE_QUANTA.Q_CAP(CHIPS)':
 'A': CDS_PINID='A';
NODE_NAME     C6104 1
 '@T6G_MB_LIB.T6G(SCH_1):PAGE157_I31@PURE_QUANTA.Q_CAP(CHIPS)':
 'A': CDS_PINID='A';
NODE_NAME     C6103 1
 '@T6G_MB_LIB.T6G(SCH_1):PAGE157_I32@PURE_QUANTA.Q_CAP(CHIPS)':
 'A': CDS_PINID='A';
NODE_NAME     C6102 1
 '@T6G_MB_LIB.T6G(SCH_1):PAGE157_I33@PURE_QUANTA.Q_CAP(CHIPS)':
 'A': CDS_PINID='A';
NODE_NAME     U6002 52
 '@T6G_MB_LIB.T6G(SCH_1):PAGE157_I119@PURE_QUANTA.TUSB8042AIRGCR(CHIPS)':
 'VDD33_52': CDS_PINID='VDD33_52';
NODE_NAME     U6002 63
 '@T6G_MB_LIB.T6G(SCH_1):PAGE157_I119@PURE_QUANTA.TUSB8042AIRGCR(CHIPS)':
 'VDD33_63': CDS_PINID='VDD33_63';
NODE_NAME     R6275 2
 '@T6G_MB_LIB.T6G(SCH_1):PAGE157_I131@PURE_QUANTA.Q_RES(CHIPS)':
 'B': CDS_PINID='B';
NODE_NAME     R6270 1
 '@T6G_MB_LIB.T6G(SCH_1):PAGE155_I143@PURE_QUANTA.Q_RES(CHIPS)':
 'A': CDS_PINID='A';
NODE_NAME     R6264 2
 '@T6G_MB_LIB.T6G(SCH_1):PAGE155_I151@PURE_QUANTA.Q_RES(CHIPS)':
 'B': CDS_PINID='B';
NODE_NAME     R6274 2
 '@T6G_MB_LIB.T6G(SCH_1):PAGE157_I142@PURE_QUANTA.Q_RES(CHIPS)':
 'B': CDS_PINID='B';
NET_NAME
'P3V3_AUX_CPU0_USB_AVDD33'
 '@T6G_MB_LIB.T6G(SCH_1):P3V3_AUX_CPU0_USB_AVDD33':
 C_SIGNAL='@t6g_mb_lib.t6g(sch_1):p3v3_aux_cpu0_usb_avdd33',
 CDS_GLOBAL_NET='TRUE';
NODE_NAME     U6001 4
 '@T6G_MB_LIB.T6G(SCH_1):PAGE154_I1@PURE_QUANTA.CYUSB330468LTXI(CHIPS)':
 'AVDD33_1': CDS_PINID='AVDD33_1';
NODE_NAME     L6000 2
 '@T6G_MB_LIB.T6G(SCH_1):PAGE154_I3@PURE_QUANTA.Q_INDUCTOR(CHIPS)':
 '2': CDS_PINID='\2\';
NODE_NAME     C6042 1
 '@T6G_MB_LIB.T6G(SCH_1):PAGE154_I9@PURE_QUANTA.Q_CAP(CHIPS)':
 'A': CDS_PINID='A';
NODE_NAME     C6043 1
 '@T6G_MB_LIB.T6G(SCH_1):PAGE154_I10@PURE_QUANTA.Q_CAP(CHIPS)':
 'A': CDS_PINID='A';
NODE_NAME     C6044 1
 '@T6G_MB_LIB.T6G(SCH_1):PAGE154_I12@PURE_QUANTA.Q_CAP(CHIPS)':
 'A': CDS_PINID='A';
NODE_NAME     C6045 1
 '@T6G_MB_LIB.T6G(SCH_1):PAGE154_I13@PURE_QUANTA.Q_CAP(CHIPS)':
 'A': CDS_PINID='A';
NET_NAME
'P3V3_AUX_DSC'
 '@T6G_MB_LIB.T6G(SCH_1):P3V3_AUX_DSC':
 C_SIGNAL='@t6g_mb_lib.t6g(sch_1):p3v3_aux_dsc';
NODE_NAME     R1481 2
 '@T6G_MB_LIB.T6G(SCH_1):PAGE146_I21@PURE_QUANTA.Q_RES(CHIPS)':
 'B': CDS_PINID='B';
NODE_NAME     Q7003 5
 '@T6G_MB_LIB.T6G(SCH_1):PAGE146_I22@PURE_QUANTA.MOSFET_NCH_1D3S(CHIPS)':
 '5': CDS_PINID='\5\';
NET_NAME
'P3V3_AUX_DSC_G1'
 '@T6G_MB_LIB.T6G(SCH_1):P3V3_AUX_DSC_G1':
 C_SIGNAL='@t6g_mb_lib.t6g(sch_1):p3v3_aux_dsc_g1';
NODE_NAME     Q7002 G
 '@T6G_MB_LIB.T6G(SCH_1):PAGE146_I23@PURE_QUANTA.MOSFET_PCH_GDS_ESD_PROTECTED(CHIPS)':
 'G': CDS_PINID='G';
NODE_NAME     R1052 2
 '@T6G_MB_LIB.T6G(SCH_1):PAGE146_I38@PURE_QUANTA.Q_RES(CHIPS)':
 'B': CDS_PINID='B';
NODE_NAME     R1092 1
 '@T6G_MB_LIB.T6G(SCH_1):PAGE146_I39@PURE_QUANTA.Q_RES(CHIPS)':
 'A': CDS_PINID='A';
NET_NAME
'P3V3_AUX_DSC_G2'
 '@T6G_MB_LIB.T6G(SCH_1):P3V3_AUX_DSC_G2':
 C_SIGNAL='@t6g_mb_lib.t6g(sch_1):p3v3_aux_dsc_g2';
NODE_NAME     Q7003 4
 '@T6G_MB_LIB.T6G(SCH_1):PAGE146_I22@PURE_QUANTA.MOSFET_NCH_1D3S(CHIPS)':
 '4': CDS_PINID='\4\';
NODE_NAME     Q7002 D
 '@T6G_MB_LIB.T6G(SCH_1):PAGE146_I23@PURE_QUANTA.MOSFET_PCH_GDS_ESD_PROTECTED(CHIPS)':
 'D': CDS_PINID='D';
NODE_NAME     R1475 1
 '@T6G_MB_LIB.T6G(SCH_1):PAGE146_I28@PURE_QUANTA.Q_RES(CHIPS)':
 'A': CDS_PINID='A';
NET_NAME
'P3V3_AUX_DSC_S1'
 '@T6G_MB_LIB.T6G(SCH_1):P3V3_AUX_DSC_S1':
 C_SIGNAL='@t6g_mb_lib.t6g(sch_1):p3v3_aux_dsc_s1';
NODE_NAME     Q7002 S
 '@T6G_MB_LIB.T6G(SCH_1):PAGE146_I23@PURE_QUANTA.MOSFET_PCH_GDS_ESD_PROTECTED(CHIPS)':
 'S': CDS_PINID='S';
NODE_NAME     U60 3
 '@T6G_MB_LIB.T6G(SCH_1):PAGE146_I25@PURE_QUANTA.SCHOTTKY_DUAL_12A_3C(CHIPS)':
 'C': CDS_PINID='C';
NODE_NAME     C1114 1
 '@T6G_MB_LIB.T6G(SCH_1):PAGE146_I30@PURE_QUANTA.Q_CAP(CHIPS)':
 'A': CDS_PINID='A';
NET_NAME
'P3V3_AUX_DSC_VOL'
 '@T6G_MB_LIB.T6G(SCH_1):P3V3_AUX_DSC_VOL':
 C_SIGNAL='@t6g_mb_lib.t6g(sch_1):p3v3_aux_dsc_vol';
NODE_NAME     U60 1
 '@T6G_MB_LIB.T6G(SCH_1):PAGE146_I25@PURE_QUANTA.SCHOTTKY_DUAL_12A_3C(CHIPS)':
 'B': CDS_PINID='B';
NODE_NAME     R896 2
 '@T6G_MB_LIB.T6G(SCH_1):PAGE146_I35@PURE_QUANTA.Q_RES(CHIPS)':
 'B': CDS_PINID='B';
NODE_NAME     R954 1
 '@T6G_MB_LIB.T6G(SCH_1):PAGE146_I36@PURE_QUANTA.Q_RES(CHIPS)':
 'A': CDS_PINID='A';
NET_NAME
'P3V3_AUX_EN'
 '@T6G_MB_LIB.T6G(SCH_1):P3V3_AUX_EN':
 C_SIGNAL='@t6g_mb_lib.t6g(sch_1):p3v3_aux_en';
NODE_NAME     R3118 1
 '@T6G_MB_LIB.T6G(SCH_1):PAGE245_I2@PURE_QUANTA.Q_RES(CHIPS)':
 'A': CDS_PINID='A';
NODE_NAME     R3117 2
 '@T6G_MB_LIB.T6G(SCH_1):PAGE245_I4@PURE_QUANTA.Q_RES(CHIPS)':
 'B': CDS_PINID='B';
NODE_NAME     PC1870 1
 '@T6G_MB_LIB.T6G(SCH_1):PAGE245_I8@PURE_QUANTA.Q_CAP(CHIPS)':
 'A': CDS_PINID='A';
NODE_NAME     R1571 2
 '@T6G_MB_LIB.T6G(SCH_1):PAGE245_I11@PURE_QUANTA.Q_RES(CHIPS)':
 'B': CDS_PINID='B';
NODE_NAME     PU9 27
 '@T6G_MB_LIB.T6G(SCH_1):PAGE245_I21@PURE_QUANTA.NCP3284AMNTXG(CHIPS)':
 'EN': CDS_PINID='EN';
NET_NAME
'P3V3_AUX_FB'
 '@T6G_MB_LIB.T6G(SCH_1):P3V3_AUX_FB':
 C_SIGNAL='@t6g_mb_lib.t6g(sch_1):p3v3_aux_fb';
NODE_NAME     PU9 30
 '@T6G_MB_LIB.T6G(SCH_1):PAGE245_I21@PURE_QUANTA.NCP3284AMNTXG(CHIPS)':
 'FB': CDS_PINID='FB';
NODE_NAME     PR830 1
 '@T6G_MB_LIB.T6G(SCH_1):PAGE245_I51@PURE_QUANTA.Q_RES(CHIPS)':
 'A': CDS_PINID='A';
NODE_NAME     PC569 1
 '@T6G_MB_LIB.T6G(SCH_1):PAGE245_I53@PURE_QUANTA.Q_CAP(CHIPS)':
 'A': CDS_PINID='A';
NODE_NAME     PR831 1
 '@T6G_MB_LIB.T6G(SCH_1):PAGE245_I54@PURE_QUANTA.Q_RES(CHIPS)':
 'A': CDS_PINID='A';
NET_NAME
'P3V3_AUX_ILIM'
 '@T6G_MB_LIB.T6G(SCH_1):P3V3_AUX_ILIM':
 C_SIGNAL='@t6g_mb_lib.t6g(sch_1):p3v3_aux_ilim';
NODE_NAME     PR834 1
 '@T6G_MB_LIB.T6G(SCH_1):PAGE245_I17@PURE_QUANTA.Q_RES(CHIPS)':
 'A': CDS_PINID='A';
NODE_NAME     PU9 1
 '@T6G_MB_LIB.T6G(SCH_1):PAGE245_I21@PURE_QUANTA.NCP3284AMNTXG(CHIPS)':
 'ILIM': CDS_PINID='ILIM';
NET_NAME
'P3V3_AUX_MODE'
 '@T6G_MB_LIB.T6G(SCH_1):P3V3_AUX_MODE':
 C_SIGNAL='@t6g_mb_lib.t6g(sch_1):p3v3_aux_mode';
NODE_NAME     PU9 36
 '@T6G_MB_LIB.T6G(SCH_1):PAGE245_I21@PURE_QUANTA.NCP3284AMNTXG(CHIPS)':
 'MODE||FSET': CDS_PINID='\mode||fset\';
NODE_NAME     PR832 1
 '@T6G_MB_LIB.T6G(SCH_1):PAGE245_I10@PURE_QUANTA.Q_RES(CHIPS)':
 'A': CDS_PINID='A';
NET_NAME
'P3V3_AUX_SS'
 '@T6G_MB_LIB.T6G(SCH_1):P3V3_AUX_SS':
 C_SIGNAL='@t6g_mb_lib.t6g(sch_1):p3v3_aux_ss';
NODE_NAME     PR833 1
 '@T6G_MB_LIB.T6G(SCH_1):PAGE245_I15@PURE_QUANTA.Q_RES(CHIPS)':
 'A': CDS_PINID='A';
NODE_NAME     PU9 29
 '@T6G_MB_LIB.T6G(SCH_1):PAGE245_I21@PURE_QUANTA.NCP3284AMNTXG(CHIPS)':
 'SS': CDS_PINID='SS';
NET_NAME
'P3V3_AUX_USB_HUB'
 '@T6G_MB_LIB.T6G(SCH_1):P3V3_AUX_USB_HUB':
 C_SIGNAL='@t6g_mb_lib.t6g(sch_1):p3v3_aux_usb_hub';
NODE_NAME     U268 5
 '@T6G_MB_LIB.T6G(SCH_1):PAGE358_I100@PURE_QUANTA.GL852GOHY60(CHIPS)':
 'AVDD'<0>: CDS_PINID='AVDD(0)';
NODE_NAME     U268 9
 '@T6G_MB_LIB.T6G(SCH_1):PAGE358_I100@PURE_QUANTA.GL852GOHY60(CHIPS)':
 'AVDD'<1>: CDS_PINID='AVDD(1)';
NODE_NAME     U268 14
 '@T6G_MB_LIB.T6G(SCH_1):PAGE358_I100@PURE_QUANTA.GL852GOHY60(CHIPS)':
 'AVDD'<2>: CDS_PINID='AVDD(2)';
NODE_NAME     U268 27
 '@T6G_MB_LIB.T6G(SCH_1):PAGE358_I100@PURE_QUANTA.GL852GOHY60(CHIPS)':
 'V5': CDS_PINID='V5';
NODE_NAME     U268 28
 '@T6G_MB_LIB.T6G(SCH_1):PAGE358_I100@PURE_QUANTA.GL852GOHY60(CHIPS)':
 'V33': CDS_PINID='V33';
NODE_NAME     C2034 1
 '@T6G_MB_LIB.T6G(SCH_1):PAGE358_I142@PURE_QUANTA.Q_CAP(CHIPS)':
 'A': CDS_PINID='A';
NODE_NAME     C2033 1
 '@T6G_MB_LIB.T6G(SCH_1):PAGE358_I143@PURE_QUANTA.Q_CAP(CHIPS)':
 'A': CDS_PINID='A';
NODE_NAME     C2032 1
 '@T6G_MB_LIB.T6G(SCH_1):PAGE358_I145@PURE_QUANTA.Q_CAP(CHIPS)':
 'A': CDS_PINID='A';
NODE_NAME     C2035 1
 '@T6G_MB_LIB.T6G(SCH_1):PAGE358_I147@PURE_QUANTA.Q_CAP(CHIPS)':
 'A': CDS_PINID='A';
NODE_NAME     C2031 1
 '@T6G_MB_LIB.T6G(SCH_1):PAGE358_I148@PURE_QUANTA.Q_CAP(CHIPS)':
 'A': CDS_PINID='A';
NODE_NAME     R3655 2
 '@T6G_MB_LIB.T6G(SCH_1):PAGE358_I161@PURE_QUANTA.Q_RES(CHIPS)':
 'B': CDS_PINID='B';
NODE_NAME     C2040 1
 '@T6G_MB_LIB.T6G(SCH_1):PAGE358_I162@PURE_QUANTA.Q_CAP(CHIPS)':
 'A': CDS_PINID='A';
NODE_NAME     C2039 1
 '@T6G_MB_LIB.T6G(SCH_1):PAGE358_I163@PURE_QUANTA.Q_CAP(CHIPS)':
 'A': CDS_PINID='A';
NODE_NAME     C2038 1
 '@T6G_MB_LIB.T6G(SCH_1):PAGE358_I164@PURE_QUANTA.Q_CAP(CHIPS)':
 'A': CDS_PINID='A';
NODE_NAME     R3662 1
 '@T6G_MB_LIB.T6G(SCH_1):PAGE358_I167@PURE_QUANTA.Q_RES(CHIPS)':
 'A': CDS_PINID='A';
NET_NAME
'P3V3_AUX_VCC'
 '@T6G_MB_LIB.T6G(SCH_1):P3V3_AUX_VCC':
 C_SIGNAL='@t6g_mb_lib.t6g(sch_1):p3v3_aux_vcc';
NODE_NAME     PR8389 2
 '@T6G_MB_LIB.T6G(SCH_1):PAGE245_I20@PURE_QUANTA.Q_RES(CHIPS)':
 'B': CDS_PINID='B';
NODE_NAME     PU9 4
 '@T6G_MB_LIB.T6G(SCH_1):PAGE245_I21@PURE_QUANTA.NCP3284AMNTXG(CHIPS)':
 'VCC': CDS_PINID='VCC';
NODE_NAME     PC591 1
 '@T6G_MB_LIB.T6G(SCH_1):PAGE245_I19@PURE_QUANTA.Q_CAP(CHIPS)':
 'A': CDS_PINID='A';
NET_NAME
'P3V3_AUX_VDRV'
 '@T6G_MB_LIB.T6G(SCH_1):P3V3_AUX_VDRV':
 C_SIGNAL='@t6g_mb_lib.t6g(sch_1):p3v3_aux_vdrv';
NODE_NAME     PR8389 1
 '@T6G_MB_LIB.T6G(SCH_1):PAGE245_I20@PURE_QUANTA.Q_RES(CHIPS)':
 'A': CDS_PINID='A';
NODE_NAME     PU9 5
 '@T6G_MB_LIB.T6G(SCH_1):PAGE245_I21@PURE_QUANTA.NCP3284AMNTXG(CHIPS)':
 'VDRV': CDS_PINID='VDRV';
NODE_NAME     PC581 1
 '@T6G_MB_LIB.T6G(SCH_1):PAGE245_I12@PURE_QUANTA.Q_CAP(CHIPS)':
 'A': CDS_PINID='A';
NET_NAME
'P3V3_AUX_VOS'
 '@T6G_MB_LIB.T6G(SCH_1):P3V3_AUX_VOS':
 C_SIGNAL='@t6g_mb_lib.t6g(sch_1):p3v3_aux_vos';
NODE_NAME     PU9 28
 '@T6G_MB_LIB.T6G(SCH_1):PAGE245_I21@PURE_QUANTA.NCP3284AMNTXG(CHIPS)':
 'VOS': CDS_PINID='VOS';
NODE_NAME     PR836 1
 '@T6G_MB_LIB.T6G(SCH_1):PAGE245_I46@PURE_QUANTA.Q_RES(CHIPS)':
 'A': CDS_PINID='A';
NET_NAME
'P3V3_E1S_0'
 '@T6G_MB_LIB.T6G(SCH_1):P3V3_E1S_0':
 C_SIGNAL='@t6g_mb_lib.t6g(sch_1):p3v3_e1s_0',
 CDS_GLOBAL_NET='TRUE';
NODE_NAME     R3532 1
 '@T6G_MB_LIB.T6G(SCH_1):PAGE346_I78@PURE_QUANTA.Q_RES(CHIPS)':
 'A': CDS_PINID='A';
NODE_NAME     R3530 1
 '@T6G_MB_LIB.T6G(SCH_1):PAGE346_I80@PURE_QUANTA.Q_RES(CHIPS)':
 'A': CDS_PINID='A';
NODE_NAME     C1998 1
 '@T6G_MB_LIB.T6G(SCH_1):PAGE346_I82@PURE_QUANTA.Q_CAP(CHIPS)':
 'A': CDS_PINID='A';
NODE_NAME     U279 1
 '@T6G_MB_LIB.T6G(SCH_1):PAGE346_I93@PURE_QUANTA.PCA9617ADP(CHIPS)':
 'VCCA': CDS_PINID='VCCA';
NODE_NAME     R3760 1
 '@T6G_MB_LIB.T6G(SCH_1):PAGE295_I134@PURE_QUANTA.Q_RES(CHIPS)':
 'A': CDS_PINID='A';
NODE_NAME     R3767 1
 '@T6G_MB_LIB.T6G(SCH_1):PAGE295_I144@PURE_QUANTA.Q_RES(CHIPS)':
 'A': CDS_PINID='A';
NODE_NAME     R2317 1
 '@T6G_MB_LIB.T6G(SCH_1):PAGE297_I31@PURE_QUANTA.Q_RES(CHIPS)':
 'A': CDS_PINID='A';
NODE_NAME     R10287 1
 '@T6G_MB_LIB.T6G(SCH_1):PAGE297_I79@PURE_QUANTA.Q_RES(CHIPS)':
 'A': CDS_PINID='A';
NODE_NAME     C1282 1
 '@T6G_MB_LIB.T6G(SCH_1):PAGE297_I87@PURE_QUANTA.Q_CAP(CHIPS)':
 'A': CDS_PINID='A';
NODE_NAME     C1283 1
 '@T6G_MB_LIB.T6G(SCH_1):PAGE297_I88@PURE_QUANTA.Q_CAP(CHIPS)':
 'A': CDS_PINID='A';
NODE_NAME     J90 B11
 '@T6G_MB_LIB.T6G(SCH_1):PAGE297_I90@PURE_QUANTA.SCONN56_123276793(CHIPS)':
 'P3V3_AUX': CDS_PINID='P3V3_AUX';
NODE_NAME     U44 5
 '@T6G_MB_LIB.T6G(SCH_1):PAGE297_I97@PURE_QUANTA.74LVC1G17GW(CHIPS)':
 'VCC': CDS_PINID='VCC';
NODE_NAME     C508 1
 '@T6G_MB_LIB.T6G(SCH_1):PAGE297_I99@PURE_QUANTA.Q_CAP(CHIPS)':
 'A': CDS_PINID='A';
NODE_NAME     R1673 1
 '@T6G_MB_LIB.T6G(SCH_1):PAGE297_I105@PURE_QUANTA.Q_RES(CHIPS)':
 'A': CDS_PINID='A';
NET_NAME
'P3V3_E1S_0_EN_G'
 '@T6G_MB_LIB.T6G(SCH_1):P3V3_E1S_0_EN_G':
 C_SIGNAL='@t6g_mb_lib.t6g(sch_1):p3v3_e1s_0_en_g';
NODE_NAME     Q126 6
 '@T6G_MB_LIB.T6G(SCH_1):PAGE324_I6@PURE_QUANTA.MOSFET_NCH_DUAL(CHIPS)':
 'D1': CDS_PINID='D1';
NODE_NAME     Q126 5
 '@T6G_MB_LIB.T6G(SCH_1):PAGE324_I7@PURE_QUANTA.MOSFET_NCH_DUAL(CHIPS)':
 'G2': CDS_PINID='G2';
NODE_NAME     R4072 2
 '@T6G_MB_LIB.T6G(SCH_1):PAGE324_I8@PURE_QUANTA.Q_RES(CHIPS)':
 'B': CDS_PINID='B';
NET_NAME
'P3V3_E1S_0_EN_R'
 '@T6G_MB_LIB.T6G(SCH_1):P3V3_E1S_0_EN_R':
 C_SIGNAL='@t6g_mb_lib.t6g(sch_1):p3v3_e1s_0_en_r';
NODE_NAME     R648 2
 '@T6G_MB_LIB.T6G(SCH_1):PAGE80_I25@PURE_QUANTA.Q_RES(CHIPS)':
 'B': CDS_PINID='B';
NODE_NAME     U18 V12
 '@T6G_MB_LIB.T6G(SCH_1):PAGE80_I216@PURE_QUANTA.LCMXO3LF9400C5BG484C(CHIPS)':
 'PB27D': CDS_PINID='PB27D';
NET_NAME
'P3V3_E1S_0_R'
 '@T6G_MB_LIB.T6G(SCH_1):P3V3_E1S_0_R':
 C_SIGNAL='@t6g_mb_lib.t6g(sch_1):p3v3_e1s_0_r',
 CDS_GLOBAL_NET='TRUE';
NODE_NAME     PU293 6_7
 '@T6G_MB_LIB.T6G(SCH_1):PAGE323_I31@PURE_QUANTA.MP5016GQHLZ(CHIPS)':
 'SOURCE': CDS_PINID='SOURCE';
NODE_NAME     PC2204 1
 '@T6G_MB_LIB.T6G(SCH_1):PAGE323_I34@PURE_QUANTA.Q_CAP(CHIPS)':
 'A': CDS_PINID='A';
NODE_NAME     PC2213 1
 '@T6G_MB_LIB.T6G(SCH_1):PAGE324_I46@PURE_QUANTA.Q_CAP(CHIPS)':
 'A': CDS_PINID='A';
NODE_NAME     PR4527 1
 '@T6G_MB_LIB.T6G(SCH_1):PAGE324_I47@PURE_QUANTA.Q_RES(CHIPS)':
 'A': CDS_PINID='A';
NODE_NAME     PD113 C
 '@T6G_MB_LIB.T6G(SCH_1):PAGE324_I50@PURE_QUANTA.SCHOTTKY_AC(CHIPS)':
 'C': CDS_PINID='C';
NODE_NAME     PC2220 1
 '@T6G_MB_LIB.T6G(SCH_1):PAGE324_I58@PURE_QUANTA.Q_CAP(CHIPS)':
 'A': CDS_PINID='A';
NODE_NAME     U276 11
 '@T6G_MB_LIB.T6G(SCH_1):PAGE295_I129@PURE_QUANTA.ISL28022FRZT(CHIPS)':
 'VBUS': CDS_PINID='VBUS';
NODE_NAME     R3758 1
 '@T6G_MB_LIB.T6G(SCH_1):PAGE295_I132@PURE_QUANTA.Q_RES(CHIPS)':
 'A': CDS_PINID='A';
NODE_NAME     C2069 1
 '@T6G_MB_LIB.T6G(SCH_1):PAGE295_I142@PURE_QUANTA.Q_CAP(CHIPS)':
 'A': CDS_PINID='A';
NODE_NAME     R3767 2
 '@T6G_MB_LIB.T6G(SCH_1):PAGE295_I144@PURE_QUANTA.Q_RES(CHIPS)':
 'B': CDS_PINID='B';
NODE_NAME     PC2218 1
 '@T6G_MB_LIB.T6G(SCH_1):PAGE324_I57@PURE_QUANTA.Q_CAP(CHIPS)':
 'A': CDS_PINID='A';
NODE_NAME     PU295 A4
 '@T6G_MB_LIB.T6G(SCH_1):PAGE324_I88@PURE_QUANTA.MAX15090BEWIT(CHIPS)':
 'OUT_A4': CDS_PINID='OUT_A4';
NODE_NAME     PU295 B4
 '@T6G_MB_LIB.T6G(SCH_1):PAGE324_I88@PURE_QUANTA.MAX15090BEWIT(CHIPS)':
 'OUT_B4': CDS_PINID='OUT_B4';
NODE_NAME     PU295 B6
 '@T6G_MB_LIB.T6G(SCH_1):PAGE324_I88@PURE_QUANTA.MAX15090BEWIT(CHIPS)':
 'OUT_B6': CDS_PINID='OUT_B6';
NODE_NAME     PU295 C4
 '@T6G_MB_LIB.T6G(SCH_1):PAGE324_I88@PURE_QUANTA.MAX15090BEWIT(CHIPS)':
 'OUT_C4': CDS_PINID='OUT_C4';
NODE_NAME     PU295 C6
 '@T6G_MB_LIB.T6G(SCH_1):PAGE324_I88@PURE_QUANTA.MAX15090BEWIT(CHIPS)':
 'OUT_C6': CDS_PINID='OUT_C6';
NODE_NAME     PU295 D4
 '@T6G_MB_LIB.T6G(SCH_1):PAGE324_I88@PURE_QUANTA.MAX15090BEWIT(CHIPS)':
 'OUT_D4': CDS_PINID='OUT_D4';
NODE_NAME     PU295 D6
 '@T6G_MB_LIB.T6G(SCH_1):PAGE324_I88@PURE_QUANTA.MAX15090BEWIT(CHIPS)':
 'OUT_D6': CDS_PINID='OUT_D6';
NODE_NAME     C8010 1
 '@T6G_MB_LIB.T6G(SCH_1):PAGE323_I64@PURE_QUANTA.Q_CAP(CHIPS)':
 'A': CDS_PINID='A';
NODE_NAME     U8003 3
 '@T6G_MB_LIB.T6G(SCH_1):PAGE323_I65@PURE_QUANTA.APX80929SAG7(CHIPS)':
 'VCC': CDS_PINID='VCC';
NODE_NAME     R8098 1
 '@T6G_MB_LIB.T6G(SCH_1):PAGE323_I70@PURE_QUANTA.Q_RES(CHIPS)':
 'A': CDS_PINID='A';
NET_NAME
'P3V3_E1S_CB_0'
 '@T6G_MB_LIB.T6G(SCH_1):P3V3_E1S_CB_0':
 C_SIGNAL='@t6g_mb_lib.t6g(sch_1):p3v3_e1s_cb_0';
NODE_NAME     PR3969 1
 '@T6G_MB_LIB.T6G(SCH_1):PAGE324_I39@PURE_QUANTA.Q_RES(CHIPS)':
 'A': CDS_PINID='A';
NODE_NAME     PU295 B1
 '@T6G_MB_LIB.T6G(SCH_1):PAGE324_I88@PURE_QUANTA.MAX15090BEWIT(CHIPS)':
 'CB': CDS_PINID='CB';
NET_NAME
'P3V3_E1S_DVDT_0'
 '@T6G_MB_LIB.T6G(SCH_1):P3V3_E1S_DVDT_0':
 C_SIGNAL='@t6g_mb_lib.t6g(sch_1):p3v3_e1s_dvdt_0';
NODE_NAME     PC2201 1
 '@T6G_MB_LIB.T6G(SCH_1):PAGE323_I30@PURE_QUANTA.Q_CAP(CHIPS)':
 'A': CDS_PINID='A';
NODE_NAME     PU293 10
 '@T6G_MB_LIB.T6G(SCH_1):PAGE323_I31@PURE_QUANTA.MP5016GQHLZ(CHIPS)':
 'DV_DT': CDS_PINID='DV_DT';
NET_NAME
'P3V3_E1S_EN_0_R'
 '@T6G_MB_LIB.T6G(SCH_1):P3V3_E1S_EN_0_R':
 C_SIGNAL='@t6g_mb_lib.t6g(sch_1):p3v3_e1s_en_0_r';
NODE_NAME     R4063 2
 '@T6G_MB_LIB.T6G(SCH_1):PAGE324_I2@PURE_QUANTA.Q_RES(CHIPS)':
 'B': CDS_PINID='B';
NODE_NAME     R6049 1
 '@T6G_MB_LIB.T6G(SCH_1):PAGE324_I4@PURE_QUANTA.Q_RES(CHIPS)':
 'A': CDS_PINID='A';
NODE_NAME     Q126 2
 '@T6G_MB_LIB.T6G(SCH_1):PAGE324_I6@PURE_QUANTA.MOSFET_NCH_DUAL(CHIPS)':
 'G1': CDS_PINID='G1';
NET_NAME
'P3V3_E1S_EN_0_R2'
 '@T6G_MB_LIB.T6G(SCH_1):P3V3_E1S_EN_0_R2':
 C_SIGNAL='@t6g_mb_lib.t6g(sch_1):p3v3_e1s_en_0_r2';
NODE_NAME     R3946 2
 '@T6G_MB_LIB.T6G(SCH_1):PAGE323_I5@PURE_QUANTA.Q_RES(CHIPS)':
 'B': CDS_PINID='B';
NODE_NAME     PU293 9
 '@T6G_MB_LIB.T6G(SCH_1):PAGE323_I31@PURE_QUANTA.MP5016GQHLZ(CHIPS)':
 'EN': CDS_PINID='EN';
NET_NAME
'P3V3_E1S_FAULT_0'
 '@T6G_MB_LIB.T6G(SCH_1):P3V3_E1S_FAULT_0':
 C_SIGNAL='@t6g_mb_lib.t6g(sch_1):p3v3_e1s_fault_0';
NODE_NAME     R3977 2
 '@T6G_MB_LIB.T6G(SCH_1):PAGE324_I52@PURE_QUANTA.Q_RES(CHIPS)':
 'B': CDS_PINID='B';
NODE_NAME     PU295 C7
 '@T6G_MB_LIB.T6G(SCH_1):PAGE324_I88@PURE_QUANTA.MAX15090BEWIT(CHIPS)':
 'FAULT#': CDS_PINID='\fault#\';
NET_NAME
'P3V3_E1S_GATE_0'
 '@T6G_MB_LIB.T6G(SCH_1):P3V3_E1S_GATE_0':
 C_SIGNAL='@t6g_mb_lib.t6g(sch_1):p3v3_e1s_gate_0';
NODE_NAME     PC2213 2
 '@T6G_MB_LIB.T6G(SCH_1):PAGE324_I46@PURE_QUANTA.Q_CAP(CHIPS)':
 'B': CDS_PINID='B';
NODE_NAME     PR4527 2
 '@T6G_MB_LIB.T6G(SCH_1):PAGE324_I47@PURE_QUANTA.Q_RES(CHIPS)':
 'B': CDS_PINID='B';
NODE_NAME     PC2216 1
 '@T6G_MB_LIB.T6G(SCH_1):PAGE324_I49@PURE_QUANTA.Q_CAP(CHIPS)':
 'A': CDS_PINID='A';
NODE_NAME     PU295 A6
 '@T6G_MB_LIB.T6G(SCH_1):PAGE324_I88@PURE_QUANTA.MAX15090BEWIT(CHIPS)':
 'GATE': CDS_PINID='GATE';
NET_NAME
'P3V3_E1S_GATE_0_PU293'
 '@T6G_MB_LIB.T6G(SCH_1):P3V3_E1S_GATE_0_PU293':
 C_SIGNAL='@t6g_mb_lib.t6g(sch_1):p3v3_e1s_gate_0_pu293';
NODE_NAME     PU293 8
 '@T6G_MB_LIB.T6G(SCH_1):PAGE323_I31@PURE_QUANTA.MP5016GQHLZ(CHIPS)':
 'GATE': CDS_PINID='GATE';
NODE_NAME     PC2203 1
 '@T6G_MB_LIB.T6G(SCH_1):PAGE323_I32@PURE_QUANTA.Q_CAP(CHIPS)':
 'A': CDS_PINID='A';
NET_NAME
'P3V3_E1S_ILIMIT_0'
 '@T6G_MB_LIB.T6G(SCH_1):P3V3_E1S_ILIMIT_0':
 C_SIGNAL='@t6g_mb_lib.t6g(sch_1):p3v3_e1s_ilimit_0';
NODE_NAME     PR3947 2
 '@T6G_MB_LIB.T6G(SCH_1):PAGE323_I6@PURE_QUANTA.Q_RES(CHIPS)':
 'B': CDS_PINID='B';
NODE_NAME     PU293 4
 '@T6G_MB_LIB.T6G(SCH_1):PAGE323_I31@PURE_QUANTA.MP5016GQHLZ(CHIPS)':
 'ILIMIT': CDS_PINID='ILIMIT';
NET_NAME
'P3V3_E1S_MODE_0'
 '@T6G_MB_LIB.T6G(SCH_1):P3V3_E1S_MODE_0':
 C_SIGNAL='@t6g_mb_lib.t6g(sch_1):p3v3_e1s_mode_0';
NODE_NAME     PC2197 1
 '@T6G_MB_LIB.T6G(SCH_1):PAGE323_I3@PURE_QUANTA.Q_CAP(CHIPS)':
 'A': CDS_PINID='A';
NODE_NAME     PR3945 1
 '@T6G_MB_LIB.T6G(SCH_1):PAGE323_I4@PURE_QUANTA.Q_RES(CHIPS)':
 'A': CDS_PINID='A';
NODE_NAME     PU293 5
 '@T6G_MB_LIB.T6G(SCH_1):PAGE323_I31@PURE_QUANTA.MP5016GQHLZ(CHIPS)':
 'MODE': CDS_PINID='MODE';
NET_NAME
'P3V3_E1S_OV_0'
 '@T6G_MB_LIB.T6G(SCH_1):P3V3_E1S_OV_0':
 C_SIGNAL='@t6g_mb_lib.t6g(sch_1):p3v3_e1s_ov_0';
NODE_NAME     PR3965 1
 '@T6G_MB_LIB.T6G(SCH_1):PAGE324_I16@PURE_QUANTA.Q_RES(CHIPS)':
 'A': CDS_PINID='A';
NODE_NAME     PR3964 2
 '@T6G_MB_LIB.T6G(SCH_1):PAGE324_I17@PURE_QUANTA.Q_RES(CHIPS)':
 'B': CDS_PINID='B';
NODE_NAME     PU295 D3
 '@T6G_MB_LIB.T6G(SCH_1):PAGE324_I88@PURE_QUANTA.MAX15090BEWIT(CHIPS)':
 'OV': CDS_PINID='OV';
NET_NAME
'P3V3_E1S_PWRGD_0'
 '@T6G_MB_LIB.T6G(SCH_1):P3V3_E1S_PWRGD_0':
 C_SIGNAL='@t6g_mb_lib.t6g(sch_1):p3v3_e1s_pwrgd_0';
NODE_NAME     R3973 1
 '@T6G_MB_LIB.T6G(SCH_1):PAGE324_I48@PURE_QUANTA.Q_RES(CHIPS)':
 'A': CDS_PINID='A';
NODE_NAME     PU295 D7
 '@T6G_MB_LIB.T6G(SCH_1):PAGE324_I88@PURE_QUANTA.MAX15090BEWIT(CHIPS)':
 'PG': CDS_PINID='PG';
NET_NAME
'P3V3_E1S_PWRGD_0_R'
 '@T6G_MB_LIB.T6G(SCH_1):P3V3_E1S_PWRGD_0_R':
 C_SIGNAL='@t6g_mb_lib.t6g(sch_1):p3v3_e1s_pwrgd_0_r';
NODE_NAME     R3973 2
 '@T6G_MB_LIB.T6G(SCH_1):PAGE324_I48@PURE_QUANTA.Q_RES(CHIPS)':
 'B': CDS_PINID='B';
NODE_NAME     R3979 2
 '@T6G_MB_LIB.T6G(SCH_1):PAGE324_I54@PURE_QUANTA.Q_RES(CHIPS)':
 'B': CDS_PINID='B';
NODE_NAME     U18 U11
 '@T6G_MB_LIB.T6G(SCH_1):PAGE80_I216@PURE_QUANTA.LCMXO3LF9400C5BG484C(CHIPS)':
 'PB22D': CDS_PINID='PB22D';
NODE_NAME     R8100 2
 '@T6G_MB_LIB.T6G(SCH_1):PAGE323_I71@PURE_QUANTA.Q_RES(CHIPS)':
 'B': CDS_PINID='B';
NET_NAME
'P3V3_E1S_PWRGD_0_R1'
 '@T6G_MB_LIB.T6G(SCH_1):P3V3_E1S_PWRGD_0_R1':
 C_SIGNAL='@t6g_mb_lib.t6g(sch_1):p3v3_e1s_pwrgd_0_r1';
NODE_NAME     U8003 2
 '@T6G_MB_LIB.T6G(SCH_1):PAGE323_I65@PURE_QUANTA.APX80929SAG7(CHIPS)':
 'RESET_L': CDS_PINID='RESET_L';
NODE_NAME     R8099 1
 '@T6G_MB_LIB.T6G(SCH_1):PAGE323_I68@PURE_QUANTA.Q_RES(CHIPS)':
 'A': CDS_PINID='A';
NODE_NAME     R8098 2
 '@T6G_MB_LIB.T6G(SCH_1):PAGE323_I70@PURE_QUANTA.Q_RES(CHIPS)':
 'B': CDS_PINID='B';
NODE_NAME     R8100 1
 '@T6G_MB_LIB.T6G(SCH_1):PAGE323_I71@PURE_QUANTA.Q_RES(CHIPS)':
 'A': CDS_PINID='A';
NET_NAME
'P3V3_E1S_REG_0'
 '@T6G_MB_LIB.T6G(SCH_1):P3V3_E1S_REG_0':
 C_SIGNAL='@t6g_mb_lib.t6g(sch_1):p3v3_e1s_reg_0';
NODE_NAME     PC2212 2
 '@T6G_MB_LIB.T6G(SCH_1):PAGE324_I42@PURE_QUANTA.Q_CAP(CHIPS)':
 'B': CDS_PINID='B';
NODE_NAME     PU295 D1
 '@T6G_MB_LIB.T6G(SCH_1):PAGE324_I88@PURE_QUANTA.MAX15090BEWIT(CHIPS)':
 'REG': CDS_PINID='REG';
NET_NAME
'P3V3_E1S_SENSE_0'
 '@T6G_MB_LIB.T6G(SCH_1):P3V3_E1S_SENSE_0':
 C_SIGNAL='@t6g_mb_lib.t6g(sch_1):p3v3_e1s_sense_0';
NODE_NAME     PR3971 1
 '@T6G_MB_LIB.T6G(SCH_1):PAGE324_I45@PURE_QUANTA.Q_RES(CHIPS)':
 'A': CDS_PINID='A';
NODE_NAME     PU295 A1
 '@T6G_MB_LIB.T6G(SCH_1):PAGE324_I88@PURE_QUANTA.MAX15090BEWIT(CHIPS)':
 'ISENSE': CDS_PINID='ISENSE';
NET_NAME
'P3V3_E1S_UV_0'
 '@T6G_MB_LIB.T6G(SCH_1):P3V3_E1S_UV_0':
 C_SIGNAL='@t6g_mb_lib.t6g(sch_1):p3v3_e1s_uv_0';
NODE_NAME     PR3964 1
 '@T6G_MB_LIB.T6G(SCH_1):PAGE324_I17@PURE_QUANTA.Q_RES(CHIPS)':
 'A': CDS_PINID='A';
NODE_NAME     PR3963 2
 '@T6G_MB_LIB.T6G(SCH_1):PAGE324_I21@PURE_QUANTA.Q_RES(CHIPS)':
 'B': CDS_PINID='B';
NODE_NAME     R3959 2
 '@T6G_MB_LIB.T6G(SCH_1):PAGE324_I18@PURE_QUANTA.Q_RES(CHIPS)':
 'B': CDS_PINID='B';
NODE_NAME     PU295 D2
 '@T6G_MB_LIB.T6G(SCH_1):PAGE324_I88@PURE_QUANTA.MAX15090BEWIT(CHIPS)':
 'UV': CDS_PINID='UV';
NET_NAME
'P3V3_E1S_UV_0_R'
 '@T6G_MB_LIB.T6G(SCH_1):P3V3_E1S_UV_0_R':
 C_SIGNAL='@t6g_mb_lib.t6g(sch_1):p3v3_e1s_uv_0_r';
NODE_NAME     Q126 3
 '@T6G_MB_LIB.T6G(SCH_1):PAGE324_I7@PURE_QUANTA.MOSFET_NCH_DUAL(CHIPS)':
 'D2': CDS_PINID='D2';
NODE_NAME     R3959 1
 '@T6G_MB_LIB.T6G(SCH_1):PAGE324_I18@PURE_QUANTA.Q_RES(CHIPS)':
 'A': CDS_PINID='A';
NET_NAME
'P3V3_E1S_VCC_0'
 '@T6G_MB_LIB.T6G(SCH_1):P3V3_E1S_VCC_0':
 C_SIGNAL='@t6g_mb_lib.t6g(sch_1):p3v3_e1s_vcc_0';
NODE_NAME     PC2210 1
 '@T6G_MB_LIB.T6G(SCH_1):PAGE324_I41@PURE_QUANTA.Q_CAP(CHIPS)':
 'A': CDS_PINID='A';
NODE_NAME     PR3967 2
 '@T6G_MB_LIB.T6G(SCH_1):PAGE324_I43@PURE_QUANTA.Q_RES(CHIPS)':
 'B': CDS_PINID='B';
NODE_NAME     PU295 A2
 '@T6G_MB_LIB.T6G(SCH_1):PAGE324_I88@PURE_QUANTA.MAX15090BEWIT(CHIPS)':
 'VCC': CDS_PINID='VCC';
NET_NAME
'P3V3_M2_0'
 '@T6G_MB_LIB.T6G(SCH_1):P3V3_M2_0':
 C_SIGNAL='@t6g_mb_lib.t6g(sch_1):p3v3_m2_0',
 CDS_GLOBAL_NET='TRUE';
NODE_NAME     J59 2
 '@T6G_MB_LIB.T6G(SCH_1):PAGE345_I88@PURE_QUANTA.SCONN75K_APCI0155P004A(CHIPS)':
 '3.3V_1': CDS_PINID='\3.3v_1\';
NODE_NAME     J59 4
 '@T6G_MB_LIB.T6G(SCH_1):PAGE345_I88@PURE_QUANTA.SCONN75K_APCI0155P004A(CHIPS)':
 '3.3V_2': CDS_PINID='\3.3v_2\';
NODE_NAME     J59 12
 '@T6G_MB_LIB.T6G(SCH_1):PAGE345_I88@PURE_QUANTA.SCONN75K_APCI0155P004A(CHIPS)':
 '3.3V_3': CDS_PINID='\3.3v_3\';
NODE_NAME     J59 14
 '@T6G_MB_LIB.T6G(SCH_1):PAGE345_I88@PURE_QUANTA.SCONN75K_APCI0155P004A(CHIPS)':
 '3.3V_4': CDS_PINID='\3.3v_4\';
NODE_NAME     J59 16
 '@T6G_MB_LIB.T6G(SCH_1):PAGE345_I88@PURE_QUANTA.SCONN75K_APCI0155P004A(CHIPS)':
 '3.3V_5': CDS_PINID='\3.3v_5\';
NODE_NAME     J59 18
 '@T6G_MB_LIB.T6G(SCH_1):PAGE345_I88@PURE_QUANTA.SCONN75K_APCI0155P004A(CHIPS)':
 '3.3V_6': CDS_PINID='\3.3v_6\';
NODE_NAME     J59 70
 '@T6G_MB_LIB.T6G(SCH_1):PAGE345_I88@PURE_QUANTA.SCONN75K_APCI0155P004A(CHIPS)':
 '3.3V_7': CDS_PINID='\3.3v_7\';
NODE_NAME     J59 72
 '@T6G_MB_LIB.T6G(SCH_1):PAGE345_I88@PURE_QUANTA.SCONN75K_APCI0155P004A(CHIPS)':
 '3.3V_8': CDS_PINID='\3.3v_8\';
NODE_NAME     J59 74
 '@T6G_MB_LIB.T6G(SCH_1):PAGE345_I88@PURE_QUANTA.SCONN75K_APCI0155P004A(CHIPS)':
 '3.3V_9': CDS_PINID='\3.3v_9\';
NODE_NAME     R3575 1
 '@T6G_MB_LIB.T6G(SCH_1):PAGE360_I33@PURE_QUANTA.Q_RES(CHIPS)':
 'A': CDS_PINID='A';
NODE_NAME     R3634 1
 '@T6G_MB_LIB.T6G(SCH_1):PAGE360_I92@PURE_QUANTA.Q_RES(CHIPS)':
 'A': CDS_PINID='A';
NODE_NAME     R3295 1
 '@T6G_MB_LIB.T6G(SCH_1):PAGE345_I21@PURE_QUANTA.Q_RES(CHIPS)':
 'A': CDS_PINID='A';
NODE_NAME     C1920 1
 '@T6G_MB_LIB.T6G(SCH_1):PAGE345_I77@PURE_QUANTA.Q_CAP(CHIPS)':
 'A': CDS_PINID='A';
NODE_NAME     C1921 1
 '@T6G_MB_LIB.T6G(SCH_1):PAGE345_I78@PURE_QUANTA.Q_CAP(CHIPS)':
 'A': CDS_PINID='A';
NODE_NAME     C9922 1
 '@T6G_MB_LIB.T6G(SCH_1):PAGE345_I79@PURE_QUANTA.Q_CAP(CHIPS)':
 'A': CDS_PINID='A';
NODE_NAME     C1923 1
 '@T6G_MB_LIB.T6G(SCH_1):PAGE345_I84@PURE_QUANTA.Q_CAP(CHIPS)':
 'A': CDS_PINID='A';
NODE_NAME     C1924 1
 '@T6G_MB_LIB.T6G(SCH_1):PAGE345_I85@PURE_QUANTA.Q_CAP(CHIPS)':
 'A': CDS_PINID='A';
NODE_NAME     C1925 1
 '@T6G_MB_LIB.T6G(SCH_1):PAGE345_I86@PURE_QUANTA.Q_CAP(CHIPS)':
 'A': CDS_PINID='A';
NET_NAME
'P3V3_MAX11617_2_VDD'
 '@T6G_MB_LIB.T6G(SCH_1):P3V3_MAX11617_2_VDD':
 C_SIGNAL='@t6g_mb_lib.t6g(sch_1):p3v3_max11617_2_vdd';
NODE_NAME     U50 16
 '@T6G_MB_LIB.T6G(SCH_1):PAGE263_I156@PURE_QUANTA.MAX11617EEET(CHIPS)':
 'VDD': CDS_PINID='VDD';
NODE_NAME     C1075 1
 '@T6G_MB_LIB.T6G(SCH_1):PAGE263_I165@PURE_QUANTA.Q_CAP(CHIPS)':
 'A': CDS_PINID='A';
NODE_NAME     C1077 1
 '@T6G_MB_LIB.T6G(SCH_1):PAGE263_I166@PURE_QUANTA.Q_CAP(CHIPS)':
 'A': CDS_PINID='A';
NODE_NAME     L24 1
 '@T6G_MB_LIB.T6G(SCH_1):PAGE263_I168@PURE_QUANTA.Q_INDUCTOR(CHIPS)':
 '1': CDS_PINID='\1\';
NET_NAME
'P3V3_MAX11617_VDD'
 '@T6G_MB_LIB.T6G(SCH_1):P3V3_MAX11617_VDD':
 C_SIGNAL='@t6g_mb_lib.t6g(sch_1):p3v3_max11617_vdd';
NODE_NAME     C1757 1
 '@T6G_MB_LIB.T6G(SCH_1):PAGE369_I162@PURE_QUANTA.Q_CAP(CHIPS)':
 'A': CDS_PINID='A';
NODE_NAME     C1768 1
 '@T6G_MB_LIB.T6G(SCH_1):PAGE369_I166@PURE_QUANTA.Q_CAP(CHIPS)':
 'A': CDS_PINID='A';
NODE_NAME     L15 1
 '@T6G_MB_LIB.T6G(SCH_1):PAGE369_I167@PURE_QUANTA.Q_INDUCTOR(CHIPS)':
 '1': CDS_PINID='\1\';
NODE_NAME     U193 16
 '@T6G_MB_LIB.T6G(SCH_1):PAGE369_I169@PURE_QUANTA.MAX11617EEET(CHIPS)':
 'VDD': CDS_PINID='VDD';
NET_NAME
'P3V3_OCP_1_EN_G'
 '@T6G_MB_LIB.T6G(SCH_1):P3V3_OCP_1_EN_G':
 C_SIGNAL='@t6g_mb_lib.t6g(sch_1):p3v3_ocp_1_en_g';
NODE_NAME     Q124 6
 '@T6G_MB_LIB.T6G(SCH_1):PAGE338_I23@PURE_QUANTA.MOSFET_NCH_DUAL(CHIPS)':
 'D1': CDS_PINID='D1';
NODE_NAME     R4070 2
 '@T6G_MB_LIB.T6G(SCH_1):PAGE338_I59@PURE_QUANTA.Q_RES(CHIPS)':
 'B': CDS_PINID='B';
NODE_NAME     Q124 5
 '@T6G_MB_LIB.T6G(SCH_1):PAGE338_I112@PURE_QUANTA.MOSFET_NCH_DUAL(CHIPS)':
 'G2': CDS_PINID='G2';
NET_NAME
'P3V3_OCP_2_EN_G'
 '@T6G_MB_LIB.T6G(SCH_1):P3V3_OCP_2_EN_G':
 C_SIGNAL='@t6g_mb_lib.t6g(sch_1):p3v3_ocp_2_en_g';
NODE_NAME     Q119 6
 '@T6G_MB_LIB.T6G(SCH_1):PAGE343_I42@PURE_QUANTA.MOSFET_NCH_DUAL(CHIPS)':
 'D1': CDS_PINID='D1';
NODE_NAME     R4067 2
 '@T6G_MB_LIB.T6G(SCH_1):PAGE343_I43@PURE_QUANTA.Q_RES(CHIPS)':
 'B': CDS_PINID='B';
NODE_NAME     Q119 5
 '@T6G_MB_LIB.T6G(SCH_1):PAGE343_I45@PURE_QUANTA.MOSFET_NCH_DUAL(CHIPS)':
 'G2': CDS_PINID='G2';
NET_NAME
'P3V3_OCP_CB_1'
 '@T6G_MB_LIB.T6G(SCH_1):P3V3_OCP_CB_1':
 C_SIGNAL='@t6g_mb_lib.t6g(sch_1):p3v3_ocp_cb_1';
NODE_NAME     PR3780 1
 '@T6G_MB_LIB.T6G(SCH_1):PAGE338_I111@PURE_QUANTA.Q_RES(CHIPS)':
 'A': CDS_PINID='A';
NODE_NAME     PU202 B1
 '@T6G_MB_LIB.T6G(SCH_1):PAGE338_I113@PURE_QUANTA.MAX15090BEWIT(CHIPS)':
 'CB': CDS_PINID='CB';
NET_NAME
'P3V3_OCP_CB_2'
 '@T6G_MB_LIB.T6G(SCH_1):P3V3_OCP_CB_2':
 C_SIGNAL='@t6g_mb_lib.t6g(sch_1):p3v3_ocp_cb_2';
NODE_NAME     PR3822 1
 '@T6G_MB_LIB.T6G(SCH_1):PAGE343_I88@PURE_QUANTA.Q_RES(CHIPS)':
 'A': CDS_PINID='A';
NODE_NAME     PU200 B1
 '@T6G_MB_LIB.T6G(SCH_1):PAGE343_I89@PURE_QUANTA.MAX15090BEWIT(CHIPS)':
 'CB': CDS_PINID='CB';
NET_NAME
'P3V3_OCP_DVDT_1'
 '@T6G_MB_LIB.T6G(SCH_1):P3V3_OCP_DVDT_1':
 C_SIGNAL='@t6g_mb_lib.t6g(sch_1):p3v3_ocp_dvdt_1';
NODE_NAME     PC2161 1
 '@T6G_MB_LIB.T6G(SCH_1):PAGE339_I104@PURE_QUANTA.Q_CAP(CHIPS)':
 'A': CDS_PINID='A';
NODE_NAME     PU205 10
 '@T6G_MB_LIB.T6G(SCH_1):PAGE339_I113@PURE_QUANTA.MP5016GQHLZ(CHIPS)':
 'DV_DT': CDS_PINID='DV_DT';
NET_NAME
'P3V3_OCP_DVDT_2'
 '@T6G_MB_LIB.T6G(SCH_1):P3V3_OCP_DVDT_2':
 C_SIGNAL='@t6g_mb_lib.t6g(sch_1):p3v3_ocp_dvdt_2';
NODE_NAME     PC1321 1
 '@T6G_MB_LIB.T6G(SCH_1):PAGE344_I50@PURE_QUANTA.Q_CAP(CHIPS)':
 'A': CDS_PINID='A';
NODE_NAME     PU207 10
 '@T6G_MB_LIB.T6G(SCH_1):PAGE344_I51@PURE_QUANTA.MP5016GQHLZ(CHIPS)':
 'DV_DT': CDS_PINID='DV_DT';
NET_NAME
'P3V3_OCP_EN_1_R'
 '@T6G_MB_LIB.T6G(SCH_1):P3V3_OCP_EN_1_R':
 C_SIGNAL='@t6g_mb_lib.t6g(sch_1):p3v3_ocp_en_1_r';
NODE_NAME     Q124 2
 '@T6G_MB_LIB.T6G(SCH_1):PAGE338_I23@PURE_QUANTA.MOSFET_NCH_DUAL(CHIPS)':
 'G1': CDS_PINID='G1';
NODE_NAME     R5487 2
 '@T6G_MB_LIB.T6G(SCH_1):PAGE338_I126@PURE_QUANTA.Q_RES(CHIPS)':
 'B': CDS_PINID='B';
NODE_NAME     R4069 1
 '@T6G_MB_LIB.T6G(SCH_1):PAGE338_I127@PURE_QUANTA.Q_RES(CHIPS)':
 'A': CDS_PINID='A';
NODE_NAME     R1136 2
 '@T6G_MB_LIB.T6G(SCH_1):PAGE338_I133@PURE_QUANTA.Q_RES(CHIPS)':
 'B': CDS_PINID='B';
NODE_NAME     R1486 2
 '@T6G_MB_LIB.T6G(SCH_1):PAGE338_I135@PURE_QUANTA.Q_RES(CHIPS)':
 'B': CDS_PINID='B';
NET_NAME
'P3V3_OCP_EN_1_R2'
 '@T6G_MB_LIB.T6G(SCH_1):P3V3_OCP_EN_1_R2':
 C_SIGNAL='@t6g_mb_lib.t6g(sch_1):p3v3_ocp_en_1_r2';
NODE_NAME     PU205 9
 '@T6G_MB_LIB.T6G(SCH_1):PAGE339_I113@PURE_QUANTA.MP5016GQHLZ(CHIPS)':
 'EN': CDS_PINID='EN';
NODE_NAME     R3845 2
 '@T6G_MB_LIB.T6G(SCH_1):PAGE339_I131@PURE_QUANTA.Q_RES(CHIPS)':
 'B': CDS_PINID='B';
NODE_NAME     R1487 2
 '@T6G_MB_LIB.T6G(SCH_1):PAGE339_I134@PURE_QUANTA.Q_RES(CHIPS)':
 'B': CDS_PINID='B';
NODE_NAME     R1137 2
 '@T6G_MB_LIB.T6G(SCH_1):PAGE339_I135@PURE_QUANTA.Q_RES(CHIPS)':
 'B': CDS_PINID='B';
NET_NAME
'P3V3_OCP_EN_2'
 '@T6G_MB_LIB.T6G(SCH_1):P3V3_OCP_EN_2':
 C_SIGNAL='@t6g_mb_lib.t6g(sch_1):p3v3_ocp_en_2';
NODE_NAME     PU207 9
 '@T6G_MB_LIB.T6G(SCH_1):PAGE344_I51@PURE_QUANTA.MP5016GQHLZ(CHIPS)':
 'EN': CDS_PINID='EN';
NODE_NAME     R3631 2
 '@T6G_MB_LIB.T6G(SCH_1):PAGE344_I74@PURE_QUANTA.Q_RES(CHIPS)':
 'B': CDS_PINID='B';
NODE_NAME     R1196 2
 '@T6G_MB_LIB.T6G(SCH_1):PAGE344_I79@PURE_QUANTA.Q_RES(CHIPS)':
 'B': CDS_PINID='B';
NODE_NAME     R1521 2
 '@T6G_MB_LIB.T6G(SCH_1):PAGE344_I80@PURE_QUANTA.Q_RES(CHIPS)':
 'B': CDS_PINID='B';
NET_NAME
'P3V3_OCP_EN_2_R'
 '@T6G_MB_LIB.T6G(SCH_1):P3V3_OCP_EN_2_R':
 C_SIGNAL='@t6g_mb_lib.t6g(sch_1):p3v3_ocp_en_2_r';
NODE_NAME     Q119 2
 '@T6G_MB_LIB.T6G(SCH_1):PAGE343_I42@PURE_QUANTA.MOSFET_NCH_DUAL(CHIPS)':
 'G1': CDS_PINID='G1';
NODE_NAME     R4066 1
 '@T6G_MB_LIB.T6G(SCH_1):PAGE343_I121@PURE_QUANTA.Q_RES(CHIPS)':
 'A': CDS_PINID='A';
NODE_NAME     R4060 2
 '@T6G_MB_LIB.T6G(SCH_1):PAGE343_I122@PURE_QUANTA.Q_RES(CHIPS)':
 'B': CDS_PINID='B';
NODE_NAME     R1182 2
 '@T6G_MB_LIB.T6G(SCH_1):PAGE343_I129@PURE_QUANTA.Q_RES(CHIPS)':
 'B': CDS_PINID='B';
NODE_NAME     R1520 2
 '@T6G_MB_LIB.T6G(SCH_1):PAGE343_I130@PURE_QUANTA.Q_RES(CHIPS)':
 'B': CDS_PINID='B';
NET_NAME
'P3V3_OCP_FAULT_1'
 '@T6G_MB_LIB.T6G(SCH_1):P3V3_OCP_FAULT_1':
 C_SIGNAL='@t6g_mb_lib.t6g(sch_1):p3v3_ocp_fault_1';
NODE_NAME     R3796 2
 '@T6G_MB_LIB.T6G(SCH_1):PAGE338_I101@PURE_QUANTA.Q_RES(CHIPS)':
 'B': CDS_PINID='B';
NODE_NAME     PU202 C7
 '@T6G_MB_LIB.T6G(SCH_1):PAGE338_I113@PURE_QUANTA.MAX15090BEWIT(CHIPS)':
 'FAULT#': CDS_PINID='\fault#\';
NET_NAME
'P3V3_OCP_FAULT_2'
 '@T6G_MB_LIB.T6G(SCH_1):P3V3_OCP_FAULT_2':
 C_SIGNAL='@t6g_mb_lib.t6g(sch_1):p3v3_ocp_fault_2';
NODE_NAME     PU200 C7
 '@T6G_MB_LIB.T6G(SCH_1):PAGE343_I89@PURE_QUANTA.MAX15090BEWIT(CHIPS)':
 'FAULT#': CDS_PINID='\fault#\';
NODE_NAME     R3833 2
 '@T6G_MB_LIB.T6G(SCH_1):PAGE343_I107@PURE_QUANTA.Q_RES(CHIPS)':
 'B': CDS_PINID='B';
NET_NAME
'P3V3_OCP_GATE_1'
 '@T6G_MB_LIB.T6G(SCH_1):P3V3_OCP_GATE_1':
 C_SIGNAL='@t6g_mb_lib.t6g(sch_1):p3v3_ocp_gate_1';
NODE_NAME     PC2162 1
 '@T6G_MB_LIB.T6G(SCH_1):PAGE339_I106@PURE_QUANTA.Q_CAP(CHIPS)':
 'A': CDS_PINID='A';
NODE_NAME     PU205 8
 '@T6G_MB_LIB.T6G(SCH_1):PAGE339_I113@PURE_QUANTA.MP5016GQHLZ(CHIPS)':
 'GATE': CDS_PINID='GATE';
NET_NAME
'P3V3_OCP_GATE_2'
 '@T6G_MB_LIB.T6G(SCH_1):P3V3_OCP_GATE_2':
 C_SIGNAL='@t6g_mb_lib.t6g(sch_1):p3v3_ocp_gate_2';
NODE_NAME     PU200 A6
 '@T6G_MB_LIB.T6G(SCH_1):PAGE343_I89@PURE_QUANTA.MAX15090BEWIT(CHIPS)':
 'GATE': CDS_PINID='GATE';
NODE_NAME     PR4523 2
 '@T6G_MB_LIB.T6G(SCH_1):PAGE343_I105@PURE_QUANTA.Q_RES(CHIPS)':
 'B': CDS_PINID='B';
NODE_NAME     PC2151 1
 '@T6G_MB_LIB.T6G(SCH_1):PAGE343_I95@PURE_QUANTA.Q_CAP(CHIPS)':
 'A': CDS_PINID='A';
NODE_NAME     PC2149 2
 '@T6G_MB_LIB.T6G(SCH_1):PAGE343_I104@PURE_QUANTA.Q_CAP(CHIPS)':
 'B': CDS_PINID='B';
NET_NAME
'P3V3_OCP_GATE_PU202_1'
 '@T6G_MB_LIB.T6G(SCH_1):P3V3_OCP_GATE_PU202_1':
 C_SIGNAL='@t6g_mb_lib.t6g(sch_1):p3v3_ocp_gate_pu202_1';
NODE_NAME     PC2144 2
 '@T6G_MB_LIB.T6G(SCH_1):PAGE338_I94@PURE_QUANTA.Q_CAP(CHIPS)':
 'B': CDS_PINID='B';
NODE_NAME     PR4525 2
 '@T6G_MB_LIB.T6G(SCH_1):PAGE338_I96@PURE_QUANTA.Q_RES(CHIPS)':
 'B': CDS_PINID='B';
NODE_NAME     PC2089 1
 '@T6G_MB_LIB.T6G(SCH_1):PAGE338_I100@PURE_QUANTA.Q_CAP(CHIPS)':
 'A': CDS_PINID='A';
NODE_NAME     PU202 A6
 '@T6G_MB_LIB.T6G(SCH_1):PAGE338_I113@PURE_QUANTA.MAX15090BEWIT(CHIPS)':
 'GATE': CDS_PINID='GATE';
NET_NAME
'P3V3_OCP_GATE_PU207_2'
 '@T6G_MB_LIB.T6G(SCH_1):P3V3_OCP_GATE_PU207_2':
 C_SIGNAL='@t6g_mb_lib.t6g(sch_1):p3v3_ocp_gate_pu207_2';
NODE_NAME     PU207 8
 '@T6G_MB_LIB.T6G(SCH_1):PAGE344_I51@PURE_QUANTA.MP5016GQHLZ(CHIPS)':
 'GATE': CDS_PINID='GATE';
NODE_NAME     PC1322 1
 '@T6G_MB_LIB.T6G(SCH_1):PAGE344_I54@PURE_QUANTA.Q_CAP(CHIPS)':
 'A': CDS_PINID='A';
NET_NAME
'P3V3_OCP_ILIMIT_1'
 '@T6G_MB_LIB.T6G(SCH_1):P3V3_OCP_ILIMIT_1':
 C_SIGNAL='@t6g_mb_lib.t6g(sch_1):p3v3_ocp_ilimit_1';
NODE_NAME     PR3846 2
 '@T6G_MB_LIB.T6G(SCH_1):PAGE339_I102@PURE_QUANTA.Q_RES(CHIPS)':
 'B': CDS_PINID='B';
NODE_NAME     PU205 4
 '@T6G_MB_LIB.T6G(SCH_1):PAGE339_I113@PURE_QUANTA.MP5016GQHLZ(CHIPS)':
 'ILIMIT': CDS_PINID='ILIMIT';
NET_NAME
'P3V3_OCP_ILIMIT_2'
 '@T6G_MB_LIB.T6G(SCH_1):P3V3_OCP_ILIMIT_2':
 C_SIGNAL='@t6g_mb_lib.t6g(sch_1):p3v3_ocp_ilimit_2';
NODE_NAME     PR3856 2
 '@T6G_MB_LIB.T6G(SCH_1):PAGE344_I46@PURE_QUANTA.Q_RES(CHIPS)':
 'B': CDS_PINID='B';
NODE_NAME     PU207 4
 '@T6G_MB_LIB.T6G(SCH_1):PAGE344_I51@PURE_QUANTA.MP5016GQHLZ(CHIPS)':
 'ILIMIT': CDS_PINID='ILIMIT';
NET_NAME
'P3V3_OCP_MODE_1'
 '@T6G_MB_LIB.T6G(SCH_1):P3V3_OCP_MODE_1':
 C_SIGNAL='@t6g_mb_lib.t6g(sch_1):p3v3_ocp_mode_1';
NODE_NAME     PC2157 1
 '@T6G_MB_LIB.T6G(SCH_1):PAGE339_I98@PURE_QUANTA.Q_CAP(CHIPS)':
 'A': CDS_PINID='A';
NODE_NAME     PR3844 1
 '@T6G_MB_LIB.T6G(SCH_1):PAGE339_I100@PURE_QUANTA.Q_RES(CHIPS)':
 'A': CDS_PINID='A';
NODE_NAME     PU205 5
 '@T6G_MB_LIB.T6G(SCH_1):PAGE339_I113@PURE_QUANTA.MP5016GQHLZ(CHIPS)':
 'MODE': CDS_PINID='MODE';
NET_NAME
'P3V3_OCP_MODE_2'
 '@T6G_MB_LIB.T6G(SCH_1):P3V3_OCP_MODE_2':
 C_SIGNAL='@t6g_mb_lib.t6g(sch_1):p3v3_ocp_mode_2';
NODE_NAME     PC2168 1
 '@T6G_MB_LIB.T6G(SCH_1):PAGE344_I35@PURE_QUANTA.Q_CAP(CHIPS)':
 'A': CDS_PINID='A';
NODE_NAME     PR3855 1
 '@T6G_MB_LIB.T6G(SCH_1):PAGE344_I43@PURE_QUANTA.Q_RES(CHIPS)':
 'A': CDS_PINID='A';
NODE_NAME     PU207 5
 '@T6G_MB_LIB.T6G(SCH_1):PAGE344_I51@PURE_QUANTA.MP5016GQHLZ(CHIPS)':
 'MODE': CDS_PINID='MODE';
NET_NAME
'P3V3_OCP_OV_1'
 '@T6G_MB_LIB.T6G(SCH_1):P3V3_OCP_OV_1':
 C_SIGNAL='@t6g_mb_lib.t6g(sch_1):p3v3_ocp_ov_1';
NODE_NAME     PR3790 2
 '@T6G_MB_LIB.T6G(SCH_1):PAGE338_I64@PURE_QUANTA.Q_RES(CHIPS)':
 'B': CDS_PINID='B';
NODE_NAME     PU202 D3
 '@T6G_MB_LIB.T6G(SCH_1):PAGE338_I113@PURE_QUANTA.MAX15090BEWIT(CHIPS)':
 'OV': CDS_PINID='OV';
NODE_NAME     PR3791 1
 '@T6G_MB_LIB.T6G(SCH_1):PAGE338_I114@PURE_QUANTA.Q_RES(CHIPS)':
 'A': CDS_PINID='A';
NET_NAME
'P3V3_OCP_OV_2'
 '@T6G_MB_LIB.T6G(SCH_1):P3V3_OCP_OV_2':
 C_SIGNAL='@t6g_mb_lib.t6g(sch_1):p3v3_ocp_ov_2';
NODE_NAME     PR3812 1
 '@T6G_MB_LIB.T6G(SCH_1):PAGE343_I51@PURE_QUANTA.Q_RES(CHIPS)':
 'A': CDS_PINID='A';
NODE_NAME     PU200 D3
 '@T6G_MB_LIB.T6G(SCH_1):PAGE343_I89@PURE_QUANTA.MAX15090BEWIT(CHIPS)':
 'OV': CDS_PINID='OV';
NODE_NAME     PR3829 2
 '@T6G_MB_LIB.T6G(SCH_1):PAGE343_I53@PURE_QUANTA.Q_RES(CHIPS)':
 'B': CDS_PINID='B';
NET_NAME
'P3V3_OCP_PWRGD_1'
 '@T6G_MB_LIB.T6G(SCH_1):P3V3_OCP_PWRGD_1':
 C_SIGNAL='@t6g_mb_lib.t6g(sch_1):p3v3_ocp_pwrgd_1';
NODE_NAME     PU202 D7
 '@T6G_MB_LIB.T6G(SCH_1):PAGE338_I113@PURE_QUANTA.MAX15090BEWIT(CHIPS)':
 'PG': CDS_PINID='PG';
NODE_NAME     R3794 1
 '@T6G_MB_LIB.T6G(SCH_1):PAGE338_I132@PURE_QUANTA.Q_RES(CHIPS)':
 'A': CDS_PINID='A';
NET_NAME
'P3V3_OCP_PWRGD_2'
 '@T6G_MB_LIB.T6G(SCH_1):P3V3_OCP_PWRGD_2':
 C_SIGNAL='@t6g_mb_lib.t6g(sch_1):p3v3_ocp_pwrgd_2';
NODE_NAME     PU200 D7
 '@T6G_MB_LIB.T6G(SCH_1):PAGE343_I89@PURE_QUANTA.MAX15090BEWIT(CHIPS)':
 'PG': CDS_PINID='PG';
NODE_NAME     R3832 1
 '@T6G_MB_LIB.T6G(SCH_1):PAGE343_I127@PURE_QUANTA.Q_RES(CHIPS)':
 'A': CDS_PINID='A';
NET_NAME
'P3V3_OCP_REG_1'
 '@T6G_MB_LIB.T6G(SCH_1):P3V3_OCP_REG_1':
 C_SIGNAL='@t6g_mb_lib.t6g(sch_1):p3v3_ocp_reg_1';
NODE_NAME     PC2093 2
 '@T6G_MB_LIB.T6G(SCH_1):PAGE338_I67@PURE_QUANTA.Q_CAP(CHIPS)':
 'B': CDS_PINID='B';
NODE_NAME     PU202 D1
 '@T6G_MB_LIB.T6G(SCH_1):PAGE338_I113@PURE_QUANTA.MAX15090BEWIT(CHIPS)':
 'REG': CDS_PINID='REG';
NET_NAME
'P3V3_OCP_REG_2'
 '@T6G_MB_LIB.T6G(SCH_1):P3V3_OCP_REG_2':
 C_SIGNAL='@t6g_mb_lib.t6g(sch_1):p3v3_ocp_reg_2';
NODE_NAME     PC2147 2
 '@T6G_MB_LIB.T6G(SCH_1):PAGE343_I86@PURE_QUANTA.Q_CAP(CHIPS)':
 'B': CDS_PINID='B';
NODE_NAME     PU200 D1
 '@T6G_MB_LIB.T6G(SCH_1):PAGE343_I89@PURE_QUANTA.MAX15090BEWIT(CHIPS)':
 'REG': CDS_PINID='REG';
NET_NAME
'P3V3_OCP_SENSE_1'
 '@T6G_MB_LIB.T6G(SCH_1):P3V3_OCP_SENSE_1':
 C_SIGNAL='@t6g_mb_lib.t6g(sch_1):p3v3_ocp_sense_1';
NODE_NAME     PR5481 1
 '@T6G_MB_LIB.T6G(SCH_1):PAGE338_I95@PURE_QUANTA.Q_RES(CHIPS)':
 'A': CDS_PINID='A';
NODE_NAME     PU202 A1
 '@T6G_MB_LIB.T6G(SCH_1):PAGE338_I113@PURE_QUANTA.MAX15090BEWIT(CHIPS)':
 'ISENSE': CDS_PINID='ISENSE';
NET_NAME
'P3V3_OCP_SENSE_2'
 '@T6G_MB_LIB.T6G(SCH_1):P3V3_OCP_SENSE_2':
 C_SIGNAL='@t6g_mb_lib.t6g(sch_1):p3v3_ocp_sense_2';
NODE_NAME     PU200 A1
 '@T6G_MB_LIB.T6G(SCH_1):PAGE343_I89@PURE_QUANTA.MAX15090BEWIT(CHIPS)':
 'ISENSE': CDS_PINID='ISENSE';
NODE_NAME     PR3824 1
 '@T6G_MB_LIB.T6G(SCH_1):PAGE343_I94@PURE_QUANTA.Q_RES(CHIPS)':
 'A': CDS_PINID='A';
NET_NAME
'P3V3_OCP_SFF'
 '@T6G_MB_LIB.T6G(SCH_1):P3V3_OCP_SFF':
 C_SIGNAL='@t6g_mb_lib.t6g(sch_1):p3v3_ocp_sff',
 CDS_GLOBAL_NET='TRUE';
NODE_NAME     C1237 1
 '@T6G_MB_LIB.T6G(SCH_1):PAGE335_I110@PURE_QUANTA.Q_CAP(CHIPS)':
 'A': CDS_PINID='A';
NODE_NAME     C1238 1
 '@T6G_MB_LIB.T6G(SCH_1):PAGE335_I111@PURE_QUANTA.Q_CAP(CHIPS)':
 'A': CDS_PINID='A';
NODE_NAME     C1240 1
 '@T6G_MB_LIB.T6G(SCH_1):PAGE335_I114@PURE_QUANTA.Q_CAP(CHIPS)':
 'A': CDS_PINID='A';
NODE_NAME     J38 B11
 '@T6G_MB_LIB.T6G(SCH_1):PAGE335_I168@PURE_QUANTA.SCONN168_ME1016810202011(CHIPS)':
 '+3.3V_EDGE': CDS_PINID='\+3.3v_edge\';
NODE_NAME     R3603 1
 '@T6G_MB_LIB.T6G(SCH_1):PAGE295_I43@PURE_QUANTA.Q_RES(CHIPS)':
 'A': CDS_PINID='A';
NODE_NAME     R3645 1
 '@T6G_MB_LIB.T6G(SCH_1):PAGE295_I93@PURE_QUANTA.Q_RES(CHIPS)':
 'A': CDS_PINID='A';
NODE_NAME     U236 8
 '@T6G_MB_LIB.T6G(SCH_1):PAGE248_I14@PURE_QUANTA.PCA9617ADP(CHIPS)':
 'VCCB': CDS_PINID='VCCB';
NODE_NAME     C1862 1
 '@T6G_MB_LIB.T6G(SCH_1):PAGE248_I19@PURE_QUANTA.Q_CAP(CHIPS)':
 'A': CDS_PINID='A';
NODE_NAME     R3500 1
 '@T6G_MB_LIB.T6G(SCH_1):PAGE248_I27@PURE_QUANTA.Q_RES(CHIPS)':
 'A': CDS_PINID='A';
NODE_NAME     R3501 1
 '@T6G_MB_LIB.T6G(SCH_1):PAGE248_I31@PURE_QUANTA.Q_RES(CHIPS)':
 'A': CDS_PINID='A';
NODE_NAME     R31 1
 '@T6G_MB_LIB.T6G(SCH_1):PAGE335_I3@PURE_QUANTA.Q_RES(CHIPS)':
 'A': CDS_PINID='A';
NODE_NAME     R33 1
 '@T6G_MB_LIB.T6G(SCH_1):PAGE335_I17@PURE_QUANTA.Q_RES(CHIPS)':
 'A': CDS_PINID='A';
NODE_NAME     R8423 2
 '@T6G_MB_LIB.T6G(SCH_1):PAGE335_I20@PURE_QUANTA.Q_RES(CHIPS)':
 'B': CDS_PINID='B';
NODE_NAME     R8421 2
 '@T6G_MB_LIB.T6G(SCH_1):PAGE335_I21@PURE_QUANTA.Q_RES(CHIPS)':
 'B': CDS_PINID='B';
NODE_NAME     R8420 2
 '@T6G_MB_LIB.T6G(SCH_1):PAGE335_I22@PURE_QUANTA.Q_RES(CHIPS)':
 'B': CDS_PINID='B';
NODE_NAME     C1239 1
 '@T6G_MB_LIB.T6G(SCH_1):PAGE335_I112@PURE_QUANTA.Q_CAP(CHIPS)':
 'A': CDS_PINID='A';
NODE_NAME     R1824 1
 '@T6G_MB_LIB.T6G(SCH_1):PAGE337_I11@PURE_QUANTA.Q_RES(CHIPS)':
 'A': CDS_PINID='A';
NODE_NAME     R45 1
 '@T6G_MB_LIB.T6G(SCH_1):PAGE337_I12@PURE_QUANTA.Q_RES(CHIPS)':
 'A': CDS_PINID='A';
NET_NAME
'P3V3_OCP_SFF_EN'
 '@T6G_MB_LIB.T6G(SCH_1):P3V3_OCP_SFF_EN':
 C_SIGNAL='@t6g_mb_lib.t6g(sch_1):p3v3_ocp_sff_en';
NODE_NAME     R23 1
 '@T6G_MB_LIB.T6G(SCH_1):PAGE79_I23@PURE_QUANTA.Q_RES(CHIPS)':
 'A': CDS_PINID='A';
NODE_NAME     U18 B9
 '@T6G_MB_LIB.T6G(SCH_1):PAGE79_I94@PURE_QUANTA.LCMXO3LF9400C5BG484C(CHIPS)':
 'PT21A': CDS_PINID='PT21A';
NET_NAME
'P3V3_OCP_SFF_EN_R'
 '@T6G_MB_LIB.T6G(SCH_1):P3V3_OCP_SFF_EN_R':
 C_SIGNAL='@t6g_mb_lib.t6g(sch_1):p3v3_ocp_sff_en_r';
NODE_NAME     R23 2
 '@T6G_MB_LIB.T6G(SCH_1):PAGE79_I23@PURE_QUANTA.Q_RES(CHIPS)':
 'B': CDS_PINID='B';
NODE_NAME     R1071 1
 '@T6G_MB_LIB.T6G(SCH_1):PAGE82_I38@PURE_QUANTA.Q_RES(CHIPS)':
 'A': CDS_PINID='A';
NODE_NAME     R5487 1
 '@T6G_MB_LIB.T6G(SCH_1):PAGE338_I126@PURE_QUANTA.Q_RES(CHIPS)':
 'A': CDS_PINID='A';
NODE_NAME     R3845 1
 '@T6G_MB_LIB.T6G(SCH_1):PAGE339_I131@PURE_QUANTA.Q_RES(CHIPS)':
 'A': CDS_PINID='A';
NODE_NAME     R3263 2
 '@T6G_MB_LIB.T6G(SCH_1):PAGE248_I35@PURE_QUANTA.Q_RES(CHIPS)':
 'B': CDS_PINID='B';
NET_NAME
'P3V3_OCP_SFF_R'
 '@T6G_MB_LIB.T6G(SCH_1):P3V3_OCP_SFF_R':
 C_SIGNAL='@t6g_mb_lib.t6g(sch_1):p3v3_ocp_sff_r',
 CDS_GLOBAL_NET='TRUE';
NODE_NAME     U266 11
 '@T6G_MB_LIB.T6G(SCH_1):PAGE295_I30@PURE_QUANTA.ISL28022FRZT(CHIPS)':
 'VBUS': CDS_PINID='VBUS';
NODE_NAME     R3602 1
 '@T6G_MB_LIB.T6G(SCH_1):PAGE295_I41@PURE_QUANTA.Q_RES(CHIPS)':
 'A': CDS_PINID='A';
NODE_NAME     C2024 1
 '@T6G_MB_LIB.T6G(SCH_1):PAGE295_I50@PURE_QUANTA.Q_CAP(CHIPS)':
 'A': CDS_PINID='A';
NODE_NAME     R3645 2
 '@T6G_MB_LIB.T6G(SCH_1):PAGE295_I93@PURE_QUANTA.Q_RES(CHIPS)':
 'B': CDS_PINID='B';
NODE_NAME     PC2144 1
 '@T6G_MB_LIB.T6G(SCH_1):PAGE338_I94@PURE_QUANTA.Q_CAP(CHIPS)':
 'A': CDS_PINID='A';
NODE_NAME     PR4525 1
 '@T6G_MB_LIB.T6G(SCH_1):PAGE338_I96@PURE_QUANTA.Q_RES(CHIPS)':
 'A': CDS_PINID='A';
NODE_NAME     PD103 C
 '@T6G_MB_LIB.T6G(SCH_1):PAGE338_I97@PURE_QUANTA.SCHOTTKY_AC(CHIPS)':
 'C': CDS_PINID='C';
NODE_NAME     PC2091 1
 '@T6G_MB_LIB.T6G(SCH_1):PAGE338_I104@PURE_QUANTA.Q_CAP(CHIPS)':
 'A': CDS_PINID='A';
NODE_NAME     PC2081 1
 '@T6G_MB_LIB.T6G(SCH_1):PAGE338_I106@PURE_QUANTA.Q_CAP(CHIPS)':
 'A': CDS_PINID='A';
NODE_NAME     PU202 A4
 '@T6G_MB_LIB.T6G(SCH_1):PAGE338_I113@PURE_QUANTA.MAX15090BEWIT(CHIPS)':
 'OUT_A4': CDS_PINID='OUT_A4';
NODE_NAME     PU202 B4
 '@T6G_MB_LIB.T6G(SCH_1):PAGE338_I113@PURE_QUANTA.MAX15090BEWIT(CHIPS)':
 'OUT_B4': CDS_PINID='OUT_B4';
NODE_NAME     PU202 B6
 '@T6G_MB_LIB.T6G(SCH_1):PAGE338_I113@PURE_QUANTA.MAX15090BEWIT(CHIPS)':
 'OUT_B6': CDS_PINID='OUT_B6';
NODE_NAME     PU202 C4
 '@T6G_MB_LIB.T6G(SCH_1):PAGE338_I113@PURE_QUANTA.MAX15090BEWIT(CHIPS)':
 'OUT_C4': CDS_PINID='OUT_C4';
NODE_NAME     PU202 C6
 '@T6G_MB_LIB.T6G(SCH_1):PAGE338_I113@PURE_QUANTA.MAX15090BEWIT(CHIPS)':
 'OUT_C6': CDS_PINID='OUT_C6';
NODE_NAME     PU202 D4
 '@T6G_MB_LIB.T6G(SCH_1):PAGE338_I113@PURE_QUANTA.MAX15090BEWIT(CHIPS)':
 'OUT_D4': CDS_PINID='OUT_D4';
NODE_NAME     PU202 D6
 '@T6G_MB_LIB.T6G(SCH_1):PAGE338_I113@PURE_QUANTA.MAX15090BEWIT(CHIPS)':
 'OUT_D6': CDS_PINID='OUT_D6';
NODE_NAME     PC2163 1
 '@T6G_MB_LIB.T6G(SCH_1):PAGE339_I108@PURE_QUANTA.Q_CAP(CHIPS)':
 'A': CDS_PINID='A';
NODE_NAME     PU205 6_7
 '@T6G_MB_LIB.T6G(SCH_1):PAGE339_I113@PURE_QUANTA.MP5016GQHLZ(CHIPS)':
 'SOURCE': CDS_PINID='SOURCE';
NODE_NAME     C8008 1
 '@T6G_MB_LIB.T6G(SCH_1):PAGE340_I79@PURE_QUANTA.Q_CAP(CHIPS)':
 'A': CDS_PINID='A';
NODE_NAME     U8001 3
 '@T6G_MB_LIB.T6G(SCH_1):PAGE340_I80@PURE_QUANTA.APX80929SAG7(CHIPS)':
 'VCC': CDS_PINID='VCC';
NODE_NAME     R8092 1
 '@T6G_MB_LIB.T6G(SCH_1):PAGE340_I90@PURE_QUANTA.Q_RES(CHIPS)':
 'A': CDS_PINID='A';
NET_NAME
'P3V3_OCP_UV_1'
 '@T6G_MB_LIB.T6G(SCH_1):P3V3_OCP_UV_1':
 C_SIGNAL='@t6g_mb_lib.t6g(sch_1):p3v3_ocp_uv_1';
NODE_NAME     R3785 2
 '@T6G_MB_LIB.T6G(SCH_1):PAGE338_I61@PURE_QUANTA.Q_RES(CHIPS)':
 'B': CDS_PINID='B';
NODE_NAME     PR3790 1
 '@T6G_MB_LIB.T6G(SCH_1):PAGE338_I64@PURE_QUANTA.Q_RES(CHIPS)':
 'A': CDS_PINID='A';
NODE_NAME     PR3789 2
 '@T6G_MB_LIB.T6G(SCH_1):PAGE338_I66@PURE_QUANTA.Q_RES(CHIPS)':
 'B': CDS_PINID='B';
NODE_NAME     PU202 D2
 '@T6G_MB_LIB.T6G(SCH_1):PAGE338_I113@PURE_QUANTA.MAX15090BEWIT(CHIPS)':
 'UV': CDS_PINID='UV';
NET_NAME
'P3V3_OCP_UV_1_R1'
 '@T6G_MB_LIB.T6G(SCH_1):P3V3_OCP_UV_1_R1':
 C_SIGNAL='@t6g_mb_lib.t6g(sch_1):p3v3_ocp_uv_1_r1';
NODE_NAME     R3785 1
 '@T6G_MB_LIB.T6G(SCH_1):PAGE338_I61@PURE_QUANTA.Q_RES(CHIPS)':
 'A': CDS_PINID='A';
NODE_NAME     Q124 3
 '@T6G_MB_LIB.T6G(SCH_1):PAGE338_I112@PURE_QUANTA.MOSFET_NCH_DUAL(CHIPS)':
 'D2': CDS_PINID='D2';
NET_NAME
'P3V3_OCP_UV_2'
 '@T6G_MB_LIB.T6G(SCH_1):P3V3_OCP_UV_2':
 C_SIGNAL='@t6g_mb_lib.t6g(sch_1):p3v3_ocp_uv_2';
NODE_NAME     PR3795 2
 '@T6G_MB_LIB.T6G(SCH_1):PAGE343_I56@PURE_QUANTA.Q_RES(CHIPS)':
 'B': CDS_PINID='B';
NODE_NAME     PU200 D2
 '@T6G_MB_LIB.T6G(SCH_1):PAGE343_I89@PURE_QUANTA.MAX15090BEWIT(CHIPS)':
 'UV': CDS_PINID='UV';
NODE_NAME     R3807 2
 '@T6G_MB_LIB.T6G(SCH_1):PAGE343_I50@PURE_QUANTA.Q_RES(CHIPS)':
 'B': CDS_PINID='B';
NODE_NAME     PR3829 1
 '@T6G_MB_LIB.T6G(SCH_1):PAGE343_I53@PURE_QUANTA.Q_RES(CHIPS)':
 'A': CDS_PINID='A';
NET_NAME
'P3V3_OCP_UV_2_R1'
 '@T6G_MB_LIB.T6G(SCH_1):P3V3_OCP_UV_2_R1':
 C_SIGNAL='@t6g_mb_lib.t6g(sch_1):p3v3_ocp_uv_2_r1';
NODE_NAME     Q119 3
 '@T6G_MB_LIB.T6G(SCH_1):PAGE343_I45@PURE_QUANTA.MOSFET_NCH_DUAL(CHIPS)':
 'D2': CDS_PINID='D2';
NODE_NAME     R3807 1
 '@T6G_MB_LIB.T6G(SCH_1):PAGE343_I50@PURE_QUANTA.Q_RES(CHIPS)':
 'A': CDS_PINID='A';
NET_NAME
'P3V3_OCP_V3_2'
 '@T6G_MB_LIB.T6G(SCH_1):P3V3_OCP_V3_2':
 C_SIGNAL='@t6g_mb_lib.t6g(sch_1):p3v3_ocp_v3_2',
 CDS_GLOBAL_NET='TRUE';
NODE_NAME     C1837 1
 '@T6G_MB_LIB.T6G(SCH_1):PAGE341_I23@PURE_QUANTA.Q_CAP(CHIPS)':
 'A': CDS_PINID='A';
NODE_NAME     R3162 1
 '@T6G_MB_LIB.T6G(SCH_1):PAGE341_I26@PURE_QUANTA.Q_RES(CHIPS)':
 'A': CDS_PINID='A';
NODE_NAME     J35 B11
 '@T6G_MB_LIB.T6G(SCH_1):PAGE341_I168@PURE_QUANTA.SCONN168_ME1016810202011(CHIPS)':
 '+3.3V_EDGE': CDS_PINID='\+3.3v_edge\';
NODE_NAME     R3571 1
 '@T6G_MB_LIB.T6G(SCH_1):PAGE360_I110@PURE_QUANTA.Q_RES(CHIPS)':
 'A': CDS_PINID='A';
NODE_NAME     R3633 1
 '@T6G_MB_LIB.T6G(SCH_1):PAGE360_I116@PURE_QUANTA.Q_RES(CHIPS)':
 'A': CDS_PINID='A';
NODE_NAME     U235 8
 '@T6G_MB_LIB.T6G(SCH_1):PAGE248_I6@PURE_QUANTA.PCA9617ADP(CHIPS)':
 'VCCB': CDS_PINID='VCCB';
NODE_NAME     C1861 1
 '@T6G_MB_LIB.T6G(SCH_1):PAGE248_I9@PURE_QUANTA.Q_CAP(CHIPS)':
 'A': CDS_PINID='A';
NODE_NAME     R3520 1
 '@T6G_MB_LIB.T6G(SCH_1):PAGE248_I23@PURE_QUANTA.Q_RES(CHIPS)':
 'A': CDS_PINID='A';
NODE_NAME     R3519 1
 '@T6G_MB_LIB.T6G(SCH_1):PAGE248_I34@PURE_QUANTA.Q_RES(CHIPS)':
 'A': CDS_PINID='A';
NODE_NAME     R3174 2
 '@T6G_MB_LIB.T6G(SCH_1):PAGE341_I9@PURE_QUANTA.Q_RES(CHIPS)':
 'B': CDS_PINID='B';
NODE_NAME     R3173 2
 '@T6G_MB_LIB.T6G(SCH_1):PAGE341_I10@PURE_QUANTA.Q_RES(CHIPS)':
 'B': CDS_PINID='B';
NODE_NAME     R3176 2
 '@T6G_MB_LIB.T6G(SCH_1):PAGE341_I12@PURE_QUANTA.Q_RES(CHIPS)':
 'B': CDS_PINID='B';
NODE_NAME     C1835 1
 '@T6G_MB_LIB.T6G(SCH_1):PAGE341_I21@PURE_QUANTA.Q_CAP(CHIPS)':
 'A': CDS_PINID='A';
NODE_NAME     C1836 1
 '@T6G_MB_LIB.T6G(SCH_1):PAGE341_I22@PURE_QUANTA.Q_CAP(CHIPS)':
 'A': CDS_PINID='A';
NODE_NAME     C1838 1
 '@T6G_MB_LIB.T6G(SCH_1):PAGE341_I24@PURE_QUANTA.Q_CAP(CHIPS)':
 'A': CDS_PINID='A';
NODE_NAME     R3166 1
 '@T6G_MB_LIB.T6G(SCH_1):PAGE341_I28@PURE_QUANTA.Q_RES(CHIPS)':
 'A': CDS_PINID='A';
NODE_NAME     R3182 1
 '@T6G_MB_LIB.T6G(SCH_1):PAGE342_I3@PURE_QUANTA.Q_RES(CHIPS)':
 'A': CDS_PINID='A';
NODE_NAME     R3183 1
 '@T6G_MB_LIB.T6G(SCH_1):PAGE342_I4@PURE_QUANTA.Q_RES(CHIPS)':
 'A': CDS_PINID='A';
NET_NAME
'P3V3_OCP_V3_2_EN_R'
 '@T6G_MB_LIB.T6G(SCH_1):P3V3_OCP_V3_2_EN_R':
 C_SIGNAL='@t6g_mb_lib.t6g(sch_1):p3v3_ocp_v3_2_en_r';
NODE_NAME     R6062 1
 '@T6G_MB_LIB.T6G(SCH_1):PAGE82_I40@PURE_QUANTA.Q_RES(CHIPS)':
 'A': CDS_PINID='A';
NODE_NAME     U18 V17
 '@T6G_MB_LIB.T6G(SCH_1):PAGE80_I216@PURE_QUANTA.LCMXO3LF9400C5BG484C(CHIPS)':
 'PB46C': CDS_PINID='PB46C';
NODE_NAME     R4060 1
 '@T6G_MB_LIB.T6G(SCH_1):PAGE343_I122@PURE_QUANTA.Q_RES(CHIPS)':
 'A': CDS_PINID='A';
NODE_NAME     R3631 1
 '@T6G_MB_LIB.T6G(SCH_1):PAGE344_I74@PURE_QUANTA.Q_RES(CHIPS)':
 'A': CDS_PINID='A';
NODE_NAME     R3264 2
 '@T6G_MB_LIB.T6G(SCH_1):PAGE248_I38@PURE_QUANTA.Q_RES(CHIPS)':
 'B': CDS_PINID='B';
NET_NAME
'P3V3_OCP_V3_2_R'
 '@T6G_MB_LIB.T6G(SCH_1):P3V3_OCP_V3_2_R':
 C_SIGNAL='@t6g_mb_lib.t6g(sch_1):p3v3_ocp_v3_2_r',
 CDS_GLOBAL_NET='TRUE';
NODE_NAME     PU200 A4
 '@T6G_MB_LIB.T6G(SCH_1):PAGE343_I89@PURE_QUANTA.MAX15090BEWIT(CHIPS)':
 'OUT_A4': CDS_PINID='OUT_A4';
NODE_NAME     PU200 B4
 '@T6G_MB_LIB.T6G(SCH_1):PAGE343_I89@PURE_QUANTA.MAX15090BEWIT(CHIPS)':
 'OUT_B4': CDS_PINID='OUT_B4';
NODE_NAME     PU200 B6
 '@T6G_MB_LIB.T6G(SCH_1):PAGE343_I89@PURE_QUANTA.MAX15090BEWIT(CHIPS)':
 'OUT_B6': CDS_PINID='OUT_B6';
NODE_NAME     PU200 C4
 '@T6G_MB_LIB.T6G(SCH_1):PAGE343_I89@PURE_QUANTA.MAX15090BEWIT(CHIPS)':
 'OUT_C4': CDS_PINID='OUT_C4';
NODE_NAME     PU200 C6
 '@T6G_MB_LIB.T6G(SCH_1):PAGE343_I89@PURE_QUANTA.MAX15090BEWIT(CHIPS)':
 'OUT_C6': CDS_PINID='OUT_C6';
NODE_NAME     PU200 D4
 '@T6G_MB_LIB.T6G(SCH_1):PAGE343_I89@PURE_QUANTA.MAX15090BEWIT(CHIPS)':
 'OUT_D4': CDS_PINID='OUT_D4';
NODE_NAME     PU200 D6
 '@T6G_MB_LIB.T6G(SCH_1):PAGE343_I89@PURE_QUANTA.MAX15090BEWIT(CHIPS)':
 'OUT_D6': CDS_PINID='OUT_D6';
NODE_NAME     PR4523 1
 '@T6G_MB_LIB.T6G(SCH_1):PAGE343_I105@PURE_QUANTA.Q_RES(CHIPS)':
 'A': CDS_PINID='A';
NODE_NAME     PU207 6_7
 '@T6G_MB_LIB.T6G(SCH_1):PAGE344_I51@PURE_QUANTA.MP5016GQHLZ(CHIPS)':
 'SOURCE': CDS_PINID='SOURCE';
NODE_NAME     PC2173 1
 '@T6G_MB_LIB.T6G(SCH_1):PAGE344_I56@PURE_QUANTA.Q_CAP(CHIPS)':
 'A': CDS_PINID='A';
NODE_NAME     U263 11
 '@T6G_MB_LIB.T6G(SCH_1):PAGE360_I94@PURE_QUANTA.ISL28022FRZT(CHIPS)':
 'VBUS': CDS_PINID='VBUS';
NODE_NAME     R3570 1
 '@T6G_MB_LIB.T6G(SCH_1):PAGE360_I109@PURE_QUANTA.Q_RES(CHIPS)':
 'A': CDS_PINID='A';
NODE_NAME     C2017 1
 '@T6G_MB_LIB.T6G(SCH_1):PAGE360_I114@PURE_QUANTA.Q_CAP(CHIPS)':
 'A': CDS_PINID='A';
NODE_NAME     R3633 2
 '@T6G_MB_LIB.T6G(SCH_1):PAGE360_I116@PURE_QUANTA.Q_RES(CHIPS)':
 'B': CDS_PINID='B';
NODE_NAME     PC2149 1
 '@T6G_MB_LIB.T6G(SCH_1):PAGE343_I104@PURE_QUANTA.Q_CAP(CHIPS)':
 'A': CDS_PINID='A';
NODE_NAME     PD109 C
 '@T6G_MB_LIB.T6G(SCH_1):PAGE343_I106@PURE_QUANTA.SCHOTTKY_AC(CHIPS)':
 'C': CDS_PINID='C';
NODE_NAME     PC2137 1
 '@T6G_MB_LIB.T6G(SCH_1):PAGE343_I108@PURE_QUANTA.Q_CAP(CHIPS)':
 'A': CDS_PINID='A';
NODE_NAME     PC2142 1
 '@T6G_MB_LIB.T6G(SCH_1):PAGE343_I112@PURE_QUANTA.Q_CAP(CHIPS)':
 'A': CDS_PINID='A';
NODE_NAME     C8009 1
 '@T6G_MB_LIB.T6G(SCH_1):PAGE257_I66@PURE_QUANTA.Q_CAP(CHIPS)':
 'A': CDS_PINID='A';
NODE_NAME     U8002 3
 '@T6G_MB_LIB.T6G(SCH_1):PAGE257_I67@PURE_QUANTA.APX80929SAG7(CHIPS)':
 'VCC': CDS_PINID='VCC';
NODE_NAME     R8095 1
 '@T6G_MB_LIB.T6G(SCH_1):PAGE257_I77@PURE_QUANTA.Q_RES(CHIPS)':
 'A': CDS_PINID='A';
NET_NAME
'P3V3_OCP_VCC_1'
 '@T6G_MB_LIB.T6G(SCH_1):P3V3_OCP_VCC_1':
 C_SIGNAL='@t6g_mb_lib.t6g(sch_1):p3v3_ocp_vcc_1';
NODE_NAME     PR3798 2
 '@T6G_MB_LIB.T6G(SCH_1):PAGE338_I68@PURE_QUANTA.Q_RES(CHIPS)':
 'B': CDS_PINID='B';
NODE_NAME     PC2086 1
 '@T6G_MB_LIB.T6G(SCH_1):PAGE338_I110@PURE_QUANTA.Q_CAP(CHIPS)':
 'A': CDS_PINID='A';
NODE_NAME     PU202 A2
 '@T6G_MB_LIB.T6G(SCH_1):PAGE338_I113@PURE_QUANTA.MAX15090BEWIT(CHIPS)':
 'VCC': CDS_PINID='VCC';
NET_NAME
'P3V3_OCP_VCC_2'
 '@T6G_MB_LIB.T6G(SCH_1):P3V3_OCP_VCC_2':
 C_SIGNAL='@t6g_mb_lib.t6g(sch_1):p3v3_ocp_vcc_2';
NODE_NAME     PU200 A2
 '@T6G_MB_LIB.T6G(SCH_1):PAGE343_I89@PURE_QUANTA.MAX15090BEWIT(CHIPS)':
 'VCC': CDS_PINID='VCC';
NODE_NAME     C39 1
 '@T6G_MB_LIB.T6G(SCH_1):PAGE343_I90@PURE_QUANTA.Q_CAP(CHIPS)':
 'A': CDS_PINID='A';
NODE_NAME     PR3782 2
 '@T6G_MB_LIB.T6G(SCH_1):PAGE343_I91@PURE_QUANTA.Q_RES(CHIPS)':
 'B': CDS_PINID='B';
NET_NAME
'P3V3_PDB_AUX_ADC'
 '@T6G_MB_LIB.T6G(SCH_1):P3V3_PDB_AUX_ADC':
 C_SIGNAL='@t6g_mb_lib.t6g(sch_1):p3v3_pdb_aux_adc';
NODE_NAME     R4567 1
 '@T6G_MB_LIB.T6G(SCH_1):PAGE369_I8@PURE_QUANTA.Q_RES(CHIPS)':
 'A': CDS_PINID='A';
NODE_NAME     J45 A3
 '@T6G_MB_LIB.T6G(SCH_1):PAGE363_I466@PURE_QUANTA.CONN60_101062636003K02LF(CHIPS)':
 'A3': CDS_PINID='A3';
NET_NAME
'P3V3_PDB_AUX_ADC_MAM'
 '@T6G_MB_LIB.T6G(SCH_1):P3V3_PDB_AUX_ADC_MAM':
 C_SIGNAL='@t6g_mb_lib.t6g(sch_1):p3v3_pdb_aux_adc_mam';
NODE_NAME     C2045 1
 '@T6G_MB_LIB.T6G(SCH_1):PAGE369_I36@PURE_QUANTA.Q_CAP(CHIPS)':
 'A': CDS_PINID='A';
NODE_NAME     R3687 2
 '@T6G_MB_LIB.T6G(SCH_1):PAGE369_I42@PURE_QUANTA.Q_RES(CHIPS)':
 'B': CDS_PINID='B';
NODE_NAME     U193 11
 '@T6G_MB_LIB.T6G(SCH_1):PAGE369_I169@PURE_QUANTA.MAX11617EEET(CHIPS)':
 'AIN6': CDS_PINID='AIN6';
NET_NAME
'P3V3_PDB_AUX_ADC_TIC'
 '@T6G_MB_LIB.T6G(SCH_1):P3V3_PDB_AUX_ADC_TIC':
 C_SIGNAL='@t6g_mb_lib.t6g(sch_1):p3v3_pdb_aux_adc_tic';
NODE_NAME     C2050 1
 '@T6G_MB_LIB.T6G(SCH_1):PAGE369_I34@PURE_QUANTA.Q_CAP(CHIPS)':
 'A': CDS_PINID='A';
NODE_NAME     R3688 2
 '@T6G_MB_LIB.T6G(SCH_1):PAGE369_I41@PURE_QUANTA.Q_RES(CHIPS)':
 'B': CDS_PINID='B';
NODE_NAME     U269 10
 '@T6G_MB_LIB.T6G(SCH_1):PAGE369_I142@PURE_QUANTA.ADC128D818CIMTXNOPB(CHIPS)':
 'IN6': CDS_PINID='IN6';
NET_NAME
'P3V3_PWRGD_CLKGEN'
 '@T6G_MB_LIB.T6G(SCH_1):P3V3_PWRGD_CLKGEN':
 C_SIGNAL='@t6g_mb_lib.t6g(sch_1):p3v3_pwrgd_clkgen';
NODE_NAME     R4080 2
 '@T6G_MB_LIB.T6G(SCH_1):PAGE232_I59@PURE_QUANTA.Q_RES(CHIPS)':
 'B': CDS_PINID='B';
NODE_NAME     U247 22
 '@T6G_MB_LIB.T6G(SCH_1):PAGE232_I77@PURE_QUANTA.9FGL0251DKILFT(CHIPS)':
 '^CKPWRGD_PD#': CDS_PINID='\^ckpwrgd_pd#\';
NET_NAME
'P3V3_RTC_AUX'
 '@T6G_MB_LIB.T6G(SCH_1):P3V3_RTC_AUX':
 C_SIGNAL='@t6g_mb_lib.t6g(sch_1):p3v3_rtc_aux',
 CDS_GLOBAL_NET='TRUE';
NODE_NAME     U166 3
 '@T6G_MB_LIB.T6G(SCH_1):PAGE156_I99@PURE_QUANTA.SCHOTTKY_DUAL_12A_3C(CHIPS)':
 'C': CDS_PINID='C';
NODE_NAME     R5052 2
 '@T6G_MB_LIB.T6G(SCH_1):PAGE156_I100@PURE_QUANTA.Q_RES(CHIPS)':
 'B': CDS_PINID='B';
NODE_NAME     R5051 1
 '@T6G_MB_LIB.T6G(SCH_1):PAGE156_I101@PURE_QUANTA.Q_RES(CHIPS)':
 'A': CDS_PINID='A';
NET_NAME
'P3V3_RTC_AUX_R'
 '@T6G_MB_LIB.T6G(SCH_1):P3V3_RTC_AUX_R':
 C_SIGNAL='@t6g_mb_lib.t6g(sch_1):p3v3_rtc_aux_r';
NODE_NAME     R5052 1
 '@T6G_MB_LIB.T6G(SCH_1):PAGE156_I100@PURE_QUANTA.Q_RES(CHIPS)':
 'A': CDS_PINID='A';
NODE_NAME     R5054 1
 '@T6G_MB_LIB.T6G(SCH_1):PAGE156_I122@PURE_QUANTA.Q_RES(CHIPS)':
 'A': CDS_PINID='A';
NET_NAME
'P3V3_STBY_R'
 '@T6G_MB_LIB.T6G(SCH_1):P3V3_STBY_R':
 C_SIGNAL='@t6g_mb_lib.t6g(sch_1):p3v3_stby_r';
NODE_NAME     R5101 2
 '@T6G_MB_LIB.T6G(SCH_1):PAGE156_I97@PURE_QUANTA.Q_RES(CHIPS)':
 'B': CDS_PINID='B';
NODE_NAME     U166 1
 '@T6G_MB_LIB.T6G(SCH_1):PAGE156_I99@PURE_QUANTA.SCHOTTKY_DUAL_12A_3C(CHIPS)':
 'B': CDS_PINID='B';
NET_NAME
'P3V_BAT'
 '@T6G_MB_LIB.T6G(SCH_1):P3V_BAT':
 C_SIGNAL='@t6g_mb_lib.t6g(sch_1):p3v_bat';
NODE_NAME     BT2 1
 '@T6G_MB_LIB.T6G(SCH_1):PAGE156_I86@PURE_QUANTA.CONN2_AAABAT029Y19(CHIPS)':
 '1': CDS_PINID='\1\';
NODE_NAME     R1775 1
 '@T6G_MB_LIB.T6G(SCH_1):PAGE156_I131@PURE_QUANTA.Q_RES(CHIPS)':
 'A': CDS_PINID='A';
NET_NAME
'P3V_BAT_R'
 '@T6G_MB_LIB.T6G(SCH_1):P3V_BAT_R':
 C_SIGNAL='@t6g_mb_lib.t6g(sch_1):p3v_bat_r',
 CDS_GLOBAL_NET='TRUE';
NODE_NAME     U166 2
 '@T6G_MB_LIB.T6G(SCH_1):PAGE156_I99@PURE_QUANTA.SCHOTTKY_DUAL_12A_3C(CHIPS)':
 'A': CDS_PINID='A';
NODE_NAME     R1775 2
 '@T6G_MB_LIB.T6G(SCH_1):PAGE156_I131@PURE_QUANTA.Q_RES(CHIPS)':
 'B': CDS_PINID='B';
NODE_NAME     R364 1
 '@T6G_MB_LIB.T6G(SCH_1):PAGE349_I231@PURE_QUANTA.Q_RES(CHIPS)':
 'A': CDS_PINID='A';
NET_NAME
'P5E_CPU0_G3_RX_DN<0>'
 '@T6G_MB_LIB.T6G(SCH_1):P5E_CPU0_G3_RX_DN'<0>:
 C_SIGNAL='@t6g_mb_lib.t6g(sch_1):p5e_cpu0_g3_rx_dn(0)';
NODE_NAME     U25 AL23
 '@T6G_MB_LIB.T6G(SCH_1):PAGE23_I216@PURE_QUANTA.GENOA_SP5(CHIPS)':
 'G3_RXN0||SATA20_RXN': CDS_PINID='\g3_rxn0||sata20_rxn\';
NODE_NAME     J38 A17
 '@T6G_MB_LIB.T6G(SCH_1):PAGE335_I168@PURE_QUANTA.SCONN168_ME1016810202011(CHIPS)':
 'PERN0': CDS_PINID='PERN0';
NET_NAME
'P5E_CPU0_G3_RX_DN<10>'
 '@T6G_MB_LIB.T6G(SCH_1):P5E_CPU0_G3_RX_DN'<10>:
 C_SIGNAL='@t6g_mb_lib.t6g(sch_1):p5e_cpu0_g3_rx_dn(10)';
NODE_NAME     U25 AJ32
 '@T6G_MB_LIB.T6G(SCH_1):PAGE23_I216@PURE_QUANTA.GENOA_SP5(CHIPS)':
 'G3_RXN10||SATA32_RXN': CDS_PINID='\g3_rxn10||sata32_rxn\';
NODE_NAME     J38 A50
 '@T6G_MB_LIB.T6G(SCH_1):PAGE335_I168@PURE_QUANTA.SCONN168_ME1016810202011(CHIPS)':
 'PERN10': CDS_PINID='PERN10';
NET_NAME
'P5E_CPU0_G3_RX_DN<11>'
 '@T6G_MB_LIB.T6G(SCH_1):P5E_CPU0_G3_RX_DN'<11>:
 C_SIGNAL='@t6g_mb_lib.t6g(sch_1):p5e_cpu0_g3_rx_dn(11)';
NODE_NAME     U25 AN32
 '@T6G_MB_LIB.T6G(SCH_1):PAGE23_I216@PURE_QUANTA.GENOA_SP5(CHIPS)':
 'G3_RXN11||SATA33_RXN': CDS_PINID='\g3_rxn11||sata33_rxn\';
NODE_NAME     J38 A53
 '@T6G_MB_LIB.T6G(SCH_1):PAGE335_I168@PURE_QUANTA.SCONN168_ME1016810202011(CHIPS)':
 'PERN11': CDS_PINID='PERN11';
NET_NAME
'P5E_CPU0_G3_RX_DN<12>'
 '@T6G_MB_LIB.T6G(SCH_1):P5E_CPU0_G3_RX_DN'<12>:
 C_SIGNAL='@t6g_mb_lib.t6g(sch_1):p5e_cpu0_g3_rx_dn(12)';
NODE_NAME     U25 AK35
 '@T6G_MB_LIB.T6G(SCH_1):PAGE23_I216@PURE_QUANTA.GENOA_SP5(CHIPS)':
 'G3_RXN12||SATA34_RXN': CDS_PINID='\g3_rxn12||sata34_rxn\';
NODE_NAME     J38 A56
 '@T6G_MB_LIB.T6G(SCH_1):PAGE335_I168@PURE_QUANTA.SCONN168_ME1016810202011(CHIPS)':
 'PERN12': CDS_PINID='PERN12';
NET_NAME
'P5E_CPU0_G3_RX_DN<13>'
 '@T6G_MB_LIB.T6G(SCH_1):P5E_CPU0_G3_RX_DN'<13>:
 C_SIGNAL='@t6g_mb_lib.t6g(sch_1):p5e_cpu0_g3_rx_dn(13)';
NODE_NAME     U25 AH35
 '@T6G_MB_LIB.T6G(SCH_1):PAGE23_I216@PURE_QUANTA.GENOA_SP5(CHIPS)':
 'G3_RXN13||SATA35_RXN': CDS_PINID='\g3_rxn13||sata35_rxn\';
NODE_NAME     J38 A59
 '@T6G_MB_LIB.T6G(SCH_1):PAGE335_I168@PURE_QUANTA.SCONN168_ME1016810202011(CHIPS)':
 'PERN13': CDS_PINID='PERN13';
NET_NAME
'P5E_CPU0_G3_RX_DN<14>'
 '@T6G_MB_LIB.T6G(SCH_1):P5E_CPU0_G3_RX_DN'<14>:
 C_SIGNAL='@t6g_mb_lib.t6g(sch_1):p5e_cpu0_g3_rx_dn(14)';
NODE_NAME     U25 AM35
 '@T6G_MB_LIB.T6G(SCH_1):PAGE23_I216@PURE_QUANTA.GENOA_SP5(CHIPS)':
 'G3_RXN14||SATA36_RXN': CDS_PINID='\g3_rxn14||sata36_rxn\';
NODE_NAME     J38 A62
 '@T6G_MB_LIB.T6G(SCH_1):PAGE335_I168@PURE_QUANTA.SCONN168_ME1016810202011(CHIPS)':
 'PERN14': CDS_PINID='PERN14';
NET_NAME
'P5E_CPU0_G3_RX_DN<15>'
 '@T6G_MB_LIB.T6G(SCH_1):P5E_CPU0_G3_RX_DN'<15>:
 C_SIGNAL='@t6g_mb_lib.t6g(sch_1):p5e_cpu0_g3_rx_dn(15)';
NODE_NAME     U25 AP35
 '@T6G_MB_LIB.T6G(SCH_1):PAGE23_I216@PURE_QUANTA.GENOA_SP5(CHIPS)':
 'G3_RXN15||SATA37_RXN': CDS_PINID='\g3_rxn15||sata37_rxn\';
NODE_NAME     J38 A65
 '@T6G_MB_LIB.T6G(SCH_1):PAGE335_I168@PURE_QUANTA.SCONN168_ME1016810202011(CHIPS)':
 'PERN15': CDS_PINID='PERN15';
NET_NAME
'P5E_CPU0_G3_RX_DN<1>'
 '@T6G_MB_LIB.T6G(SCH_1):P5E_CPU0_G3_RX_DN'<1>:
 C_SIGNAL='@t6g_mb_lib.t6g(sch_1):p5e_cpu0_g3_rx_dn(1)';
NODE_NAME     U25 AJ23
 '@T6G_MB_LIB.T6G(SCH_1):PAGE23_I216@PURE_QUANTA.GENOA_SP5(CHIPS)':
 'G3_RXN1||SATA21_RXN': CDS_PINID='\g3_rxn1||sata21_rxn\';
NODE_NAME     J38 A20
 '@T6G_MB_LIB.T6G(SCH_1):PAGE335_I168@PURE_QUANTA.SCONN168_ME1016810202011(CHIPS)':
 'PERN1': CDS_PINID='PERN1';
NET_NAME
'P5E_CPU0_G3_RX_DN<2>'
 '@T6G_MB_LIB.T6G(SCH_1):P5E_CPU0_G3_RX_DN'<2>:
 C_SIGNAL='@t6g_mb_lib.t6g(sch_1):p5e_cpu0_g3_rx_dn(2)';
NODE_NAME     U25 AN23
 '@T6G_MB_LIB.T6G(SCH_1):PAGE23_I216@PURE_QUANTA.GENOA_SP5(CHIPS)':
 'G3_RXN2||SATA22_RXN': CDS_PINID='\g3_rxn2||sata22_rxn\';
NODE_NAME     J38 A23
 '@T6G_MB_LIB.T6G(SCH_1):PAGE335_I168@PURE_QUANTA.SCONN168_ME1016810202011(CHIPS)':
 'PERN2': CDS_PINID='PERN2';
NET_NAME
'P5E_CPU0_G3_RX_DN<3>'
 '@T6G_MB_LIB.T6G(SCH_1):P5E_CPU0_G3_RX_DN'<3>:
 C_SIGNAL='@t6g_mb_lib.t6g(sch_1):p5e_cpu0_g3_rx_dn(3)';
NODE_NAME     U25 AL26
 '@T6G_MB_LIB.T6G(SCH_1):PAGE23_I216@PURE_QUANTA.GENOA_SP5(CHIPS)':
 'G3_RXN3||SATA23_RXN': CDS_PINID='\g3_rxn3||sata23_rxn\';
NODE_NAME     J38 A26
 '@T6G_MB_LIB.T6G(SCH_1):PAGE335_I168@PURE_QUANTA.SCONN168_ME1016810202011(CHIPS)':
 'PERN3': CDS_PINID='PERN3';
NET_NAME
'P5E_CPU0_G3_RX_DN<4>'
 '@T6G_MB_LIB.T6G(SCH_1):P5E_CPU0_G3_RX_DN'<4>:
 C_SIGNAL='@t6g_mb_lib.t6g(sch_1):p5e_cpu0_g3_rx_dn(4)';
NODE_NAME     U25 AJ26
 '@T6G_MB_LIB.T6G(SCH_1):PAGE23_I216@PURE_QUANTA.GENOA_SP5(CHIPS)':
 'G3_RXN4||SATA24_RXN': CDS_PINID='\g3_rxn4||sata24_rxn\';
NODE_NAME     J38 A30
 '@T6G_MB_LIB.T6G(SCH_1):PAGE335_I168@PURE_QUANTA.SCONN168_ME1016810202011(CHIPS)':
 'PERN4': CDS_PINID='PERN4';
NET_NAME
'P5E_CPU0_G3_RX_DN<5>'
 '@T6G_MB_LIB.T6G(SCH_1):P5E_CPU0_G3_RX_DN'<5>:
 C_SIGNAL='@t6g_mb_lib.t6g(sch_1):p5e_cpu0_g3_rx_dn(5)';
NODE_NAME     U25 AN26
 '@T6G_MB_LIB.T6G(SCH_1):PAGE23_I216@PURE_QUANTA.GENOA_SP5(CHIPS)':
 'G3_RXN5||SATA25_RXN': CDS_PINID='\g3_rxn5||sata25_rxn\';
NODE_NAME     J38 A33
 '@T6G_MB_LIB.T6G(SCH_1):PAGE335_I168@PURE_QUANTA.SCONN168_ME1016810202011(CHIPS)':
 'PERN5': CDS_PINID='PERN5';
NET_NAME
'P5E_CPU0_G3_RX_DN<6>'
 '@T6G_MB_LIB.T6G(SCH_1):P5E_CPU0_G3_RX_DN'<6>:
 C_SIGNAL='@t6g_mb_lib.t6g(sch_1):p5e_cpu0_g3_rx_dn(6)';
NODE_NAME     U25 AL29
 '@T6G_MB_LIB.T6G(SCH_1):PAGE23_I216@PURE_QUANTA.GENOA_SP5(CHIPS)':
 'G3_RXN6||SATA26_RXN': CDS_PINID='\g3_rxn6||sata26_rxn\';
NODE_NAME     J38 A36
 '@T6G_MB_LIB.T6G(SCH_1):PAGE335_I168@PURE_QUANTA.SCONN168_ME1016810202011(CHIPS)':
 'PERN6': CDS_PINID='PERN6';
NET_NAME
'P5E_CPU0_G3_RX_DN<7>'
 '@T6G_MB_LIB.T6G(SCH_1):P5E_CPU0_G3_RX_DN'<7>:
 C_SIGNAL='@t6g_mb_lib.t6g(sch_1):p5e_cpu0_g3_rx_dn(7)';
NODE_NAME     U25 AJ29
 '@T6G_MB_LIB.T6G(SCH_1):PAGE23_I216@PURE_QUANTA.GENOA_SP5(CHIPS)':
 'G3_RXN7||SATA27_RXN': CDS_PINID='\g3_rxn7||sata27_rxn\';
NODE_NAME     J38 A39
 '@T6G_MB_LIB.T6G(SCH_1):PAGE335_I168@PURE_QUANTA.SCONN168_ME1016810202011(CHIPS)':
 'PERN7': CDS_PINID='PERN7';
NET_NAME
'P5E_CPU0_G3_RX_DN<8>'
 '@T6G_MB_LIB.T6G(SCH_1):P5E_CPU0_G3_RX_DN'<8>:
 C_SIGNAL='@t6g_mb_lib.t6g(sch_1):p5e_cpu0_g3_rx_dn(8)';
NODE_NAME     U25 AN29
 '@T6G_MB_LIB.T6G(SCH_1):PAGE23_I216@PURE_QUANTA.GENOA_SP5(CHIPS)':
 'G3_RXN8||SATA30_RXN': CDS_PINID='\g3_rxn8||sata30_rxn\';
NODE_NAME     J38 A44
 '@T6G_MB_LIB.T6G(SCH_1):PAGE335_I168@PURE_QUANTA.SCONN168_ME1016810202011(CHIPS)':
 'PERN8': CDS_PINID='PERN8';
NET_NAME
'P5E_CPU0_G3_RX_DN<9>'
 '@T6G_MB_LIB.T6G(SCH_1):P5E_CPU0_G3_RX_DN'<9>:
 C_SIGNAL='@t6g_mb_lib.t6g(sch_1):p5e_cpu0_g3_rx_dn(9)';
NODE_NAME     U25 AL32
 '@T6G_MB_LIB.T6G(SCH_1):PAGE23_I216@PURE_QUANTA.GENOA_SP5(CHIPS)':
 'G3_RXN9||SATA31_RXN': CDS_PINID='\g3_rxn9||sata31_rxn\';
NODE_NAME     J38 A47
 '@T6G_MB_LIB.T6G(SCH_1):PAGE335_I168@PURE_QUANTA.SCONN168_ME1016810202011(CHIPS)':
 'PERN9': CDS_PINID='PERN9';
NET_NAME
'P5E_CPU0_G3_RX_DP<0>'
 '@T6G_MB_LIB.T6G(SCH_1):P5E_CPU0_G3_RX_DP'<0>:
 C_SIGNAL='@t6g_mb_lib.t6g(sch_1):p5e_cpu0_g3_rx_dp(0)';
NODE_NAME     U25 AL24
 '@T6G_MB_LIB.T6G(SCH_1):PAGE23_I216@PURE_QUANTA.GENOA_SP5(CHIPS)':
 'G3_RXP0||SATA20_RXP': CDS_PINID='\g3_rxp0||sata20_rxp\';
NODE_NAME     J38 A18
 '@T6G_MB_LIB.T6G(SCH_1):PAGE335_I168@PURE_QUANTA.SCONN168_ME1016810202011(CHIPS)':
 'PERP0': CDS_PINID='PERP0';
NET_NAME
'P5E_CPU0_G3_RX_DP<10>'
 '@T6G_MB_LIB.T6G(SCH_1):P5E_CPU0_G3_RX_DP'<10>:
 C_SIGNAL='@t6g_mb_lib.t6g(sch_1):p5e_cpu0_g3_rx_dp(10)';
NODE_NAME     U25 AJ33
 '@T6G_MB_LIB.T6G(SCH_1):PAGE23_I216@PURE_QUANTA.GENOA_SP5(CHIPS)':
 'G3_RXP10||SATA32_RXP': CDS_PINID='\g3_rxp10||sata32_rxp\';
NODE_NAME     J38 A51
 '@T6G_MB_LIB.T6G(SCH_1):PAGE335_I168@PURE_QUANTA.SCONN168_ME1016810202011(CHIPS)':
 'PERP10': CDS_PINID='PERP10';
NET_NAME
'P5E_CPU0_G3_RX_DP<11>'
 '@T6G_MB_LIB.T6G(SCH_1):P5E_CPU0_G3_RX_DP'<11>:
 C_SIGNAL='@t6g_mb_lib.t6g(sch_1):p5e_cpu0_g3_rx_dp(11)';
NODE_NAME     U25 AN33
 '@T6G_MB_LIB.T6G(SCH_1):PAGE23_I216@PURE_QUANTA.GENOA_SP5(CHIPS)':
 'G3_RXP11||SATA33_RXP': CDS_PINID='\g3_rxp11||sata33_rxp\';
NODE_NAME     J38 A54
 '@T6G_MB_LIB.T6G(SCH_1):PAGE335_I168@PURE_QUANTA.SCONN168_ME1016810202011(CHIPS)':
 'PERP11': CDS_PINID='PERP11';
NET_NAME
'P5E_CPU0_G3_RX_DP<12>'
 '@T6G_MB_LIB.T6G(SCH_1):P5E_CPU0_G3_RX_DP'<12>:
 C_SIGNAL='@t6g_mb_lib.t6g(sch_1):p5e_cpu0_g3_rx_dp(12)';
NODE_NAME     U25 AK36
 '@T6G_MB_LIB.T6G(SCH_1):PAGE23_I216@PURE_QUANTA.GENOA_SP5(CHIPS)':
 'G3_RXP12||SATA34_RXP': CDS_PINID='\g3_rxp12||sata34_rxp\';
NODE_NAME     J38 A57
 '@T6G_MB_LIB.T6G(SCH_1):PAGE335_I168@PURE_QUANTA.SCONN168_ME1016810202011(CHIPS)':
 'PERP12': CDS_PINID='PERP12';
NET_NAME
'P5E_CPU0_G3_RX_DP<13>'
 '@T6G_MB_LIB.T6G(SCH_1):P5E_CPU0_G3_RX_DP'<13>:
 C_SIGNAL='@t6g_mb_lib.t6g(sch_1):p5e_cpu0_g3_rx_dp(13)';
NODE_NAME     U25 AH36
 '@T6G_MB_LIB.T6G(SCH_1):PAGE23_I216@PURE_QUANTA.GENOA_SP5(CHIPS)':
 'G3_RXP13||SATA35_RXP': CDS_PINID='\g3_rxp13||sata35_rxp\';
NODE_NAME     J38 A60
 '@T6G_MB_LIB.T6G(SCH_1):PAGE335_I168@PURE_QUANTA.SCONN168_ME1016810202011(CHIPS)':
 'PERP13': CDS_PINID='PERP13';
NET_NAME
'P5E_CPU0_G3_RX_DP<14>'
 '@T6G_MB_LIB.T6G(SCH_1):P5E_CPU0_G3_RX_DP'<14>:
 C_SIGNAL='@t6g_mb_lib.t6g(sch_1):p5e_cpu0_g3_rx_dp(14)';
NODE_NAME     U25 AM36
 '@T6G_MB_LIB.T6G(SCH_1):PAGE23_I216@PURE_QUANTA.GENOA_SP5(CHIPS)':
 'G3_RXP14||SATA36_RXP': CDS_PINID='\g3_rxp14||sata36_rxp\';
NODE_NAME     J38 A63
 '@T6G_MB_LIB.T6G(SCH_1):PAGE335_I168@PURE_QUANTA.SCONN168_ME1016810202011(CHIPS)':
 'PERP14': CDS_PINID='PERP14';
NET_NAME
'P5E_CPU0_G3_RX_DP<15>'
 '@T6G_MB_LIB.T6G(SCH_1):P5E_CPU0_G3_RX_DP'<15>:
 C_SIGNAL='@t6g_mb_lib.t6g(sch_1):p5e_cpu0_g3_rx_dp(15)';
NODE_NAME     U25 AP36
 '@T6G_MB_LIB.T6G(SCH_1):PAGE23_I216@PURE_QUANTA.GENOA_SP5(CHIPS)':
 'G3_RXP15||SATA37_RXP': CDS_PINID='\g3_rxp15||sata37_rxp\';
NODE_NAME     J38 A66
 '@T6G_MB_LIB.T6G(SCH_1):PAGE335_I168@PURE_QUANTA.SCONN168_ME1016810202011(CHIPS)':
 'PERP15': CDS_PINID='PERP15';
NET_NAME
'P5E_CPU0_G3_RX_DP<1>'
 '@T6G_MB_LIB.T6G(SCH_1):P5E_CPU0_G3_RX_DP'<1>:
 C_SIGNAL='@t6g_mb_lib.t6g(sch_1):p5e_cpu0_g3_rx_dp(1)';
NODE_NAME     U25 AJ24
 '@T6G_MB_LIB.T6G(SCH_1):PAGE23_I216@PURE_QUANTA.GENOA_SP5(CHIPS)':
 'G3_RXP1||SATA21_RXP': CDS_PINID='\g3_rxp1||sata21_rxp\';
NODE_NAME     J38 A21
 '@T6G_MB_LIB.T6G(SCH_1):PAGE335_I168@PURE_QUANTA.SCONN168_ME1016810202011(CHIPS)':
 'PERP1': CDS_PINID='PERP1';
NET_NAME
'P5E_CPU0_G3_RX_DP<2>'
 '@T6G_MB_LIB.T6G(SCH_1):P5E_CPU0_G3_RX_DP'<2>:
 C_SIGNAL='@t6g_mb_lib.t6g(sch_1):p5e_cpu0_g3_rx_dp(2)';
NODE_NAME     U25 AN24
 '@T6G_MB_LIB.T6G(SCH_1):PAGE23_I216@PURE_QUANTA.GENOA_SP5(CHIPS)':
 'G3_RXP2||SATA22_RXP': CDS_PINID='\g3_rxp2||sata22_rxp\';
NODE_NAME     J38 A24
 '@T6G_MB_LIB.T6G(SCH_1):PAGE335_I168@PURE_QUANTA.SCONN168_ME1016810202011(CHIPS)':
 'PERP2': CDS_PINID='PERP2';
NET_NAME
'P5E_CPU0_G3_RX_DP<3>'
 '@T6G_MB_LIB.T6G(SCH_1):P5E_CPU0_G3_RX_DP'<3>:
 C_SIGNAL='@t6g_mb_lib.t6g(sch_1):p5e_cpu0_g3_rx_dp(3)';
NODE_NAME     U25 AL27
 '@T6G_MB_LIB.T6G(SCH_1):PAGE23_I216@PURE_QUANTA.GENOA_SP5(CHIPS)':
 'G3_RXP3||SATA23_RXP': CDS_PINID='\g3_rxp3||sata23_rxp\';
NODE_NAME     J38 A27
 '@T6G_MB_LIB.T6G(SCH_1):PAGE335_I168@PURE_QUANTA.SCONN168_ME1016810202011(CHIPS)':
 'PERP3': CDS_PINID='PERP3';
NET_NAME
'P5E_CPU0_G3_RX_DP<4>'
 '@T6G_MB_LIB.T6G(SCH_1):P5E_CPU0_G3_RX_DP'<4>:
 C_SIGNAL='@t6g_mb_lib.t6g(sch_1):p5e_cpu0_g3_rx_dp(4)';
NODE_NAME     U25 AJ27
 '@T6G_MB_LIB.T6G(SCH_1):PAGE23_I216@PURE_QUANTA.GENOA_SP5(CHIPS)':
 'G3_RXP4||SATA24_RXP': CDS_PINID='\g3_rxp4||sata24_rxp\';
NODE_NAME     J38 A31
 '@T6G_MB_LIB.T6G(SCH_1):PAGE335_I168@PURE_QUANTA.SCONN168_ME1016810202011(CHIPS)':
 'PERP4': CDS_PINID='PERP4';
NET_NAME
'P5E_CPU0_G3_RX_DP<5>'
 '@T6G_MB_LIB.T6G(SCH_1):P5E_CPU0_G3_RX_DP'<5>:
 C_SIGNAL='@t6g_mb_lib.t6g(sch_1):p5e_cpu0_g3_rx_dp(5)';
NODE_NAME     U25 AN27
 '@T6G_MB_LIB.T6G(SCH_1):PAGE23_I216@PURE_QUANTA.GENOA_SP5(CHIPS)':
 'G3_RXP5||SATA25_RXP': CDS_PINID='\g3_rxp5||sata25_rxp\';
NODE_NAME     J38 A34
 '@T6G_MB_LIB.T6G(SCH_1):PAGE335_I168@PURE_QUANTA.SCONN168_ME1016810202011(CHIPS)':
 'PERP5': CDS_PINID='PERP5';
NET_NAME
'P5E_CPU0_G3_RX_DP<6>'
 '@T6G_MB_LIB.T6G(SCH_1):P5E_CPU0_G3_RX_DP'<6>:
 C_SIGNAL='@t6g_mb_lib.t6g(sch_1):p5e_cpu0_g3_rx_dp(6)';
NODE_NAME     U25 AL30
 '@T6G_MB_LIB.T6G(SCH_1):PAGE23_I216@PURE_QUANTA.GENOA_SP5(CHIPS)':
 'G3_RXP6||SATA26_RXP': CDS_PINID='\g3_rxp6||sata26_rxp\';
NODE_NAME     J38 A37
 '@T6G_MB_LIB.T6G(SCH_1):PAGE335_I168@PURE_QUANTA.SCONN168_ME1016810202011(CHIPS)':
 'PERP6': CDS_PINID='PERP6';
NET_NAME
'P5E_CPU0_G3_RX_DP<7>'
 '@T6G_MB_LIB.T6G(SCH_1):P5E_CPU0_G3_RX_DP'<7>:
 C_SIGNAL='@t6g_mb_lib.t6g(sch_1):p5e_cpu0_g3_rx_dp(7)';
NODE_NAME     U25 AJ30
 '@T6G_MB_LIB.T6G(SCH_1):PAGE23_I216@PURE_QUANTA.GENOA_SP5(CHIPS)':
 'G3_RXP7||SATA27_RXP': CDS_PINID='\g3_rxp7||sata27_rxp\';
NODE_NAME     J38 A40
 '@T6G_MB_LIB.T6G(SCH_1):PAGE335_I168@PURE_QUANTA.SCONN168_ME1016810202011(CHIPS)':
 'PERP7': CDS_PINID='PERP7';
NET_NAME
'P5E_CPU0_G3_RX_DP<8>'
 '@T6G_MB_LIB.T6G(SCH_1):P5E_CPU0_G3_RX_DP'<8>:
 C_SIGNAL='@t6g_mb_lib.t6g(sch_1):p5e_cpu0_g3_rx_dp(8)';
NODE_NAME     U25 AN30
 '@T6G_MB_LIB.T6G(SCH_1):PAGE23_I216@PURE_QUANTA.GENOA_SP5(CHIPS)':
 'G3_RXP8||SATA30_RXP': CDS_PINID='\g3_rxp8||sata30_rxp\';
NODE_NAME     J38 A45
 '@T6G_MB_LIB.T6G(SCH_1):PAGE335_I168@PURE_QUANTA.SCONN168_ME1016810202011(CHIPS)':
 'PERP8': CDS_PINID='PERP8';
NET_NAME
'P5E_CPU0_G3_RX_DP<9>'
 '@T6G_MB_LIB.T6G(SCH_1):P5E_CPU0_G3_RX_DP'<9>:
 C_SIGNAL='@t6g_mb_lib.t6g(sch_1):p5e_cpu0_g3_rx_dp(9)';
NODE_NAME     U25 AL33
 '@T6G_MB_LIB.T6G(SCH_1):PAGE23_I216@PURE_QUANTA.GENOA_SP5(CHIPS)':
 'G3_RXP9||SATA31_RXP': CDS_PINID='\g3_rxp9||sata31_rxp\';
NODE_NAME     J38 A48
 '@T6G_MB_LIB.T6G(SCH_1):PAGE335_I168@PURE_QUANTA.SCONN168_ME1016810202011(CHIPS)':
 'PERP9': CDS_PINID='PERP9';
NET_NAME
'P5E_CPU0_G3_TX_C_DN<0>'
 '@T6G_MB_LIB.T6G(SCH_1):P5E_CPU0_G3_TX_C_DN'<0>:
 C_SIGNAL='@t6g_mb_lib.t6g(sch_1):p5e_cpu0_g3_tx_c_dn(0)';
NODE_NAME     J38 B18
 '@T6G_MB_LIB.T6G(SCH_1):PAGE335_I168@PURE_QUANTA.SCONN168_ME1016810202011(CHIPS)':
 'PETP0': CDS_PINID='PETP0';
NODE_NAME     C1578 1
 '@T6G_MB_LIB.T6G(SCH_1):PAGE353_I230@PURE_QUANTA.Q_CAP_DIFFBUS(CHIPS)':
 '1': CDS_PINID='\1\';
NET_NAME
'P5E_CPU0_G3_TX_C_DN<10>'
 '@T6G_MB_LIB.T6G(SCH_1):P5E_CPU0_G3_TX_C_DN'<10>:
 C_SIGNAL='@t6g_mb_lib.t6g(sch_1):p5e_cpu0_g3_tx_c_dn(10)';
NODE_NAME     J38 B51
 '@T6G_MB_LIB.T6G(SCH_1):PAGE335_I168@PURE_QUANTA.SCONN168_ME1016810202011(CHIPS)':
 'PETP10': CDS_PINID='PETP10';
NODE_NAME     C1558 1
 '@T6G_MB_LIB.T6G(SCH_1):PAGE353_I264@PURE_QUANTA.Q_CAP_DIFFBUS(CHIPS)':
 '1': CDS_PINID='\1\';
NET_NAME
'P5E_CPU0_G3_TX_C_DN<11>'
 '@T6G_MB_LIB.T6G(SCH_1):P5E_CPU0_G3_TX_C_DN'<11>:
 C_SIGNAL='@t6g_mb_lib.t6g(sch_1):p5e_cpu0_g3_tx_c_dn(11)';
NODE_NAME     J38 B54
 '@T6G_MB_LIB.T6G(SCH_1):PAGE335_I168@PURE_QUANTA.SCONN168_ME1016810202011(CHIPS)':
 'PETP11': CDS_PINID='PETP11';
NODE_NAME     C1556 1
 '@T6G_MB_LIB.T6G(SCH_1):PAGE353_I265@PURE_QUANTA.Q_CAP_DIFFBUS(CHIPS)':
 '1': CDS_PINID='\1\';
NET_NAME
'P5E_CPU0_G3_TX_C_DN<12>'
 '@T6G_MB_LIB.T6G(SCH_1):P5E_CPU0_G3_TX_C_DN'<12>:
 C_SIGNAL='@t6g_mb_lib.t6g(sch_1):p5e_cpu0_g3_tx_c_dn(12)';
NODE_NAME     J38 B57
 '@T6G_MB_LIB.T6G(SCH_1):PAGE335_I168@PURE_QUANTA.SCONN168_ME1016810202011(CHIPS)':
 'PETP12': CDS_PINID='PETP12';
NODE_NAME     C41 1
 '@T6G_MB_LIB.T6G(SCH_1):PAGE353_I268@PURE_QUANTA.Q_CAP_DIFFBUS(CHIPS)':
 '1': CDS_PINID='\1\';
NET_NAME
'P5E_CPU0_G3_TX_C_DN<13>'
 '@T6G_MB_LIB.T6G(SCH_1):P5E_CPU0_G3_TX_C_DN'<13>:
 C_SIGNAL='@t6g_mb_lib.t6g(sch_1):p5e_cpu0_g3_tx_c_dn(13)';
NODE_NAME     J38 B60
 '@T6G_MB_LIB.T6G(SCH_1):PAGE335_I168@PURE_QUANTA.SCONN168_ME1016810202011(CHIPS)':
 'PETP13': CDS_PINID='PETP13';
NODE_NAME     C1552 1
 '@T6G_MB_LIB.T6G(SCH_1):PAGE353_I270@PURE_QUANTA.Q_CAP_DIFFBUS(CHIPS)':
 '1': CDS_PINID='\1\';
NET_NAME
'P5E_CPU0_G3_TX_C_DN<14>'
 '@T6G_MB_LIB.T6G(SCH_1):P5E_CPU0_G3_TX_C_DN'<14>:
 C_SIGNAL='@t6g_mb_lib.t6g(sch_1):p5e_cpu0_g3_tx_c_dn(14)';
NODE_NAME     J38 B63
 '@T6G_MB_LIB.T6G(SCH_1):PAGE335_I168@PURE_QUANTA.SCONN168_ME1016810202011(CHIPS)':
 'PETP14': CDS_PINID='PETP14';
NODE_NAME     C1550 1
 '@T6G_MB_LIB.T6G(SCH_1):PAGE353_I272@PURE_QUANTA.Q_CAP_DIFFBUS(CHIPS)':
 '1': CDS_PINID='\1\';
NET_NAME
'P5E_CPU0_G3_TX_C_DN<15>'
 '@T6G_MB_LIB.T6G(SCH_1):P5E_CPU0_G3_TX_C_DN'<15>:
 C_SIGNAL='@t6g_mb_lib.t6g(sch_1):p5e_cpu0_g3_tx_c_dn(15)';
NODE_NAME     J38 B66
 '@T6G_MB_LIB.T6G(SCH_1):PAGE335_I168@PURE_QUANTA.SCONN168_ME1016810202011(CHIPS)':
 'PETP15': CDS_PINID='PETP15';
NODE_NAME     C1548 1
 '@T6G_MB_LIB.T6G(SCH_1):PAGE353_I273@PURE_QUANTA.Q_CAP_DIFFBUS(CHIPS)':
 '1': CDS_PINID='\1\';
NET_NAME
'P5E_CPU0_G3_TX_C_DN<1>'
 '@T6G_MB_LIB.T6G(SCH_1):P5E_CPU0_G3_TX_C_DN'<1>:
 C_SIGNAL='@t6g_mb_lib.t6g(sch_1):p5e_cpu0_g3_tx_c_dn(1)';
NODE_NAME     J38 B21
 '@T6G_MB_LIB.T6G(SCH_1):PAGE335_I168@PURE_QUANTA.SCONN168_ME1016810202011(CHIPS)':
 'PETP1': CDS_PINID='PETP1';
NODE_NAME     C1576 1
 '@T6G_MB_LIB.T6G(SCH_1):PAGE353_I312@PURE_QUANTA.Q_CAP_DIFFBUS(CHIPS)':
 '1': CDS_PINID='\1\';
NET_NAME
'P5E_CPU0_G3_TX_C_DN<2>'
 '@T6G_MB_LIB.T6G(SCH_1):P5E_CPU0_G3_TX_C_DN'<2>:
 C_SIGNAL='@t6g_mb_lib.t6g(sch_1):p5e_cpu0_g3_tx_c_dn(2)';
NODE_NAME     J38 B24
 '@T6G_MB_LIB.T6G(SCH_1):PAGE335_I168@PURE_QUANTA.SCONN168_ME1016810202011(CHIPS)':
 'PETP2': CDS_PINID='PETP2';
NODE_NAME     C1574 1
 '@T6G_MB_LIB.T6G(SCH_1):PAGE353_I232@PURE_QUANTA.Q_CAP_DIFFBUS(CHIPS)':
 '1': CDS_PINID='\1\';
NET_NAME
'P5E_CPU0_G3_TX_C_DN<3>'
 '@T6G_MB_LIB.T6G(SCH_1):P5E_CPU0_G3_TX_C_DN'<3>:
 C_SIGNAL='@t6g_mb_lib.t6g(sch_1):p5e_cpu0_g3_tx_c_dn(3)';
NODE_NAME     J38 B27
 '@T6G_MB_LIB.T6G(SCH_1):PAGE335_I168@PURE_QUANTA.SCONN168_ME1016810202011(CHIPS)':
 'PETP3': CDS_PINID='PETP3';
NODE_NAME     C1572 1
 '@T6G_MB_LIB.T6G(SCH_1):PAGE353_I234@PURE_QUANTA.Q_CAP_DIFFBUS(CHIPS)':
 '1': CDS_PINID='\1\';
NET_NAME
'P5E_CPU0_G3_TX_C_DN<4>'
 '@T6G_MB_LIB.T6G(SCH_1):P5E_CPU0_G3_TX_C_DN'<4>:
 C_SIGNAL='@t6g_mb_lib.t6g(sch_1):p5e_cpu0_g3_tx_c_dn(4)';
NODE_NAME     J38 B31
 '@T6G_MB_LIB.T6G(SCH_1):PAGE335_I168@PURE_QUANTA.SCONN168_ME1016810202011(CHIPS)':
 'PETP4': CDS_PINID='PETP4';
NODE_NAME     C1570 1
 '@T6G_MB_LIB.T6G(SCH_1):PAGE353_I235@PURE_QUANTA.Q_CAP_DIFFBUS(CHIPS)':
 '1': CDS_PINID='\1\';
NET_NAME
'P5E_CPU0_G3_TX_C_DN<5>'
 '@T6G_MB_LIB.T6G(SCH_1):P5E_CPU0_G3_TX_C_DN'<5>:
 C_SIGNAL='@t6g_mb_lib.t6g(sch_1):p5e_cpu0_g3_tx_c_dn(5)';
NODE_NAME     J38 B34
 '@T6G_MB_LIB.T6G(SCH_1):PAGE335_I168@PURE_QUANTA.SCONN168_ME1016810202011(CHIPS)':
 'PETP5': CDS_PINID='PETP5';
NODE_NAME     C1568 1
 '@T6G_MB_LIB.T6G(SCH_1):PAGE353_I238@PURE_QUANTA.Q_CAP_DIFFBUS(CHIPS)':
 '1': CDS_PINID='\1\';
NET_NAME
'P5E_CPU0_G3_TX_C_DN<6>'
 '@T6G_MB_LIB.T6G(SCH_1):P5E_CPU0_G3_TX_C_DN'<6>:
 C_SIGNAL='@t6g_mb_lib.t6g(sch_1):p5e_cpu0_g3_tx_c_dn(6)';
NODE_NAME     J38 B37
 '@T6G_MB_LIB.T6G(SCH_1):PAGE335_I168@PURE_QUANTA.SCONN168_ME1016810202011(CHIPS)':
 'PETP6': CDS_PINID='PETP6';
NODE_NAME     C1566 1
 '@T6G_MB_LIB.T6G(SCH_1):PAGE353_I240@PURE_QUANTA.Q_CAP_DIFFBUS(CHIPS)':
 '1': CDS_PINID='\1\';
NET_NAME
'P5E_CPU0_G3_TX_C_DN<7>'
 '@T6G_MB_LIB.T6G(SCH_1):P5E_CPU0_G3_TX_C_DN'<7>:
 C_SIGNAL='@t6g_mb_lib.t6g(sch_1):p5e_cpu0_g3_tx_c_dn(7)';
NODE_NAME     J38 B40
 '@T6G_MB_LIB.T6G(SCH_1):PAGE335_I168@PURE_QUANTA.SCONN168_ME1016810202011(CHIPS)':
 'PETP7': CDS_PINID='PETP7';
NODE_NAME     C46 1
 '@T6G_MB_LIB.T6G(SCH_1):PAGE353_I242@PURE_QUANTA.Q_CAP_DIFFBUS(CHIPS)':
 '1': CDS_PINID='\1\';
NET_NAME
'P5E_CPU0_G3_TX_C_DN<8>'
 '@T6G_MB_LIB.T6G(SCH_1):P5E_CPU0_G3_TX_C_DN'<8>:
 C_SIGNAL='@t6g_mb_lib.t6g(sch_1):p5e_cpu0_g3_tx_c_dn(8)';
NODE_NAME     J38 B45
 '@T6G_MB_LIB.T6G(SCH_1):PAGE335_I168@PURE_QUANTA.SCONN168_ME1016810202011(CHIPS)':
 'PETP8': CDS_PINID='PETP8';
NODE_NAME     C1794 1
 '@T6G_MB_LIB.T6G(SCH_1):PAGE353_I260@PURE_QUANTA.Q_CAP_DIFFBUS(CHIPS)':
 '1': CDS_PINID='\1\';
NET_NAME
'P5E_CPU0_G3_TX_C_DN<9>'
 '@T6G_MB_LIB.T6G(SCH_1):P5E_CPU0_G3_TX_C_DN'<9>:
 C_SIGNAL='@t6g_mb_lib.t6g(sch_1):p5e_cpu0_g3_tx_c_dn(9)';
NODE_NAME     J38 B48
 '@T6G_MB_LIB.T6G(SCH_1):PAGE335_I168@PURE_QUANTA.SCONN168_ME1016810202011(CHIPS)':
 'PETP9': CDS_PINID='PETP9';
NODE_NAME     C1560 1
 '@T6G_MB_LIB.T6G(SCH_1):PAGE353_I262@PURE_QUANTA.Q_CAP_DIFFBUS(CHIPS)':
 '1': CDS_PINID='\1\';
NET_NAME
'P5E_CPU0_G3_TX_C_DP<0>'
 '@T6G_MB_LIB.T6G(SCH_1):P5E_CPU0_G3_TX_C_DP'<0>:
 C_SIGNAL='@t6g_mb_lib.t6g(sch_1):p5e_cpu0_g3_tx_c_dp(0)';
NODE_NAME     J38 B17
 '@T6G_MB_LIB.T6G(SCH_1):PAGE335_I168@PURE_QUANTA.SCONN168_ME1016810202011(CHIPS)':
 'PETN0': CDS_PINID='PETN0';
NODE_NAME     C1579 1
 '@T6G_MB_LIB.T6G(SCH_1):PAGE353_I229@PURE_QUANTA.Q_CAP_DIFFBUS(CHIPS)':
 '1': CDS_PINID='\1\';
NET_NAME
'P5E_CPU0_G3_TX_C_DP<10>'
 '@T6G_MB_LIB.T6G(SCH_1):P5E_CPU0_G3_TX_C_DP'<10>:
 C_SIGNAL='@t6g_mb_lib.t6g(sch_1):p5e_cpu0_g3_tx_c_dp(10)';
NODE_NAME     J38 B50
 '@T6G_MB_LIB.T6G(SCH_1):PAGE335_I168@PURE_QUANTA.SCONN168_ME1016810202011(CHIPS)':
 'PETN10': CDS_PINID='PETN10';
NODE_NAME     C1559 1
 '@T6G_MB_LIB.T6G(SCH_1):PAGE353_I263@PURE_QUANTA.Q_CAP_DIFFBUS(CHIPS)':
 '1': CDS_PINID='\1\';
NET_NAME
'P5E_CPU0_G3_TX_C_DP<11>'
 '@T6G_MB_LIB.T6G(SCH_1):P5E_CPU0_G3_TX_C_DP'<11>:
 C_SIGNAL='@t6g_mb_lib.t6g(sch_1):p5e_cpu0_g3_tx_c_dp(11)';
NODE_NAME     J38 B53
 '@T6G_MB_LIB.T6G(SCH_1):PAGE335_I168@PURE_QUANTA.SCONN168_ME1016810202011(CHIPS)':
 'PETN11': CDS_PINID='PETN11';
NODE_NAME     C1557 1
 '@T6G_MB_LIB.T6G(SCH_1):PAGE353_I266@PURE_QUANTA.Q_CAP_DIFFBUS(CHIPS)':
 '1': CDS_PINID='\1\';
NET_NAME
'P5E_CPU0_G3_TX_C_DP<12>'
 '@T6G_MB_LIB.T6G(SCH_1):P5E_CPU0_G3_TX_C_DP'<12>:
 C_SIGNAL='@t6g_mb_lib.t6g(sch_1):p5e_cpu0_g3_tx_c_dp(12)';
NODE_NAME     J38 B56
 '@T6G_MB_LIB.T6G(SCH_1):PAGE335_I168@PURE_QUANTA.SCONN168_ME1016810202011(CHIPS)':
 'PETN12': CDS_PINID='PETN12';
NODE_NAME     C1555 1
 '@T6G_MB_LIB.T6G(SCH_1):PAGE353_I267@PURE_QUANTA.Q_CAP_DIFFBUS(CHIPS)':
 '1': CDS_PINID='\1\';
NET_NAME
'P5E_CPU0_G3_TX_C_DP<13>'
 '@T6G_MB_LIB.T6G(SCH_1):P5E_CPU0_G3_TX_C_DP'<13>:
 C_SIGNAL='@t6g_mb_lib.t6g(sch_1):p5e_cpu0_g3_tx_c_dp(13)';
NODE_NAME     J38 B59
 '@T6G_MB_LIB.T6G(SCH_1):PAGE335_I168@PURE_QUANTA.SCONN168_ME1016810202011(CHIPS)':
 'PETN13': CDS_PINID='PETN13';
NODE_NAME     C1553 1
 '@T6G_MB_LIB.T6G(SCH_1):PAGE353_I269@PURE_QUANTA.Q_CAP_DIFFBUS(CHIPS)':
 '1': CDS_PINID='\1\';
NET_NAME
'P5E_CPU0_G3_TX_C_DP<14>'
 '@T6G_MB_LIB.T6G(SCH_1):P5E_CPU0_G3_TX_C_DP'<14>:
 C_SIGNAL='@t6g_mb_lib.t6g(sch_1):p5e_cpu0_g3_tx_c_dp(14)';
NODE_NAME     J38 B62
 '@T6G_MB_LIB.T6G(SCH_1):PAGE335_I168@PURE_QUANTA.SCONN168_ME1016810202011(CHIPS)':
 'PETN14': CDS_PINID='PETN14';
NODE_NAME     C1792 1
 '@T6G_MB_LIB.T6G(SCH_1):PAGE353_I271@PURE_QUANTA.Q_CAP_DIFFBUS(CHIPS)':
 '1': CDS_PINID='\1\';
NET_NAME
'P5E_CPU0_G3_TX_C_DP<15>'
 '@T6G_MB_LIB.T6G(SCH_1):P5E_CPU0_G3_TX_C_DP'<15>:
 C_SIGNAL='@t6g_mb_lib.t6g(sch_1):p5e_cpu0_g3_tx_c_dp(15)';
NODE_NAME     J38 B65
 '@T6G_MB_LIB.T6G(SCH_1):PAGE335_I168@PURE_QUANTA.SCONN168_ME1016810202011(CHIPS)':
 'PETN15': CDS_PINID='PETN15';
NODE_NAME     C1549 1
 '@T6G_MB_LIB.T6G(SCH_1):PAGE353_I274@PURE_QUANTA.Q_CAP_DIFFBUS(CHIPS)':
 '1': CDS_PINID='\1\';
NET_NAME
'P5E_CPU0_G3_TX_C_DP<1>'
 '@T6G_MB_LIB.T6G(SCH_1):P5E_CPU0_G3_TX_C_DP'<1>:
 C_SIGNAL='@t6g_mb_lib.t6g(sch_1):p5e_cpu0_g3_tx_c_dp(1)';
NODE_NAME     J38 B20
 '@T6G_MB_LIB.T6G(SCH_1):PAGE335_I168@PURE_QUANTA.SCONN168_ME1016810202011(CHIPS)':
 'PETN1': CDS_PINID='PETN1';
NODE_NAME     C1577 1
 '@T6G_MB_LIB.T6G(SCH_1):PAGE353_I311@PURE_QUANTA.Q_CAP_DIFFBUS(CHIPS)':
 '1': CDS_PINID='\1\';
NET_NAME
'P5E_CPU0_G3_TX_C_DP<2>'
 '@T6G_MB_LIB.T6G(SCH_1):P5E_CPU0_G3_TX_C_DP'<2>:
 C_SIGNAL='@t6g_mb_lib.t6g(sch_1):p5e_cpu0_g3_tx_c_dp(2)';
NODE_NAME     J38 B23
 '@T6G_MB_LIB.T6G(SCH_1):PAGE335_I168@PURE_QUANTA.SCONN168_ME1016810202011(CHIPS)':
 'PETN2': CDS_PINID='PETN2';
NODE_NAME     C1575 1
 '@T6G_MB_LIB.T6G(SCH_1):PAGE353_I231@PURE_QUANTA.Q_CAP_DIFFBUS(CHIPS)':
 '1': CDS_PINID='\1\';
NET_NAME
'P5E_CPU0_G3_TX_C_DP<3>'
 '@T6G_MB_LIB.T6G(SCH_1):P5E_CPU0_G3_TX_C_DP'<3>:
 C_SIGNAL='@t6g_mb_lib.t6g(sch_1):p5e_cpu0_g3_tx_c_dp(3)';
NODE_NAME     J38 B26
 '@T6G_MB_LIB.T6G(SCH_1):PAGE335_I168@PURE_QUANTA.SCONN168_ME1016810202011(CHIPS)':
 'PETN3': CDS_PINID='PETN3';
NODE_NAME     C1573 1
 '@T6G_MB_LIB.T6G(SCH_1):PAGE353_I233@PURE_QUANTA.Q_CAP_DIFFBUS(CHIPS)':
 '1': CDS_PINID='\1\';
NET_NAME
'P5E_CPU0_G3_TX_C_DP<4>'
 '@T6G_MB_LIB.T6G(SCH_1):P5E_CPU0_G3_TX_C_DP'<4>:
 C_SIGNAL='@t6g_mb_lib.t6g(sch_1):p5e_cpu0_g3_tx_c_dp(4)';
NODE_NAME     J38 B30
 '@T6G_MB_LIB.T6G(SCH_1):PAGE335_I168@PURE_QUANTA.SCONN168_ME1016810202011(CHIPS)':
 'PETN4': CDS_PINID='PETN4';
NODE_NAME     C1571 1
 '@T6G_MB_LIB.T6G(SCH_1):PAGE353_I236@PURE_QUANTA.Q_CAP_DIFFBUS(CHIPS)':
 '1': CDS_PINID='\1\';
NET_NAME
'P5E_CPU0_G3_TX_C_DP<5>'
 '@T6G_MB_LIB.T6G(SCH_1):P5E_CPU0_G3_TX_C_DP'<5>:
 C_SIGNAL='@t6g_mb_lib.t6g(sch_1):p5e_cpu0_g3_tx_c_dp(5)';
NODE_NAME     J38 B33
 '@T6G_MB_LIB.T6G(SCH_1):PAGE335_I168@PURE_QUANTA.SCONN168_ME1016810202011(CHIPS)':
 'PETN5': CDS_PINID='PETN5';
NODE_NAME     C1569 1
 '@T6G_MB_LIB.T6G(SCH_1):PAGE353_I237@PURE_QUANTA.Q_CAP_DIFFBUS(CHIPS)':
 '1': CDS_PINID='\1\';
NET_NAME
'P5E_CPU0_G3_TX_C_DP<6>'
 '@T6G_MB_LIB.T6G(SCH_1):P5E_CPU0_G3_TX_C_DP'<6>:
 C_SIGNAL='@t6g_mb_lib.t6g(sch_1):p5e_cpu0_g3_tx_c_dp(6)';
NODE_NAME     J38 B36
 '@T6G_MB_LIB.T6G(SCH_1):PAGE335_I168@PURE_QUANTA.SCONN168_ME1016810202011(CHIPS)':
 'PETN6': CDS_PINID='PETN6';
NODE_NAME     C47 1
 '@T6G_MB_LIB.T6G(SCH_1):PAGE353_I239@PURE_QUANTA.Q_CAP_DIFFBUS(CHIPS)':
 '1': CDS_PINID='\1\';
NET_NAME
'P5E_CPU0_G3_TX_C_DP<7>'
 '@T6G_MB_LIB.T6G(SCH_1):P5E_CPU0_G3_TX_C_DP'<7>:
 C_SIGNAL='@t6g_mb_lib.t6g(sch_1):p5e_cpu0_g3_tx_c_dp(7)';
NODE_NAME     J38 B39
 '@T6G_MB_LIB.T6G(SCH_1):PAGE335_I168@PURE_QUANTA.SCONN168_ME1016810202011(CHIPS)':
 'PETN7': CDS_PINID='PETN7';
NODE_NAME     C1565 1
 '@T6G_MB_LIB.T6G(SCH_1):PAGE353_I241@PURE_QUANTA.Q_CAP_DIFFBUS(CHIPS)':
 '1': CDS_PINID='\1\';
NET_NAME
'P5E_CPU0_G3_TX_C_DP<8>'
 '@T6G_MB_LIB.T6G(SCH_1):P5E_CPU0_G3_TX_C_DP'<8>:
 C_SIGNAL='@t6g_mb_lib.t6g(sch_1):p5e_cpu0_g3_tx_c_dp(8)';
NODE_NAME     J38 B44
 '@T6G_MB_LIB.T6G(SCH_1):PAGE335_I168@PURE_QUANTA.SCONN168_ME1016810202011(CHIPS)':
 'PETN8': CDS_PINID='PETN8';
NODE_NAME     C44 1
 '@T6G_MB_LIB.T6G(SCH_1):PAGE353_I259@PURE_QUANTA.Q_CAP_DIFFBUS(CHIPS)':
 '1': CDS_PINID='\1\';
NET_NAME
'P5E_CPU0_G3_TX_C_DP<9>'
 '@T6G_MB_LIB.T6G(SCH_1):P5E_CPU0_G3_TX_C_DP'<9>:
 C_SIGNAL='@t6g_mb_lib.t6g(sch_1):p5e_cpu0_g3_tx_c_dp(9)';
NODE_NAME     J38 B47
 '@T6G_MB_LIB.T6G(SCH_1):PAGE335_I168@PURE_QUANTA.SCONN168_ME1016810202011(CHIPS)':
 'PETN9': CDS_PINID='PETN9';
NODE_NAME     C1793 1
 '@T6G_MB_LIB.T6G(SCH_1):PAGE353_I261@PURE_QUANTA.Q_CAP_DIFFBUS(CHIPS)':
 '1': CDS_PINID='\1\';
NET_NAME
'P5E_CPU0_G3_TX_DN<0>'
 '@T6G_MB_LIB.T6G(SCH_1):P5E_CPU0_G3_TX_DN'<0>:
 C_SIGNAL='@t6g_mb_lib.t6g(sch_1):p5e_cpu0_g3_tx_dn(0)';
NODE_NAME     U25 U24
 '@T6G_MB_LIB.T6G(SCH_1):PAGE23_I216@PURE_QUANTA.GENOA_SP5(CHIPS)':
 'G3_TXN0||SATA20_TXN': CDS_PINID='\g3_txn0||sata20_txn\';
NODE_NAME     C1578 2
 '@T6G_MB_LIB.T6G(SCH_1):PAGE353_I230@PURE_QUANTA.Q_CAP_DIFFBUS(CHIPS)':
 '2': CDS_PINID='\2\';
NET_NAME
'P5E_CPU0_G3_TX_DN<10>'
 '@T6G_MB_LIB.T6G(SCH_1):P5E_CPU0_G3_TX_DN'<10>:
 C_SIGNAL='@t6g_mb_lib.t6g(sch_1):p5e_cpu0_g3_tx_dn(10)';
NODE_NAME     U25 R33
 '@T6G_MB_LIB.T6G(SCH_1):PAGE23_I216@PURE_QUANTA.GENOA_SP5(CHIPS)':
 'G3_TXN10||SATA32_TXN': CDS_PINID='\g3_txn10||sata32_txn\';
NODE_NAME     C1558 2
 '@T6G_MB_LIB.T6G(SCH_1):PAGE353_I264@PURE_QUANTA.Q_CAP_DIFFBUS(CHIPS)':
 '2': CDS_PINID='\2\';
NET_NAME
'P5E_CPU0_G3_TX_DN<11>'
 '@T6G_MB_LIB.T6G(SCH_1):P5E_CPU0_G3_TX_DN'<11>:
 C_SIGNAL='@t6g_mb_lib.t6g(sch_1):p5e_cpu0_g3_tx_dn(11)';
NODE_NAME     U25 N33
 '@T6G_MB_LIB.T6G(SCH_1):PAGE23_I216@PURE_QUANTA.GENOA_SP5(CHIPS)':
 'G3_TXN11||SATA33_TXN': CDS_PINID='\g3_txn11||sata33_txn\';
NODE_NAME     C1556 2
 '@T6G_MB_LIB.T6G(SCH_1):PAGE353_I265@PURE_QUANTA.Q_CAP_DIFFBUS(CHIPS)':
 '2': CDS_PINID='\2\';
NET_NAME
'P5E_CPU0_G3_TX_DN<12>'
 '@T6G_MB_LIB.T6G(SCH_1):P5E_CPU0_G3_TX_DN'<12>:
 C_SIGNAL='@t6g_mb_lib.t6g(sch_1):p5e_cpu0_g3_tx_dn(12)';
NODE_NAME     U25 U33
 '@T6G_MB_LIB.T6G(SCH_1):PAGE23_I216@PURE_QUANTA.GENOA_SP5(CHIPS)':
 'G3_TXN12||SATA34_TXN': CDS_PINID='\g3_txn12||sata34_txn\';
NODE_NAME     C41 2
 '@T6G_MB_LIB.T6G(SCH_1):PAGE353_I268@PURE_QUANTA.Q_CAP_DIFFBUS(CHIPS)':
 '2': CDS_PINID='\2\';
NET_NAME
'P5E_CPU0_G3_TX_DN<13>'
 '@T6G_MB_LIB.T6G(SCH_1):P5E_CPU0_G3_TX_DN'<13>:
 C_SIGNAL='@t6g_mb_lib.t6g(sch_1):p5e_cpu0_g3_tx_dn(13)';
NODE_NAME     U25 P36
 '@T6G_MB_LIB.T6G(SCH_1):PAGE23_I216@PURE_QUANTA.GENOA_SP5(CHIPS)':
 'G3_TXN13||SATA35_TXN': CDS_PINID='\g3_txn13||sata35_txn\';
NODE_NAME     C1552 2
 '@T6G_MB_LIB.T6G(SCH_1):PAGE353_I270@PURE_QUANTA.Q_CAP_DIFFBUS(CHIPS)':
 '2': CDS_PINID='\2\';
NET_NAME
'P5E_CPU0_G3_TX_DN<14>'
 '@T6G_MB_LIB.T6G(SCH_1):P5E_CPU0_G3_TX_DN'<14>:
 C_SIGNAL='@t6g_mb_lib.t6g(sch_1):p5e_cpu0_g3_tx_dn(14)';
NODE_NAME     U25 T36
 '@T6G_MB_LIB.T6G(SCH_1):PAGE23_I216@PURE_QUANTA.GENOA_SP5(CHIPS)':
 'G3_TXN14||SATA36_TXN': CDS_PINID='\g3_txn14||sata36_txn\';
NODE_NAME     C1550 2
 '@T6G_MB_LIB.T6G(SCH_1):PAGE353_I272@PURE_QUANTA.Q_CAP_DIFFBUS(CHIPS)':
 '2': CDS_PINID='\2\';
NET_NAME
'P5E_CPU0_G3_TX_DN<15>'
 '@T6G_MB_LIB.T6G(SCH_1):P5E_CPU0_G3_TX_DN'<15>:
 C_SIGNAL='@t6g_mb_lib.t6g(sch_1):p5e_cpu0_g3_tx_dn(15)';
NODE_NAME     U25 V36
 '@T6G_MB_LIB.T6G(SCH_1):PAGE23_I216@PURE_QUANTA.GENOA_SP5(CHIPS)':
 'G3_TXN15||SATA37_TXN': CDS_PINID='\g3_txn15||sata37_txn\';
NODE_NAME     C1548 2
 '@T6G_MB_LIB.T6G(SCH_1):PAGE353_I273@PURE_QUANTA.Q_CAP_DIFFBUS(CHIPS)':
 '2': CDS_PINID='\2\';
NET_NAME
'P5E_CPU0_G3_TX_DN<1>'
 '@T6G_MB_LIB.T6G(SCH_1):P5E_CPU0_G3_TX_DN'<1>:
 C_SIGNAL='@t6g_mb_lib.t6g(sch_1):p5e_cpu0_g3_tx_dn(1)';
NODE_NAME     U25 R24
 '@T6G_MB_LIB.T6G(SCH_1):PAGE23_I216@PURE_QUANTA.GENOA_SP5(CHIPS)':
 'G3_TXN1||SATA21_TXN': CDS_PINID='\g3_txn1||sata21_txn\';
NODE_NAME     C1576 2
 '@T6G_MB_LIB.T6G(SCH_1):PAGE353_I312@PURE_QUANTA.Q_CAP_DIFFBUS(CHIPS)':
 '2': CDS_PINID='\2\';
NET_NAME
'P5E_CPU0_G3_TX_DN<2>'
 '@T6G_MB_LIB.T6G(SCH_1):P5E_CPU0_G3_TX_DN'<2>:
 C_SIGNAL='@t6g_mb_lib.t6g(sch_1):p5e_cpu0_g3_tx_dn(2)';
NODE_NAME     U25 W24
 '@T6G_MB_LIB.T6G(SCH_1):PAGE23_I216@PURE_QUANTA.GENOA_SP5(CHIPS)':
 'G3_TXN2||SATA22_TXN': CDS_PINID='\g3_txn2||sata22_txn\';
NODE_NAME     C1574 2
 '@T6G_MB_LIB.T6G(SCH_1):PAGE353_I232@PURE_QUANTA.Q_CAP_DIFFBUS(CHIPS)':
 '2': CDS_PINID='\2\';
NET_NAME
'P5E_CPU0_G3_TX_DN<3>'
 '@T6G_MB_LIB.T6G(SCH_1):P5E_CPU0_G3_TX_DN'<3>:
 C_SIGNAL='@t6g_mb_lib.t6g(sch_1):p5e_cpu0_g3_tx_dn(3)';
NODE_NAME     U25 U27
 '@T6G_MB_LIB.T6G(SCH_1):PAGE23_I216@PURE_QUANTA.GENOA_SP5(CHIPS)':
 'G3_TXN3||SATA23_TXN': CDS_PINID='\g3_txn3||sata23_txn\';
NODE_NAME     C1572 2
 '@T6G_MB_LIB.T6G(SCH_1):PAGE353_I234@PURE_QUANTA.Q_CAP_DIFFBUS(CHIPS)':
 '2': CDS_PINID='\2\';
NET_NAME
'P5E_CPU0_G3_TX_DN<4>'
 '@T6G_MB_LIB.T6G(SCH_1):P5E_CPU0_G3_TX_DN'<4>:
 C_SIGNAL='@t6g_mb_lib.t6g(sch_1):p5e_cpu0_g3_tx_dn(4)';
NODE_NAME     U25 R27
 '@T6G_MB_LIB.T6G(SCH_1):PAGE23_I216@PURE_QUANTA.GENOA_SP5(CHIPS)':
 'G3_TXN4||SATA24_TXN': CDS_PINID='\g3_txn4||sata24_txn\';
NODE_NAME     C1570 2
 '@T6G_MB_LIB.T6G(SCH_1):PAGE353_I235@PURE_QUANTA.Q_CAP_DIFFBUS(CHIPS)':
 '2': CDS_PINID='\2\';
NET_NAME
'P5E_CPU0_G3_TX_DN<5>'
 '@T6G_MB_LIB.T6G(SCH_1):P5E_CPU0_G3_TX_DN'<5>:
 C_SIGNAL='@t6g_mb_lib.t6g(sch_1):p5e_cpu0_g3_tx_dn(5)';
NODE_NAME     U25 N27
 '@T6G_MB_LIB.T6G(SCH_1):PAGE23_I216@PURE_QUANTA.GENOA_SP5(CHIPS)':
 'G3_TXN5||SATA25_TXN': CDS_PINID='\g3_txn5||sata25_txn\';
NODE_NAME     C1568 2
 '@T6G_MB_LIB.T6G(SCH_1):PAGE353_I238@PURE_QUANTA.Q_CAP_DIFFBUS(CHIPS)':
 '2': CDS_PINID='\2\';
NET_NAME
'P5E_CPU0_G3_TX_DN<6>'
 '@T6G_MB_LIB.T6G(SCH_1):P5E_CPU0_G3_TX_DN'<6>:
 C_SIGNAL='@t6g_mb_lib.t6g(sch_1):p5e_cpu0_g3_tx_dn(6)';
NODE_NAME     U25 W27
 '@T6G_MB_LIB.T6G(SCH_1):PAGE23_I216@PURE_QUANTA.GENOA_SP5(CHIPS)':
 'G3_TXN6||SATA26_TXN': CDS_PINID='\g3_txn6||sata26_txn\';
NODE_NAME     C1566 2
 '@T6G_MB_LIB.T6G(SCH_1):PAGE353_I240@PURE_QUANTA.Q_CAP_DIFFBUS(CHIPS)':
 '2': CDS_PINID='\2\';
NET_NAME
'P5E_CPU0_G3_TX_DN<7>'
 '@T6G_MB_LIB.T6G(SCH_1):P5E_CPU0_G3_TX_DN'<7>:
 C_SIGNAL='@t6g_mb_lib.t6g(sch_1):p5e_cpu0_g3_tx_dn(7)';
NODE_NAME     U25 R30
 '@T6G_MB_LIB.T6G(SCH_1):PAGE23_I216@PURE_QUANTA.GENOA_SP5(CHIPS)':
 'G3_TXN7||SATA27_TXN': CDS_PINID='\g3_txn7||sata27_txn\';
NODE_NAME     C46 2
 '@T6G_MB_LIB.T6G(SCH_1):PAGE353_I242@PURE_QUANTA.Q_CAP_DIFFBUS(CHIPS)':
 '2': CDS_PINID='\2\';
NET_NAME
'P5E_CPU0_G3_TX_DN<8>'
 '@T6G_MB_LIB.T6G(SCH_1):P5E_CPU0_G3_TX_DN'<8>:
 C_SIGNAL='@t6g_mb_lib.t6g(sch_1):p5e_cpu0_g3_tx_dn(8)';
NODE_NAME     U25 N30
 '@T6G_MB_LIB.T6G(SCH_1):PAGE23_I216@PURE_QUANTA.GENOA_SP5(CHIPS)':
 'G3_TXN8||SATA30_TXN': CDS_PINID='\g3_txn8||sata30_txn\';
NODE_NAME     C1794 2
 '@T6G_MB_LIB.T6G(SCH_1):PAGE353_I260@PURE_QUANTA.Q_CAP_DIFFBUS(CHIPS)':
 '2': CDS_PINID='\2\';
NET_NAME
'P5E_CPU0_G3_TX_DN<9>'
 '@T6G_MB_LIB.T6G(SCH_1):P5E_CPU0_G3_TX_DN'<9>:
 C_SIGNAL='@t6g_mb_lib.t6g(sch_1):p5e_cpu0_g3_tx_dn(9)';
NODE_NAME     U25 U30
 '@T6G_MB_LIB.T6G(SCH_1):PAGE23_I216@PURE_QUANTA.GENOA_SP5(CHIPS)':
 'G3_TXN9||SATA31_TXN': CDS_PINID='\g3_txn9||sata31_txn\';
NODE_NAME     C1560 2
 '@T6G_MB_LIB.T6G(SCH_1):PAGE353_I262@PURE_QUANTA.Q_CAP_DIFFBUS(CHIPS)':
 '2': CDS_PINID='\2\';
NET_NAME
'P5E_CPU0_G3_TX_DP<0>'
 '@T6G_MB_LIB.T6G(SCH_1):P5E_CPU0_G3_TX_DP'<0>:
 C_SIGNAL='@t6g_mb_lib.t6g(sch_1):p5e_cpu0_g3_tx_dp(0)';
NODE_NAME     U25 U23
 '@T6G_MB_LIB.T6G(SCH_1):PAGE23_I216@PURE_QUANTA.GENOA_SP5(CHIPS)':
 'G3_TXP0||SATA20_TXP': CDS_PINID='\g3_txp0||sata20_txp\';
NODE_NAME     C1579 2
 '@T6G_MB_LIB.T6G(SCH_1):PAGE353_I229@PURE_QUANTA.Q_CAP_DIFFBUS(CHIPS)':
 '2': CDS_PINID='\2\';
NET_NAME
'P5E_CPU0_G3_TX_DP<10>'
 '@T6G_MB_LIB.T6G(SCH_1):P5E_CPU0_G3_TX_DP'<10>:
 C_SIGNAL='@t6g_mb_lib.t6g(sch_1):p5e_cpu0_g3_tx_dp(10)';
NODE_NAME     U25 R32
 '@T6G_MB_LIB.T6G(SCH_1):PAGE23_I216@PURE_QUANTA.GENOA_SP5(CHIPS)':
 'G3_TXP10||SATA32_TXP': CDS_PINID='\g3_txp10||sata32_txp\';
NODE_NAME     C1559 2
 '@T6G_MB_LIB.T6G(SCH_1):PAGE353_I263@PURE_QUANTA.Q_CAP_DIFFBUS(CHIPS)':
 '2': CDS_PINID='\2\';
NET_NAME
'P5E_CPU0_G3_TX_DP<11>'
 '@T6G_MB_LIB.T6G(SCH_1):P5E_CPU0_G3_TX_DP'<11>:
 C_SIGNAL='@t6g_mb_lib.t6g(sch_1):p5e_cpu0_g3_tx_dp(11)';
NODE_NAME     U25 N32
 '@T6G_MB_LIB.T6G(SCH_1):PAGE23_I216@PURE_QUANTA.GENOA_SP5(CHIPS)':
 'G3_TXP11||SATA33_TXP': CDS_PINID='\g3_txp11||sata33_txp\';
NODE_NAME     C1557 2
 '@T6G_MB_LIB.T6G(SCH_1):PAGE353_I266@PURE_QUANTA.Q_CAP_DIFFBUS(CHIPS)':
 '2': CDS_PINID='\2\';
NET_NAME
'P5E_CPU0_G3_TX_DP<12>'
 '@T6G_MB_LIB.T6G(SCH_1):P5E_CPU0_G3_TX_DP'<12>:
 C_SIGNAL='@t6g_mb_lib.t6g(sch_1):p5e_cpu0_g3_tx_dp(12)';
NODE_NAME     U25 U32
 '@T6G_MB_LIB.T6G(SCH_1):PAGE23_I216@PURE_QUANTA.GENOA_SP5(CHIPS)':
 'G3_TXP12||SATA34_TXP': CDS_PINID='\g3_txp12||sata34_txp\';
NODE_NAME     C1555 2
 '@T6G_MB_LIB.T6G(SCH_1):PAGE353_I267@PURE_QUANTA.Q_CAP_DIFFBUS(CHIPS)':
 '2': CDS_PINID='\2\';
NET_NAME
'P5E_CPU0_G3_TX_DP<13>'
 '@T6G_MB_LIB.T6G(SCH_1):P5E_CPU0_G3_TX_DP'<13>:
 C_SIGNAL='@t6g_mb_lib.t6g(sch_1):p5e_cpu0_g3_tx_dp(13)';
NODE_NAME     U25 P35
 '@T6G_MB_LIB.T6G(SCH_1):PAGE23_I216@PURE_QUANTA.GENOA_SP5(CHIPS)':
 'G3_TXP13||SATA35_TXP': CDS_PINID='\g3_txp13||sata35_txp\';
NODE_NAME     C1553 2
 '@T6G_MB_LIB.T6G(SCH_1):PAGE353_I269@PURE_QUANTA.Q_CAP_DIFFBUS(CHIPS)':
 '2': CDS_PINID='\2\';
NET_NAME
'P5E_CPU0_G3_TX_DP<14>'
 '@T6G_MB_LIB.T6G(SCH_1):P5E_CPU0_G3_TX_DP'<14>:
 C_SIGNAL='@t6g_mb_lib.t6g(sch_1):p5e_cpu0_g3_tx_dp(14)';
NODE_NAME     U25 T35
 '@T6G_MB_LIB.T6G(SCH_1):PAGE23_I216@PURE_QUANTA.GENOA_SP5(CHIPS)':
 'G3_TXP14||SATA36_TXP': CDS_PINID='\g3_txp14||sata36_txp\';
NODE_NAME     C1792 2
 '@T6G_MB_LIB.T6G(SCH_1):PAGE353_I271@PURE_QUANTA.Q_CAP_DIFFBUS(CHIPS)':
 '2': CDS_PINID='\2\';
NET_NAME
'P5E_CPU0_G3_TX_DP<15>'
 '@T6G_MB_LIB.T6G(SCH_1):P5E_CPU0_G3_TX_DP'<15>:
 C_SIGNAL='@t6g_mb_lib.t6g(sch_1):p5e_cpu0_g3_tx_dp(15)';
NODE_NAME     U25 V35
 '@T6G_MB_LIB.T6G(SCH_1):PAGE23_I216@PURE_QUANTA.GENOA_SP5(CHIPS)':
 'G3_TXP15||SATA37_TXP': CDS_PINID='\g3_txp15||sata37_txp\';
NODE_NAME     C1549 2
 '@T6G_MB_LIB.T6G(SCH_1):PAGE353_I274@PURE_QUANTA.Q_CAP_DIFFBUS(CHIPS)':
 '2': CDS_PINID='\2\';
NET_NAME
'P5E_CPU0_G3_TX_DP<1>'
 '@T6G_MB_LIB.T6G(SCH_1):P5E_CPU0_G3_TX_DP'<1>:
 C_SIGNAL='@t6g_mb_lib.t6g(sch_1):p5e_cpu0_g3_tx_dp(1)';
NODE_NAME     U25 R23
 '@T6G_MB_LIB.T6G(SCH_1):PAGE23_I216@PURE_QUANTA.GENOA_SP5(CHIPS)':
 'G3_TXP1||SATA21_TXP': CDS_PINID='\g3_txp1||sata21_txp\';
NODE_NAME     C1577 2
 '@T6G_MB_LIB.T6G(SCH_1):PAGE353_I311@PURE_QUANTA.Q_CAP_DIFFBUS(CHIPS)':
 '2': CDS_PINID='\2\';
NET_NAME
'P5E_CPU0_G3_TX_DP<2>'
 '@T6G_MB_LIB.T6G(SCH_1):P5E_CPU0_G3_TX_DP'<2>:
 C_SIGNAL='@t6g_mb_lib.t6g(sch_1):p5e_cpu0_g3_tx_dp(2)';
NODE_NAME     U25 W23
 '@T6G_MB_LIB.T6G(SCH_1):PAGE23_I216@PURE_QUANTA.GENOA_SP5(CHIPS)':
 'G3_TXP2||SATA22_TXP': CDS_PINID='\g3_txp2||sata22_txp\';
NODE_NAME     C1575 2
 '@T6G_MB_LIB.T6G(SCH_1):PAGE353_I231@PURE_QUANTA.Q_CAP_DIFFBUS(CHIPS)':
 '2': CDS_PINID='\2\';
NET_NAME
'P5E_CPU0_G3_TX_DP<3>'
 '@T6G_MB_LIB.T6G(SCH_1):P5E_CPU0_G3_TX_DP'<3>:
 C_SIGNAL='@t6g_mb_lib.t6g(sch_1):p5e_cpu0_g3_tx_dp(3)';
NODE_NAME     U25 U26
 '@T6G_MB_LIB.T6G(SCH_1):PAGE23_I216@PURE_QUANTA.GENOA_SP5(CHIPS)':
 'G3_TXP3||SATA23_TXP': CDS_PINID='\g3_txp3||sata23_txp\';
NODE_NAME     C1573 2
 '@T6G_MB_LIB.T6G(SCH_1):PAGE353_I233@PURE_QUANTA.Q_CAP_DIFFBUS(CHIPS)':
 '2': CDS_PINID='\2\';
NET_NAME
'P5E_CPU0_G3_TX_DP<4>'
 '@T6G_MB_LIB.T6G(SCH_1):P5E_CPU0_G3_TX_DP'<4>:
 C_SIGNAL='@t6g_mb_lib.t6g(sch_1):p5e_cpu0_g3_tx_dp(4)';
NODE_NAME     U25 R26
 '@T6G_MB_LIB.T6G(SCH_1):PAGE23_I216@PURE_QUANTA.GENOA_SP5(CHIPS)':
 'G3_TXP4||SATA24_TXP': CDS_PINID='\g3_txp4||sata24_txp\';
NODE_NAME     C1571 2
 '@T6G_MB_LIB.T6G(SCH_1):PAGE353_I236@PURE_QUANTA.Q_CAP_DIFFBUS(CHIPS)':
 '2': CDS_PINID='\2\';
NET_NAME
'P5E_CPU0_G3_TX_DP<5>'
 '@T6G_MB_LIB.T6G(SCH_1):P5E_CPU0_G3_TX_DP'<5>:
 C_SIGNAL='@t6g_mb_lib.t6g(sch_1):p5e_cpu0_g3_tx_dp(5)';
NODE_NAME     U25 N26
 '@T6G_MB_LIB.T6G(SCH_1):PAGE23_I216@PURE_QUANTA.GENOA_SP5(CHIPS)':
 'G3_TXP5||SATA25_TXP': CDS_PINID='\g3_txp5||sata25_txp\';
NODE_NAME     C1569 2
 '@T6G_MB_LIB.T6G(SCH_1):PAGE353_I237@PURE_QUANTA.Q_CAP_DIFFBUS(CHIPS)':
 '2': CDS_PINID='\2\';
NET_NAME
'P5E_CPU0_G3_TX_DP<6>'
 '@T6G_MB_LIB.T6G(SCH_1):P5E_CPU0_G3_TX_DP'<6>:
 C_SIGNAL='@t6g_mb_lib.t6g(sch_1):p5e_cpu0_g3_tx_dp(6)';
NODE_NAME     U25 W26
 '@T6G_MB_LIB.T6G(SCH_1):PAGE23_I216@PURE_QUANTA.GENOA_SP5(CHIPS)':
 'G3_TXP6||SATA26_TXP': CDS_PINID='\g3_txp6||sata26_txp\';
NODE_NAME     C47 2
 '@T6G_MB_LIB.T6G(SCH_1):PAGE353_I239@PURE_QUANTA.Q_CAP_DIFFBUS(CHIPS)':
 '2': CDS_PINID='\2\';
NET_NAME
'P5E_CPU0_G3_TX_DP<7>'
 '@T6G_MB_LIB.T6G(SCH_1):P5E_CPU0_G3_TX_DP'<7>:
 C_SIGNAL='@t6g_mb_lib.t6g(sch_1):p5e_cpu0_g3_tx_dp(7)';
NODE_NAME     U25 R29
 '@T6G_MB_LIB.T6G(SCH_1):PAGE23_I216@PURE_QUANTA.GENOA_SP5(CHIPS)':
 'G3_TXP7||SATA27_TXP': CDS_PINID='\g3_txp7||sata27_txp\';
NODE_NAME     C1565 2
 '@T6G_MB_LIB.T6G(SCH_1):PAGE353_I241@PURE_QUANTA.Q_CAP_DIFFBUS(CHIPS)':
 '2': CDS_PINID='\2\';
NET_NAME
'P5E_CPU0_G3_TX_DP<8>'
 '@T6G_MB_LIB.T6G(SCH_1):P5E_CPU0_G3_TX_DP'<8>:
 C_SIGNAL='@t6g_mb_lib.t6g(sch_1):p5e_cpu0_g3_tx_dp(8)';
NODE_NAME     U25 N29
 '@T6G_MB_LIB.T6G(SCH_1):PAGE23_I216@PURE_QUANTA.GENOA_SP5(CHIPS)':
 'G3_TXP8||SATA30_TXP': CDS_PINID='\g3_txp8||sata30_txp\';
NODE_NAME     C44 2
 '@T6G_MB_LIB.T6G(SCH_1):PAGE353_I259@PURE_QUANTA.Q_CAP_DIFFBUS(CHIPS)':
 '2': CDS_PINID='\2\';
NET_NAME
'P5E_CPU0_G3_TX_DP<9>'
 '@T6G_MB_LIB.T6G(SCH_1):P5E_CPU0_G3_TX_DP'<9>:
 C_SIGNAL='@t6g_mb_lib.t6g(sch_1):p5e_cpu0_g3_tx_dp(9)';
NODE_NAME     U25 U29
 '@T6G_MB_LIB.T6G(SCH_1):PAGE23_I216@PURE_QUANTA.GENOA_SP5(CHIPS)':
 'G3_TXP9||SATA31_TXP': CDS_PINID='\g3_txp9||sata31_txp\';
NODE_NAME     C1793 2
 '@T6G_MB_LIB.T6G(SCH_1):PAGE353_I261@PURE_QUANTA.Q_CAP_DIFFBUS(CHIPS)':
 '2': CDS_PINID='\2\';
NET_NAME
'P5E_CPU0_P0_RX_BUF_DN<0>'
 '@T6G_MB_LIB.T6G(SCH_1):P5E_CPU0_P0_RX_BUF_DN'<0>:
 C_SIGNAL='@t6g_mb_lib.t6g(sch_1):p5e_cpu0_p0_rx_buf_dn(0)';
NODE_NAME     U6010 EV2
 '@T6G_MB_LIB.T6G(SCH_1):PAGE383_I3@PURE_QUANTA.PT5161LRS(CHIPS)':
 'A_PERN15': CDS_PINID='A_PERN15';
NODE_NAME     J108 C1
 '@T6G_MB_LIB.T6G(SCH_1):PAGE320_I72@PURE_QUANTA.CONN112_10137002101LF(CHIPS)':
 'C1': CDS_PINID='C1';
NET_NAME
'P5E_CPU0_P0_RX_BUF_DN<10>'
 '@T6G_MB_LIB.T6G(SCH_1):P5E_CPU0_P0_RX_BUF_DN'<10>:
 C_SIGNAL='@t6g_mb_lib.t6g(sch_1):p5e_cpu0_p0_rx_buf_dn(10)';
NODE_NAME     U6010 BH2
 '@T6G_MB_LIB.T6G(SCH_1):PAGE383_I4@PURE_QUANTA.PT5161LRS(CHIPS)':
 'A_PERN5': CDS_PINID='A_PERN5';
NODE_NAME     J107 C3
 '@T6G_MB_LIB.T6G(SCH_1):PAGE317_I49@PURE_QUANTA.CONN112_10137002101LF(CHIPS)':
 'C3': CDS_PINID='C3';
NET_NAME
'P5E_CPU0_P0_RX_BUF_DN<11>'
 '@T6G_MB_LIB.T6G(SCH_1):P5E_CPU0_P0_RX_BUF_DN'<11>:
 C_SIGNAL='@t6g_mb_lib.t6g(sch_1):p5e_cpu0_p0_rx_buf_dn(11)';
NODE_NAME     U6010 BA2
 '@T6G_MB_LIB.T6G(SCH_1):PAGE383_I4@PURE_QUANTA.PT5161LRS(CHIPS)':
 'A_PERN4': CDS_PINID='A_PERN4';
NODE_NAME     J107 B4
 '@T6G_MB_LIB.T6G(SCH_1):PAGE317_I49@PURE_QUANTA.CONN112_10137002101LF(CHIPS)':
 'B4': CDS_PINID='B4';
NET_NAME
'P5E_CPU0_P0_RX_BUF_DN<12>'
 '@T6G_MB_LIB.T6G(SCH_1):P5E_CPU0_P0_RX_BUF_DN'<12>:
 C_SIGNAL='@t6g_mb_lib.t6g(sch_1):p5e_cpu0_p0_rx_buf_dn(12)';
NODE_NAME     U6010 AP2
 '@T6G_MB_LIB.T6G(SCH_1):PAGE383_I4@PURE_QUANTA.PT5161LRS(CHIPS)':
 'A_PERN3': CDS_PINID='A_PERN3';
NODE_NAME     J107 C5
 '@T6G_MB_LIB.T6G(SCH_1):PAGE317_I70@PURE_QUANTA.CONN112_10137002101LF(CHIPS)':
 'C5': CDS_PINID='C5';
NET_NAME
'P5E_CPU0_P0_RX_BUF_DN<13>'
 '@T6G_MB_LIB.T6G(SCH_1):P5E_CPU0_P0_RX_BUF_DN'<13>:
 C_SIGNAL='@t6g_mb_lib.t6g(sch_1):p5e_cpu0_p0_rx_buf_dn(13)';
NODE_NAME     U6010 AG2
 '@T6G_MB_LIB.T6G(SCH_1):PAGE383_I4@PURE_QUANTA.PT5161LRS(CHIPS)':
 'A_PERN2': CDS_PINID='A_PERN2';
NODE_NAME     J107 B6
 '@T6G_MB_LIB.T6G(SCH_1):PAGE317_I70@PURE_QUANTA.CONN112_10137002101LF(CHIPS)':
 'B6': CDS_PINID='B6';
NET_NAME
'P5E_CPU0_P0_RX_BUF_DN<14>'
 '@T6G_MB_LIB.T6G(SCH_1):P5E_CPU0_P0_RX_BUF_DN'<14>:
 C_SIGNAL='@t6g_mb_lib.t6g(sch_1):p5e_cpu0_p0_rx_buf_dn(14)';
NODE_NAME     U6010 Y2
 '@T6G_MB_LIB.T6G(SCH_1):PAGE383_I4@PURE_QUANTA.PT5161LRS(CHIPS)':
 'A_PERN1': CDS_PINID='A_PERN1';
NODE_NAME     J107 C7
 '@T6G_MB_LIB.T6G(SCH_1):PAGE317_I70@PURE_QUANTA.CONN112_10137002101LF(CHIPS)':
 'C7': CDS_PINID='C7';
NET_NAME
'P5E_CPU0_P0_RX_BUF_DN<15>'
 '@T6G_MB_LIB.T6G(SCH_1):P5E_CPU0_P0_RX_BUF_DN'<15>:
 C_SIGNAL='@t6g_mb_lib.t6g(sch_1):p5e_cpu0_p0_rx_buf_dn(15)';
NODE_NAME     U6010 N2
 '@T6G_MB_LIB.T6G(SCH_1):PAGE383_I4@PURE_QUANTA.PT5161LRS(CHIPS)':
 'A_PERN0': CDS_PINID='A_PERN0';
NODE_NAME     J107 B8
 '@T6G_MB_LIB.T6G(SCH_1):PAGE317_I70@PURE_QUANTA.CONN112_10137002101LF(CHIPS)':
 'B8': CDS_PINID='B8';
NET_NAME
'P5E_CPU0_P0_RX_BUF_DN<1>'
 '@T6G_MB_LIB.T6G(SCH_1):P5E_CPU0_P0_RX_BUF_DN'<1>:
 C_SIGNAL='@t6g_mb_lib.t6g(sch_1):p5e_cpu0_p0_rx_buf_dn(1)';
NODE_NAME     U6010 EL2
 '@T6G_MB_LIB.T6G(SCH_1):PAGE383_I3@PURE_QUANTA.PT5161LRS(CHIPS)':
 'A_PERN14': CDS_PINID='A_PERN14';
NODE_NAME     J108 B2
 '@T6G_MB_LIB.T6G(SCH_1):PAGE320_I72@PURE_QUANTA.CONN112_10137002101LF(CHIPS)':
 'B2': CDS_PINID='B2';
NET_NAME
'P5E_CPU0_P0_RX_BUF_DN<2>'
 '@T6G_MB_LIB.T6G(SCH_1):P5E_CPU0_P0_RX_BUF_DN'<2>:
 C_SIGNAL='@t6g_mb_lib.t6g(sch_1):p5e_cpu0_p0_rx_buf_dn(2)';
NODE_NAME     U6010 ED2
 '@T6G_MB_LIB.T6G(SCH_1):PAGE383_I3@PURE_QUANTA.PT5161LRS(CHIPS)':
 'A_PERN13': CDS_PINID='A_PERN13';
NODE_NAME     J108 C3
 '@T6G_MB_LIB.T6G(SCH_1):PAGE320_I72@PURE_QUANTA.CONN112_10137002101LF(CHIPS)':
 'C3': CDS_PINID='C3';
NET_NAME
'P5E_CPU0_P0_RX_BUF_DN<3>'
 '@T6G_MB_LIB.T6G(SCH_1):P5E_CPU0_P0_RX_BUF_DN'<3>:
 C_SIGNAL='@t6g_mb_lib.t6g(sch_1):p5e_cpu0_p0_rx_buf_dn(3)';
NODE_NAME     U6010 DU2
 '@T6G_MB_LIB.T6G(SCH_1):PAGE383_I3@PURE_QUANTA.PT5161LRS(CHIPS)':
 'A_PERN12': CDS_PINID='A_PERN12';
NODE_NAME     J108 B4
 '@T6G_MB_LIB.T6G(SCH_1):PAGE320_I72@PURE_QUANTA.CONN112_10137002101LF(CHIPS)':
 'B4': CDS_PINID='B4';
NET_NAME
'P5E_CPU0_P0_RX_BUF_DN<4>'
 '@T6G_MB_LIB.T6G(SCH_1):P5E_CPU0_P0_RX_BUF_DN'<4>:
 C_SIGNAL='@t6g_mb_lib.t6g(sch_1):p5e_cpu0_p0_rx_buf_dn(4)';
NODE_NAME     U6010 DK2
 '@T6G_MB_LIB.T6G(SCH_1):PAGE383_I3@PURE_QUANTA.PT5161LRS(CHIPS)':
 'A_PERN11': CDS_PINID='A_PERN11';
NODE_NAME     J108 C5
 '@T6G_MB_LIB.T6G(SCH_1):PAGE320_I15@PURE_QUANTA.CONN112_10137002101LF(CHIPS)':
 'C5': CDS_PINID='C5';
NET_NAME
'P5E_CPU0_P0_RX_BUF_DN<5>'
 '@T6G_MB_LIB.T6G(SCH_1):P5E_CPU0_P0_RX_BUF_DN'<5>:
 C_SIGNAL='@t6g_mb_lib.t6g(sch_1):p5e_cpu0_p0_rx_buf_dn(5)';
NODE_NAME     U6010 DC2
 '@T6G_MB_LIB.T6G(SCH_1):PAGE383_I3@PURE_QUANTA.PT5161LRS(CHIPS)':
 'A_PERN10': CDS_PINID='A_PERN10';
NODE_NAME     J108 B6
 '@T6G_MB_LIB.T6G(SCH_1):PAGE320_I15@PURE_QUANTA.CONN112_10137002101LF(CHIPS)':
 'B6': CDS_PINID='B6';
NET_NAME
'P5E_CPU0_P0_RX_BUF_DN<6>'
 '@T6G_MB_LIB.T6G(SCH_1):P5E_CPU0_P0_RX_BUF_DN'<6>:
 C_SIGNAL='@t6g_mb_lib.t6g(sch_1):p5e_cpu0_p0_rx_buf_dn(6)';
NODE_NAME     U6010 CT2
 '@T6G_MB_LIB.T6G(SCH_1):PAGE383_I3@PURE_QUANTA.PT5161LRS(CHIPS)':
 'A_PERN9': CDS_PINID='A_PERN9';
NODE_NAME     J108 C7
 '@T6G_MB_LIB.T6G(SCH_1):PAGE320_I15@PURE_QUANTA.CONN112_10137002101LF(CHIPS)':
 'C7': CDS_PINID='C7';
NET_NAME
'P5E_CPU0_P0_RX_BUF_DN<7>'
 '@T6G_MB_LIB.T6G(SCH_1):P5E_CPU0_P0_RX_BUF_DN'<7>:
 C_SIGNAL='@t6g_mb_lib.t6g(sch_1):p5e_cpu0_p0_rx_buf_dn(7)';
NODE_NAME     U6010 CJ2
 '@T6G_MB_LIB.T6G(SCH_1):PAGE383_I3@PURE_QUANTA.PT5161LRS(CHIPS)':
 'A_PERN8': CDS_PINID='A_PERN8';
NODE_NAME     J108 B8
 '@T6G_MB_LIB.T6G(SCH_1):PAGE320_I15@PURE_QUANTA.CONN112_10137002101LF(CHIPS)':
 'B8': CDS_PINID='B8';
NET_NAME
'P5E_CPU0_P0_RX_BUF_DN<8>'
 '@T6G_MB_LIB.T6G(SCH_1):P5E_CPU0_P0_RX_BUF_DN'<8>:
 C_SIGNAL='@t6g_mb_lib.t6g(sch_1):p5e_cpu0_p0_rx_buf_dn(8)';
NODE_NAME     U6010 CB2
 '@T6G_MB_LIB.T6G(SCH_1):PAGE383_I4@PURE_QUANTA.PT5161LRS(CHIPS)':
 'A_PERN7': CDS_PINID='A_PERN7';
NODE_NAME     J107 C1
 '@T6G_MB_LIB.T6G(SCH_1):PAGE317_I49@PURE_QUANTA.CONN112_10137002101LF(CHIPS)':
 'C1': CDS_PINID='C1';
NET_NAME
'P5E_CPU0_P0_RX_BUF_DN<9>'
 '@T6G_MB_LIB.T6G(SCH_1):P5E_CPU0_P0_RX_BUF_DN'<9>:
 C_SIGNAL='@t6g_mb_lib.t6g(sch_1):p5e_cpu0_p0_rx_buf_dn(9)';
NODE_NAME     U6010 BR2
 '@T6G_MB_LIB.T6G(SCH_1):PAGE383_I4@PURE_QUANTA.PT5161LRS(CHIPS)':
 'A_PERN6': CDS_PINID='A_PERN6';
NODE_NAME     J107 B2
 '@T6G_MB_LIB.T6G(SCH_1):PAGE317_I49@PURE_QUANTA.CONN112_10137002101LF(CHIPS)':
 'B2': CDS_PINID='B2';
NET_NAME
'P5E_CPU0_P0_RX_BUF_DP<0>'
 '@T6G_MB_LIB.T6G(SCH_1):P5E_CPU0_P0_RX_BUF_DP'<0>:
 C_SIGNAL='@t6g_mb_lib.t6g(sch_1):p5e_cpu0_p0_rx_buf_dp(0)';
NODE_NAME     U6010 EY1
 '@T6G_MB_LIB.T6G(SCH_1):PAGE383_I3@PURE_QUANTA.PT5161LRS(CHIPS)':
 'A_PERP15': CDS_PINID='A_PERP15';
NODE_NAME     J108 D1
 '@T6G_MB_LIB.T6G(SCH_1):PAGE320_I72@PURE_QUANTA.CONN112_10137002101LF(CHIPS)':
 'D1': CDS_PINID='D1';
NET_NAME
'P5E_CPU0_P0_RX_BUF_DP<10>'
 '@T6G_MB_LIB.T6G(SCH_1):P5E_CPU0_P0_RX_BUF_DP'<10>:
 C_SIGNAL='@t6g_mb_lib.t6g(sch_1):p5e_cpu0_p0_rx_buf_dp(10)';
NODE_NAME     U6010 BK1
 '@T6G_MB_LIB.T6G(SCH_1):PAGE383_I4@PURE_QUANTA.PT5161LRS(CHIPS)':
 'A_PERP5': CDS_PINID='A_PERP5';
NODE_NAME     J107 D3
 '@T6G_MB_LIB.T6G(SCH_1):PAGE317_I49@PURE_QUANTA.CONN112_10137002101LF(CHIPS)':
 'D3': CDS_PINID='D3';
NET_NAME
'P5E_CPU0_P0_RX_BUF_DP<11>'
 '@T6G_MB_LIB.T6G(SCH_1):P5E_CPU0_P0_RX_BUF_DP'<11>:
 C_SIGNAL='@t6g_mb_lib.t6g(sch_1):p5e_cpu0_p0_rx_buf_dp(11)';
NODE_NAME     U6010 BC1
 '@T6G_MB_LIB.T6G(SCH_1):PAGE383_I4@PURE_QUANTA.PT5161LRS(CHIPS)':
 'A_PERP4': CDS_PINID='A_PERP4';
NODE_NAME     J107 C4
 '@T6G_MB_LIB.T6G(SCH_1):PAGE317_I49@PURE_QUANTA.CONN112_10137002101LF(CHIPS)':
 'C4': CDS_PINID='C4';
NET_NAME
'P5E_CPU0_P0_RX_BUF_DP<12>'
 '@T6G_MB_LIB.T6G(SCH_1):P5E_CPU0_P0_RX_BUF_DP'<12>:
 C_SIGNAL='@t6g_mb_lib.t6g(sch_1):p5e_cpu0_p0_rx_buf_dp(12)';
NODE_NAME     U6010 AT1
 '@T6G_MB_LIB.T6G(SCH_1):PAGE383_I4@PURE_QUANTA.PT5161LRS(CHIPS)':
 'A_PERP3': CDS_PINID='A_PERP3';
NODE_NAME     J107 D5
 '@T6G_MB_LIB.T6G(SCH_1):PAGE317_I70@PURE_QUANTA.CONN112_10137002101LF(CHIPS)':
 'D5': CDS_PINID='D5';
NET_NAME
'P5E_CPU0_P0_RX_BUF_DP<13>'
 '@T6G_MB_LIB.T6G(SCH_1):P5E_CPU0_P0_RX_BUF_DP'<13>:
 C_SIGNAL='@t6g_mb_lib.t6g(sch_1):p5e_cpu0_p0_rx_buf_dp(13)';
NODE_NAME     U6010 AJ1
 '@T6G_MB_LIB.T6G(SCH_1):PAGE383_I4@PURE_QUANTA.PT5161LRS(CHIPS)':
 'A_PERP2': CDS_PINID='A_PERP2';
NODE_NAME     J107 C6
 '@T6G_MB_LIB.T6G(SCH_1):PAGE317_I70@PURE_QUANTA.CONN112_10137002101LF(CHIPS)':
 'C6': CDS_PINID='C6';
NET_NAME
'P5E_CPU0_P0_RX_BUF_DP<14>'
 '@T6G_MB_LIB.T6G(SCH_1):P5E_CPU0_P0_RX_BUF_DP'<14>:
 C_SIGNAL='@t6g_mb_lib.t6g(sch_1):p5e_cpu0_p0_rx_buf_dp(14)';
NODE_NAME     U6010 AB1
 '@T6G_MB_LIB.T6G(SCH_1):PAGE383_I4@PURE_QUANTA.PT5161LRS(CHIPS)':
 'A_PERP1': CDS_PINID='A_PERP1';
NODE_NAME     J107 D7
 '@T6G_MB_LIB.T6G(SCH_1):PAGE317_I70@PURE_QUANTA.CONN112_10137002101LF(CHIPS)':
 'D7': CDS_PINID='D7';
NET_NAME
'P5E_CPU0_P0_RX_BUF_DP<15>'
 '@T6G_MB_LIB.T6G(SCH_1):P5E_CPU0_P0_RX_BUF_DP'<15>:
 C_SIGNAL='@t6g_mb_lib.t6g(sch_1):p5e_cpu0_p0_rx_buf_dp(15)';
NODE_NAME     U6010 R1
 '@T6G_MB_LIB.T6G(SCH_1):PAGE383_I4@PURE_QUANTA.PT5161LRS(CHIPS)':
 'A_PERP0': CDS_PINID='A_PERP0';
NODE_NAME     J107 C8
 '@T6G_MB_LIB.T6G(SCH_1):PAGE317_I70@PURE_QUANTA.CONN112_10137002101LF(CHIPS)':
 'C8': CDS_PINID='C8';
NET_NAME
'P5E_CPU0_P0_RX_BUF_DP<1>'
 '@T6G_MB_LIB.T6G(SCH_1):P5E_CPU0_P0_RX_BUF_DP'<1>:
 C_SIGNAL='@t6g_mb_lib.t6g(sch_1):p5e_cpu0_p0_rx_buf_dp(1)';
NODE_NAME     U6010 EN1
 '@T6G_MB_LIB.T6G(SCH_1):PAGE383_I3@PURE_QUANTA.PT5161LRS(CHIPS)':
 'A_PERP14': CDS_PINID='A_PERP14';
NODE_NAME     J108 C2
 '@T6G_MB_LIB.T6G(SCH_1):PAGE320_I72@PURE_QUANTA.CONN112_10137002101LF(CHIPS)':
 'C2': CDS_PINID='C2';
NET_NAME
'P5E_CPU0_P0_RX_BUF_DP<2>'
 '@T6G_MB_LIB.T6G(SCH_1):P5E_CPU0_P0_RX_BUF_DP'<2>:
 C_SIGNAL='@t6g_mb_lib.t6g(sch_1):p5e_cpu0_p0_rx_buf_dp(2)';
NODE_NAME     U6010 EF1
 '@T6G_MB_LIB.T6G(SCH_1):PAGE383_I3@PURE_QUANTA.PT5161LRS(CHIPS)':
 'A_PERP13': CDS_PINID='A_PERP13';
NODE_NAME     J108 D3
 '@T6G_MB_LIB.T6G(SCH_1):PAGE320_I72@PURE_QUANTA.CONN112_10137002101LF(CHIPS)':
 'D3': CDS_PINID='D3';
NET_NAME
'P5E_CPU0_P0_RX_BUF_DP<3>'
 '@T6G_MB_LIB.T6G(SCH_1):P5E_CPU0_P0_RX_BUF_DP'<3>:
 C_SIGNAL='@t6g_mb_lib.t6g(sch_1):p5e_cpu0_p0_rx_buf_dp(3)';
NODE_NAME     U6010 DW1
 '@T6G_MB_LIB.T6G(SCH_1):PAGE383_I3@PURE_QUANTA.PT5161LRS(CHIPS)':
 'A_PERP12': CDS_PINID='A_PERP12';
NODE_NAME     J108 C4
 '@T6G_MB_LIB.T6G(SCH_1):PAGE320_I72@PURE_QUANTA.CONN112_10137002101LF(CHIPS)':
 'C4': CDS_PINID='C4';
NET_NAME
'P5E_CPU0_P0_RX_BUF_DP<4>'
 '@T6G_MB_LIB.T6G(SCH_1):P5E_CPU0_P0_RX_BUF_DP'<4>:
 C_SIGNAL='@t6g_mb_lib.t6g(sch_1):p5e_cpu0_p0_rx_buf_dp(4)';
NODE_NAME     U6010 DM1
 '@T6G_MB_LIB.T6G(SCH_1):PAGE383_I3@PURE_QUANTA.PT5161LRS(CHIPS)':
 'A_PERP11': CDS_PINID='A_PERP11';
NODE_NAME     J108 D5
 '@T6G_MB_LIB.T6G(SCH_1):PAGE320_I15@PURE_QUANTA.CONN112_10137002101LF(CHIPS)':
 'D5': CDS_PINID='D5';
NET_NAME
'P5E_CPU0_P0_RX_BUF_DP<5>'
 '@T6G_MB_LIB.T6G(SCH_1):P5E_CPU0_P0_RX_BUF_DP'<5>:
 C_SIGNAL='@t6g_mb_lib.t6g(sch_1):p5e_cpu0_p0_rx_buf_dp(5)';
NODE_NAME     U6010 DE1
 '@T6G_MB_LIB.T6G(SCH_1):PAGE383_I3@PURE_QUANTA.PT5161LRS(CHIPS)':
 'A_PERP10': CDS_PINID='A_PERP10';
NODE_NAME     J108 C6
 '@T6G_MB_LIB.T6G(SCH_1):PAGE320_I15@PURE_QUANTA.CONN112_10137002101LF(CHIPS)':
 'C6': CDS_PINID='C6';
NET_NAME
'P5E_CPU0_P0_RX_BUF_DP<6>'
 '@T6G_MB_LIB.T6G(SCH_1):P5E_CPU0_P0_RX_BUF_DP'<6>:
 C_SIGNAL='@t6g_mb_lib.t6g(sch_1):p5e_cpu0_p0_rx_buf_dp(6)';
NODE_NAME     U6010 CV1
 '@T6G_MB_LIB.T6G(SCH_1):PAGE383_I3@PURE_QUANTA.PT5161LRS(CHIPS)':
 'A_PERP9': CDS_PINID='A_PERP9';
NODE_NAME     J108 D7
 '@T6G_MB_LIB.T6G(SCH_1):PAGE320_I15@PURE_QUANTA.CONN112_10137002101LF(CHIPS)':
 'D7': CDS_PINID='D7';
NET_NAME
'P5E_CPU0_P0_RX_BUF_DP<7>'
 '@T6G_MB_LIB.T6G(SCH_1):P5E_CPU0_P0_RX_BUF_DP'<7>:
 C_SIGNAL='@t6g_mb_lib.t6g(sch_1):p5e_cpu0_p0_rx_buf_dp(7)';
NODE_NAME     U6010 CL1
 '@T6G_MB_LIB.T6G(SCH_1):PAGE383_I3@PURE_QUANTA.PT5161LRS(CHIPS)':
 'A_PERP8': CDS_PINID='A_PERP8';
NODE_NAME     J108 C8
 '@T6G_MB_LIB.T6G(SCH_1):PAGE320_I15@PURE_QUANTA.CONN112_10137002101LF(CHIPS)':
 'C8': CDS_PINID='C8';
NET_NAME
'P5E_CPU0_P0_RX_BUF_DP<8>'
 '@T6G_MB_LIB.T6G(SCH_1):P5E_CPU0_P0_RX_BUF_DP'<8>:
 C_SIGNAL='@t6g_mb_lib.t6g(sch_1):p5e_cpu0_p0_rx_buf_dp(8)';
NODE_NAME     U6010 CD1
 '@T6G_MB_LIB.T6G(SCH_1):PAGE383_I4@PURE_QUANTA.PT5161LRS(CHIPS)':
 'A_PERP7': CDS_PINID='A_PERP7';
NODE_NAME     J107 D1
 '@T6G_MB_LIB.T6G(SCH_1):PAGE317_I49@PURE_QUANTA.CONN112_10137002101LF(CHIPS)':
 'D1': CDS_PINID='D1';
NET_NAME
'P5E_CPU0_P0_RX_BUF_DP<9>'
 '@T6G_MB_LIB.T6G(SCH_1):P5E_CPU0_P0_RX_BUF_DP'<9>:
 C_SIGNAL='@t6g_mb_lib.t6g(sch_1):p5e_cpu0_p0_rx_buf_dp(9)';
NODE_NAME     U6010 BU1
 '@T6G_MB_LIB.T6G(SCH_1):PAGE383_I4@PURE_QUANTA.PT5161LRS(CHIPS)':
 'A_PERP6': CDS_PINID='A_PERP6';
NODE_NAME     J107 C2
 '@T6G_MB_LIB.T6G(SCH_1):PAGE317_I49@PURE_QUANTA.CONN112_10137002101LF(CHIPS)':
 'C2': CDS_PINID='C2';
NET_NAME
'P5E_CPU0_P0_RX_DN<0>'
 '@T6G_MB_LIB.T6G(SCH_1):P5E_CPU0_P0_RX_DN'<0>:
 C_SIGNAL='@t6g_mb_lib.t6g(sch_1):p5e_cpu0_p0_rx_dn(0)';
NODE_NAME     U25 BW53
 '@T6G_MB_LIB.T6G(SCH_1):PAGE24_I148@PURE_QUANTA.GENOA_SP5(CHIPS)':
 'P0_RXN0||SATA00_RXN': CDS_PINID='\p0_rxn0||sata00_rxn\';
NODE_NAME     U6010 EW29
 '@T6G_MB_LIB.T6G(SCH_1):PAGE382_I3@PURE_QUANTA.PT5161LRS(CHIPS)':
 'A_PETN15': CDS_PINID='A_PETN15';
NET_NAME
'P5E_CPU0_P0_RX_DN<10>'
 '@T6G_MB_LIB.T6G(SCH_1):P5E_CPU0_P0_RX_DN'<10>:
 C_SIGNAL='@t6g_mb_lib.t6g(sch_1):p5e_cpu0_p0_rx_dn(10)';
NODE_NAME     U25 CA44
 '@T6G_MB_LIB.T6G(SCH_1):PAGE24_I148@PURE_QUANTA.GENOA_SP5(CHIPS)':
 'P0_RXN10||SATA12_RXN': CDS_PINID='\p0_rxn10||sata12_rxn\';
NODE_NAME     U6010 BJ29
 '@T6G_MB_LIB.T6G(SCH_1):PAGE382_I2@PURE_QUANTA.PT5161LRS(CHIPS)':
 'A_PETN5': CDS_PINID='A_PETN5';
NET_NAME
'P5E_CPU0_P0_RX_DN<11>'
 '@T6G_MB_LIB.T6G(SCH_1):P5E_CPU0_P0_RX_DN'<11>:
 C_SIGNAL='@t6g_mb_lib.t6g(sch_1):p5e_cpu0_p0_rx_dn(11)';
NODE_NAME     U25 BU44
 '@T6G_MB_LIB.T6G(SCH_1):PAGE24_I148@PURE_QUANTA.GENOA_SP5(CHIPS)':
 'P0_RXN11||SATA13_RXN': CDS_PINID='\p0_rxn11||sata13_rxn\';
NODE_NAME     U6010 BB29
 '@T6G_MB_LIB.T6G(SCH_1):PAGE382_I2@PURE_QUANTA.PT5161LRS(CHIPS)':
 'A_PETN4': CDS_PINID='A_PETN4';
NET_NAME
'P5E_CPU0_P0_RX_DN<12>'
 '@T6G_MB_LIB.T6G(SCH_1):P5E_CPU0_P0_RX_DN'<12>:
 C_SIGNAL='@t6g_mb_lib.t6g(sch_1):p5e_cpu0_p0_rx_dn(12)';
NODE_NAME     U25 BY41
 '@T6G_MB_LIB.T6G(SCH_1):PAGE24_I148@PURE_QUANTA.GENOA_SP5(CHIPS)':
 'P0_RXN12||SATA14_RXN': CDS_PINID='\p0_rxn12||sata14_rxn\';
NODE_NAME     U6010 AR29
 '@T6G_MB_LIB.T6G(SCH_1):PAGE382_I2@PURE_QUANTA.PT5161LRS(CHIPS)':
 'A_PETN3': CDS_PINID='A_PETN3';
NET_NAME
'P5E_CPU0_P0_RX_DN<13>'
 '@T6G_MB_LIB.T6G(SCH_1):P5E_CPU0_P0_RX_DN'<13>:
 C_SIGNAL='@t6g_mb_lib.t6g(sch_1):p5e_cpu0_p0_rx_dn(13)';
NODE_NAME     U25 CB41
 '@T6G_MB_LIB.T6G(SCH_1):PAGE24_I148@PURE_QUANTA.GENOA_SP5(CHIPS)':
 'P0_RXN13||SATA15_RXN': CDS_PINID='\p0_rxn13||sata15_rxn\';
NODE_NAME     U6010 AH29
 '@T6G_MB_LIB.T6G(SCH_1):PAGE382_I2@PURE_QUANTA.PT5161LRS(CHIPS)':
 'A_PETN2': CDS_PINID='A_PETN2';
NET_NAME
'P5E_CPU0_P0_RX_DN<14>'
 '@T6G_MB_LIB.T6G(SCH_1):P5E_CPU0_P0_RX_DN'<14>:
 C_SIGNAL='@t6g_mb_lib.t6g(sch_1):p5e_cpu0_p0_rx_dn(14)';
NODE_NAME     U25 BV41
 '@T6G_MB_LIB.T6G(SCH_1):PAGE24_I148@PURE_QUANTA.GENOA_SP5(CHIPS)':
 'P0_RXN14||SATA16_RXN': CDS_PINID='\p0_rxn14||sata16_rxn\';
NODE_NAME     U6010 AA29
 '@T6G_MB_LIB.T6G(SCH_1):PAGE382_I2@PURE_QUANTA.PT5161LRS(CHIPS)':
 'A_PETN1': CDS_PINID='A_PETN1';
NET_NAME
'P5E_CPU0_P0_RX_DN<15>'
 '@T6G_MB_LIB.T6G(SCH_1):P5E_CPU0_P0_RX_DN'<15>:
 C_SIGNAL='@t6g_mb_lib.t6g(sch_1):p5e_cpu0_p0_rx_dn(15)';
NODE_NAME     U25 BT41
 '@T6G_MB_LIB.T6G(SCH_1):PAGE24_I148@PURE_QUANTA.GENOA_SP5(CHIPS)':
 'P0_RXN15||SATA17_RXN': CDS_PINID='\p0_rxn15||sata17_rxn\';
NODE_NAME     U6010 P29
 '@T6G_MB_LIB.T6G(SCH_1):PAGE382_I2@PURE_QUANTA.PT5161LRS(CHIPS)':
 'A_PETN0': CDS_PINID='A_PETN0';
NET_NAME
'P5E_CPU0_P0_RX_DN<1>'
 '@T6G_MB_LIB.T6G(SCH_1):P5E_CPU0_P0_RX_DN'<1>:
 C_SIGNAL='@t6g_mb_lib.t6g(sch_1):p5e_cpu0_p0_rx_dn(1)';
NODE_NAME     U25 CA53
 '@T6G_MB_LIB.T6G(SCH_1):PAGE24_I148@PURE_QUANTA.GENOA_SP5(CHIPS)':
 'P0_RXN1||SATA01_RXN': CDS_PINID='\p0_rxn1||sata01_rxn\';
NODE_NAME     U6010 EM29
 '@T6G_MB_LIB.T6G(SCH_1):PAGE382_I3@PURE_QUANTA.PT5161LRS(CHIPS)':
 'A_PETN14': CDS_PINID='A_PETN14';
NET_NAME
'P5E_CPU0_P0_RX_DN<2>'
 '@T6G_MB_LIB.T6G(SCH_1):P5E_CPU0_P0_RX_DN'<2>:
 C_SIGNAL='@t6g_mb_lib.t6g(sch_1):p5e_cpu0_p0_rx_dn(2)';
NODE_NAME     U25 BU53
 '@T6G_MB_LIB.T6G(SCH_1):PAGE24_I148@PURE_QUANTA.GENOA_SP5(CHIPS)':
 'P0_RXN2||SATA02_RXN': CDS_PINID='\p0_rxn2||sata02_rxn\';
NODE_NAME     U6010 EE29
 '@T6G_MB_LIB.T6G(SCH_1):PAGE382_I3@PURE_QUANTA.PT5161LRS(CHIPS)':
 'A_PETN13': CDS_PINID='A_PETN13';
NET_NAME
'P5E_CPU0_P0_RX_DN<3>'
 '@T6G_MB_LIB.T6G(SCH_1):P5E_CPU0_P0_RX_DN'<3>:
 C_SIGNAL='@t6g_mb_lib.t6g(sch_1):p5e_cpu0_p0_rx_dn(3)';
NODE_NAME     U25 BW50
 '@T6G_MB_LIB.T6G(SCH_1):PAGE24_I148@PURE_QUANTA.GENOA_SP5(CHIPS)':
 'P0_RXN3||SATA03_RXN': CDS_PINID='\p0_rxn3||sata03_rxn\';
NODE_NAME     U6010 DV29
 '@T6G_MB_LIB.T6G(SCH_1):PAGE382_I3@PURE_QUANTA.PT5161LRS(CHIPS)':
 'A_PETN12': CDS_PINID='A_PETN12';
NET_NAME
'P5E_CPU0_P0_RX_DN<4>'
 '@T6G_MB_LIB.T6G(SCH_1):P5E_CPU0_P0_RX_DN'<4>:
 C_SIGNAL='@t6g_mb_lib.t6g(sch_1):p5e_cpu0_p0_rx_dn(4)';
NODE_NAME     U25 CA50
 '@T6G_MB_LIB.T6G(SCH_1):PAGE24_I148@PURE_QUANTA.GENOA_SP5(CHIPS)':
 'P0_RXN4||SATA04_RXN': CDS_PINID='\p0_rxn4||sata04_rxn\';
NODE_NAME     U6010 DL29
 '@T6G_MB_LIB.T6G(SCH_1):PAGE382_I3@PURE_QUANTA.PT5161LRS(CHIPS)':
 'A_PETN11': CDS_PINID='A_PETN11';
NET_NAME
'P5E_CPU0_P0_RX_DN<5>'
 '@T6G_MB_LIB.T6G(SCH_1):P5E_CPU0_P0_RX_DN'<5>:
 C_SIGNAL='@t6g_mb_lib.t6g(sch_1):p5e_cpu0_p0_rx_dn(5)';
NODE_NAME     U25 BU50
 '@T6G_MB_LIB.T6G(SCH_1):PAGE24_I148@PURE_QUANTA.GENOA_SP5(CHIPS)':
 'P0_RXN5||SATA05_RXN': CDS_PINID='\p0_rxn5||sata05_rxn\';
NODE_NAME     U6010 DD29
 '@T6G_MB_LIB.T6G(SCH_1):PAGE382_I3@PURE_QUANTA.PT5161LRS(CHIPS)':
 'A_PETN10': CDS_PINID='A_PETN10';
NET_NAME
'P5E_CPU0_P0_RX_DN<6>'
 '@T6G_MB_LIB.T6G(SCH_1):P5E_CPU0_P0_RX_DN'<6>:
 C_SIGNAL='@t6g_mb_lib.t6g(sch_1):p5e_cpu0_p0_rx_dn(6)';
NODE_NAME     U25 BW47
 '@T6G_MB_LIB.T6G(SCH_1):PAGE24_I148@PURE_QUANTA.GENOA_SP5(CHIPS)':
 'P0_RXN6||SATA06_RXN': CDS_PINID='\p0_rxn6||sata06_rxn\';
NODE_NAME     U6010 CU29
 '@T6G_MB_LIB.T6G(SCH_1):PAGE382_I3@PURE_QUANTA.PT5161LRS(CHIPS)':
 'A_PETN9': CDS_PINID='A_PETN9';
NET_NAME
'P5E_CPU0_P0_RX_DN<7>'
 '@T6G_MB_LIB.T6G(SCH_1):P5E_CPU0_P0_RX_DN'<7>:
 C_SIGNAL='@t6g_mb_lib.t6g(sch_1):p5e_cpu0_p0_rx_dn(7)';
NODE_NAME     U25 CA47
 '@T6G_MB_LIB.T6G(SCH_1):PAGE24_I148@PURE_QUANTA.GENOA_SP5(CHIPS)':
 'P0_RXN7||SATA07_RXN': CDS_PINID='\p0_rxn7||sata07_rxn\';
NODE_NAME     U6010 CK29
 '@T6G_MB_LIB.T6G(SCH_1):PAGE382_I3@PURE_QUANTA.PT5161LRS(CHIPS)':
 'A_PETN8': CDS_PINID='A_PETN8';
NET_NAME
'P5E_CPU0_P0_RX_DN<8>'
 '@T6G_MB_LIB.T6G(SCH_1):P5E_CPU0_P0_RX_DN'<8>:
 C_SIGNAL='@t6g_mb_lib.t6g(sch_1):p5e_cpu0_p0_rx_dn(8)';
NODE_NAME     U25 BU47
 '@T6G_MB_LIB.T6G(SCH_1):PAGE24_I148@PURE_QUANTA.GENOA_SP5(CHIPS)':
 'P0_RXN8||SATA10_RXN': CDS_PINID='\p0_rxn8||sata10_rxn\';
NODE_NAME     U6010 CC29
 '@T6G_MB_LIB.T6G(SCH_1):PAGE382_I2@PURE_QUANTA.PT5161LRS(CHIPS)':
 'A_PETN7': CDS_PINID='A_PETN7';
NET_NAME
'P5E_CPU0_P0_RX_DN<9>'
 '@T6G_MB_LIB.T6G(SCH_1):P5E_CPU0_P0_RX_DN'<9>:
 C_SIGNAL='@t6g_mb_lib.t6g(sch_1):p5e_cpu0_p0_rx_dn(9)';
NODE_NAME     U25 BW44
 '@T6G_MB_LIB.T6G(SCH_1):PAGE24_I148@PURE_QUANTA.GENOA_SP5(CHIPS)':
 'P0_RXN9||SATA11_RXN': CDS_PINID='\p0_rxn9||sata11_rxn\';
NODE_NAME     U6010 BT29
 '@T6G_MB_LIB.T6G(SCH_1):PAGE382_I2@PURE_QUANTA.PT5161LRS(CHIPS)':
 'A_PETN6': CDS_PINID='A_PETN6';
NET_NAME
'P5E_CPU0_P0_RX_DP<0>'
 '@T6G_MB_LIB.T6G(SCH_1):P5E_CPU0_P0_RX_DP'<0>:
 C_SIGNAL='@t6g_mb_lib.t6g(sch_1):p5e_cpu0_p0_rx_dp(0)';
NODE_NAME     U25 BW52
 '@T6G_MB_LIB.T6G(SCH_1):PAGE24_I148@PURE_QUANTA.GENOA_SP5(CHIPS)':
 'P0_RXP0||SATA00_RXP': CDS_PINID='\p0_rxp0||sata00_rxp\';
NODE_NAME     U6010 EU26
 '@T6G_MB_LIB.T6G(SCH_1):PAGE382_I3@PURE_QUANTA.PT5161LRS(CHIPS)':
 'A_PETP15': CDS_PINID='A_PETP15';
NET_NAME
'P5E_CPU0_P0_RX_DP<10>'
 '@T6G_MB_LIB.T6G(SCH_1):P5E_CPU0_P0_RX_DP'<10>:
 C_SIGNAL='@t6g_mb_lib.t6g(sch_1):p5e_cpu0_p0_rx_dp(10)';
NODE_NAME     U25 CA43
 '@T6G_MB_LIB.T6G(SCH_1):PAGE24_I148@PURE_QUANTA.GENOA_SP5(CHIPS)':
 'P0_RXP10||SATA12_RXP': CDS_PINID='\p0_rxp10||sata12_rxp\';
NODE_NAME     U6010 BG26
 '@T6G_MB_LIB.T6G(SCH_1):PAGE382_I2@PURE_QUANTA.PT5161LRS(CHIPS)':
 'A_PETP5': CDS_PINID='A_PETP5';
NET_NAME
'P5E_CPU0_P0_RX_DP<11>'
 '@T6G_MB_LIB.T6G(SCH_1):P5E_CPU0_P0_RX_DP'<11>:
 C_SIGNAL='@t6g_mb_lib.t6g(sch_1):p5e_cpu0_p0_rx_dp(11)';
NODE_NAME     U25 BU43
 '@T6G_MB_LIB.T6G(SCH_1):PAGE24_I148@PURE_QUANTA.GENOA_SP5(CHIPS)':
 'P0_RXP11||SATA13_RXP': CDS_PINID='\p0_rxp11||sata13_rxp\';
NODE_NAME     U6010 AY26
 '@T6G_MB_LIB.T6G(SCH_1):PAGE382_I2@PURE_QUANTA.PT5161LRS(CHIPS)':
 'A_PETP4': CDS_PINID='A_PETP4';
NET_NAME
'P5E_CPU0_P0_RX_DP<12>'
 '@T6G_MB_LIB.T6G(SCH_1):P5E_CPU0_P0_RX_DP'<12>:
 C_SIGNAL='@t6g_mb_lib.t6g(sch_1):p5e_cpu0_p0_rx_dp(12)';
NODE_NAME     U25 BY40
 '@T6G_MB_LIB.T6G(SCH_1):PAGE24_I148@PURE_QUANTA.GENOA_SP5(CHIPS)':
 'P0_RXP12||SATA14_RXP': CDS_PINID='\p0_rxp12||sata14_rxp\';
NODE_NAME     U6010 AN26
 '@T6G_MB_LIB.T6G(SCH_1):PAGE382_I2@PURE_QUANTA.PT5161LRS(CHIPS)':
 'A_PETP3': CDS_PINID='A_PETP3';
NET_NAME
'P5E_CPU0_P0_RX_DP<13>'
 '@T6G_MB_LIB.T6G(SCH_1):P5E_CPU0_P0_RX_DP'<13>:
 C_SIGNAL='@t6g_mb_lib.t6g(sch_1):p5e_cpu0_p0_rx_dp(13)';
NODE_NAME     U25 CB40
 '@T6G_MB_LIB.T6G(SCH_1):PAGE24_I148@PURE_QUANTA.GENOA_SP5(CHIPS)':
 'P0_RXP13||SATA15_RXP': CDS_PINID='\p0_rxp13||sata15_rxp\';
NODE_NAME     U6010 AF26
 '@T6G_MB_LIB.T6G(SCH_1):PAGE382_I2@PURE_QUANTA.PT5161LRS(CHIPS)':
 'A_PETP2': CDS_PINID='A_PETP2';
NET_NAME
'P5E_CPU0_P0_RX_DP<14>'
 '@T6G_MB_LIB.T6G(SCH_1):P5E_CPU0_P0_RX_DP'<14>:
 C_SIGNAL='@t6g_mb_lib.t6g(sch_1):p5e_cpu0_p0_rx_dp(14)';
NODE_NAME     U25 BV40
 '@T6G_MB_LIB.T6G(SCH_1):PAGE24_I148@PURE_QUANTA.GENOA_SP5(CHIPS)':
 'P0_RXP14||SATA16_RXP': CDS_PINID='\p0_rxp14||sata16_rxp\';
NODE_NAME     U6010 W26
 '@T6G_MB_LIB.T6G(SCH_1):PAGE382_I2@PURE_QUANTA.PT5161LRS(CHIPS)':
 'A_PETP1': CDS_PINID='A_PETP1';
NET_NAME
'P5E_CPU0_P0_RX_DP<15>'
 '@T6G_MB_LIB.T6G(SCH_1):P5E_CPU0_P0_RX_DP'<15>:
 C_SIGNAL='@t6g_mb_lib.t6g(sch_1):p5e_cpu0_p0_rx_dp(15)';
NODE_NAME     U25 BT40
 '@T6G_MB_LIB.T6G(SCH_1):PAGE24_I148@PURE_QUANTA.GENOA_SP5(CHIPS)':
 'P0_RXP15||SATA17_RXP': CDS_PINID='\p0_rxp15||sata17_rxp\';
NODE_NAME     U6010 M26
 '@T6G_MB_LIB.T6G(SCH_1):PAGE382_I2@PURE_QUANTA.PT5161LRS(CHIPS)':
 'A_PETP0': CDS_PINID='A_PETP0';
NET_NAME
'P5E_CPU0_P0_RX_DP<1>'
 '@T6G_MB_LIB.T6G(SCH_1):P5E_CPU0_P0_RX_DP'<1>:
 C_SIGNAL='@t6g_mb_lib.t6g(sch_1):p5e_cpu0_p0_rx_dp(1)';
NODE_NAME     U25 CA52
 '@T6G_MB_LIB.T6G(SCH_1):PAGE24_I148@PURE_QUANTA.GENOA_SP5(CHIPS)':
 'P0_RXP1||SATA01_RXP': CDS_PINID='\p0_rxp1||sata01_rxp\';
NODE_NAME     U6010 EK26
 '@T6G_MB_LIB.T6G(SCH_1):PAGE382_I3@PURE_QUANTA.PT5161LRS(CHIPS)':
 'A_PETP14': CDS_PINID='A_PETP14';
NET_NAME
'P5E_CPU0_P0_RX_DP<2>'
 '@T6G_MB_LIB.T6G(SCH_1):P5E_CPU0_P0_RX_DP'<2>:
 C_SIGNAL='@t6g_mb_lib.t6g(sch_1):p5e_cpu0_p0_rx_dp(2)';
NODE_NAME     U25 BU52
 '@T6G_MB_LIB.T6G(SCH_1):PAGE24_I148@PURE_QUANTA.GENOA_SP5(CHIPS)':
 'P0_RXP2||SATA02_RXP': CDS_PINID='\p0_rxp2||sata02_rxp\';
NODE_NAME     U6010 EC26
 '@T6G_MB_LIB.T6G(SCH_1):PAGE382_I3@PURE_QUANTA.PT5161LRS(CHIPS)':
 'A_PETP13': CDS_PINID='A_PETP13';
NET_NAME
'P5E_CPU0_P0_RX_DP<3>'
 '@T6G_MB_LIB.T6G(SCH_1):P5E_CPU0_P0_RX_DP'<3>:
 C_SIGNAL='@t6g_mb_lib.t6g(sch_1):p5e_cpu0_p0_rx_dp(3)';
NODE_NAME     U25 BW49
 '@T6G_MB_LIB.T6G(SCH_1):PAGE24_I148@PURE_QUANTA.GENOA_SP5(CHIPS)':
 'P0_RXP3||SATA03_RXP': CDS_PINID='\p0_rxp3||sata03_rxp\';
NODE_NAME     U6010 DT26
 '@T6G_MB_LIB.T6G(SCH_1):PAGE382_I3@PURE_QUANTA.PT5161LRS(CHIPS)':
 'A_PETP12': CDS_PINID='A_PETP12';
NET_NAME
'P5E_CPU0_P0_RX_DP<4>'
 '@T6G_MB_LIB.T6G(SCH_1):P5E_CPU0_P0_RX_DP'<4>:
 C_SIGNAL='@t6g_mb_lib.t6g(sch_1):p5e_cpu0_p0_rx_dp(4)';
NODE_NAME     U25 CA49
 '@T6G_MB_LIB.T6G(SCH_1):PAGE24_I148@PURE_QUANTA.GENOA_SP5(CHIPS)':
 'P0_RXP4||SATA04_RXP': CDS_PINID='\p0_rxp4||sata04_rxp\';
NODE_NAME     U6010 DJ26
 '@T6G_MB_LIB.T6G(SCH_1):PAGE382_I3@PURE_QUANTA.PT5161LRS(CHIPS)':
 'A_PETP11': CDS_PINID='A_PETP11';
NET_NAME
'P5E_CPU0_P0_RX_DP<5>'
 '@T6G_MB_LIB.T6G(SCH_1):P5E_CPU0_P0_RX_DP'<5>:
 C_SIGNAL='@t6g_mb_lib.t6g(sch_1):p5e_cpu0_p0_rx_dp(5)';
NODE_NAME     U25 BU49
 '@T6G_MB_LIB.T6G(SCH_1):PAGE24_I148@PURE_QUANTA.GENOA_SP5(CHIPS)':
 'P0_RXP5||SATA05_RXP': CDS_PINID='\p0_rxp5||sata05_rxp\';
NODE_NAME     U6010 DB26
 '@T6G_MB_LIB.T6G(SCH_1):PAGE382_I3@PURE_QUANTA.PT5161LRS(CHIPS)':
 'A_PETP10': CDS_PINID='A_PETP10';
NET_NAME
'P5E_CPU0_P0_RX_DP<6>'
 '@T6G_MB_LIB.T6G(SCH_1):P5E_CPU0_P0_RX_DP'<6>:
 C_SIGNAL='@t6g_mb_lib.t6g(sch_1):p5e_cpu0_p0_rx_dp(6)';
NODE_NAME     U25 BW46
 '@T6G_MB_LIB.T6G(SCH_1):PAGE24_I148@PURE_QUANTA.GENOA_SP5(CHIPS)':
 'P0_RXP6||SATA06_RXP': CDS_PINID='\p0_rxp6||sata06_rxp\';
NODE_NAME     U6010 CR26
 '@T6G_MB_LIB.T6G(SCH_1):PAGE382_I3@PURE_QUANTA.PT5161LRS(CHIPS)':
 'A_PETP9': CDS_PINID='A_PETP9';
NET_NAME
'P5E_CPU0_P0_RX_DP<7>'
 '@T6G_MB_LIB.T6G(SCH_1):P5E_CPU0_P0_RX_DP'<7>:
 C_SIGNAL='@t6g_mb_lib.t6g(sch_1):p5e_cpu0_p0_rx_dp(7)';
NODE_NAME     U25 CA46
 '@T6G_MB_LIB.T6G(SCH_1):PAGE24_I148@PURE_QUANTA.GENOA_SP5(CHIPS)':
 'P0_RXP7||SATA07_RXP': CDS_PINID='\p0_rxp7||sata07_rxp\';
NODE_NAME     U6010 CH26
 '@T6G_MB_LIB.T6G(SCH_1):PAGE382_I3@PURE_QUANTA.PT5161LRS(CHIPS)':
 'A_PETP8': CDS_PINID='A_PETP8';
NET_NAME
'P5E_CPU0_P0_RX_DP<8>'
 '@T6G_MB_LIB.T6G(SCH_1):P5E_CPU0_P0_RX_DP'<8>:
 C_SIGNAL='@t6g_mb_lib.t6g(sch_1):p5e_cpu0_p0_rx_dp(8)';
NODE_NAME     U25 BU46
 '@T6G_MB_LIB.T6G(SCH_1):PAGE24_I148@PURE_QUANTA.GENOA_SP5(CHIPS)':
 'P0_RXP8||SATA10_RXP': CDS_PINID='\p0_rxp8||sata10_rxp\';
NODE_NAME     U6010 CA26
 '@T6G_MB_LIB.T6G(SCH_1):PAGE382_I2@PURE_QUANTA.PT5161LRS(CHIPS)':
 'A_PETP7': CDS_PINID='A_PETP7';
NET_NAME
'P5E_CPU0_P0_RX_DP<9>'
 '@T6G_MB_LIB.T6G(SCH_1):P5E_CPU0_P0_RX_DP'<9>:
 C_SIGNAL='@t6g_mb_lib.t6g(sch_1):p5e_cpu0_p0_rx_dp(9)';
NODE_NAME     U25 BW43
 '@T6G_MB_LIB.T6G(SCH_1):PAGE24_I148@PURE_QUANTA.GENOA_SP5(CHIPS)':
 'P0_RXP9||SATA11_RXP': CDS_PINID='\p0_rxp9||sata11_rxp\';
NODE_NAME     U6010 BP26
 '@T6G_MB_LIB.T6G(SCH_1):PAGE382_I2@PURE_QUANTA.PT5161LRS(CHIPS)':
 'A_PETP6': CDS_PINID='A_PETP6';
NET_NAME
'P5E_CPU0_P0_TX_BUF_C_DN<0>'
 '@T6G_MB_LIB.T6G(SCH_1):P5E_CPU0_P0_TX_BUF_C_DN'<0>:
 C_SIGNAL='@t6g_mb_lib.t6g(sch_1):p5e_cpu0_p0_tx_buf_c_dn(0)';
NODE_NAME     C6502 1
 '@T6G_MB_LIB.T6G(SCH_1):PAGE384_I78@PURE_QUANTA.Q_CAP_DIFFBUS(CHIPS)':
 '1': CDS_PINID='\1\';
NODE_NAME     J108 I1
 '@T6G_MB_LIB.T6G(SCH_1):PAGE320_I72@PURE_QUANTA.CONN112_10137002101LF(CHIPS)':
 'I1': CDS_PINID='I1';
NET_NAME
'P5E_CPU0_P0_TX_BUF_C_DN<10>'
 '@T6G_MB_LIB.T6G(SCH_1):P5E_CPU0_P0_TX_BUF_C_DN'<10>:
 C_SIGNAL='@t6g_mb_lib.t6g(sch_1):p5e_cpu0_p0_tx_buf_c_dn(10)';
NODE_NAME     C6522 1
 '@T6G_MB_LIB.T6G(SCH_1):PAGE384_I118@PURE_QUANTA.Q_CAP_DIFFBUS(CHIPS)':
 '1': CDS_PINID='\1\';
NODE_NAME     J107 I3
 '@T6G_MB_LIB.T6G(SCH_1):PAGE317_I49@PURE_QUANTA.CONN112_10137002101LF(CHIPS)':
 'I3': CDS_PINID='I3';
NET_NAME
'P5E_CPU0_P0_TX_BUF_C_DN<11>'
 '@T6G_MB_LIB.T6G(SCH_1):P5E_CPU0_P0_TX_BUF_C_DN'<11>:
 C_SIGNAL='@t6g_mb_lib.t6g(sch_1):p5e_cpu0_p0_tx_buf_c_dn(11)';
NODE_NAME     C6524 1
 '@T6G_MB_LIB.T6G(SCH_1):PAGE384_I121@PURE_QUANTA.Q_CAP_DIFFBUS(CHIPS)':
 '1': CDS_PINID='\1\';
NODE_NAME     J107 H4
 '@T6G_MB_LIB.T6G(SCH_1):PAGE317_I49@PURE_QUANTA.CONN112_10137002101LF(CHIPS)':
 'H4': CDS_PINID='H4';
NET_NAME
'P5E_CPU0_P0_TX_BUF_C_DN<12>'
 '@T6G_MB_LIB.T6G(SCH_1):P5E_CPU0_P0_TX_BUF_C_DN'<12>:
 C_SIGNAL='@t6g_mb_lib.t6g(sch_1):p5e_cpu0_p0_tx_buf_c_dn(12)';
NODE_NAME     C6526 1
 '@T6G_MB_LIB.T6G(SCH_1):PAGE384_I122@PURE_QUANTA.Q_CAP_DIFFBUS(CHIPS)':
 '1': CDS_PINID='\1\';
NODE_NAME     J107 I5
 '@T6G_MB_LIB.T6G(SCH_1):PAGE317_I70@PURE_QUANTA.CONN112_10137002101LF(CHIPS)':
 'I5': CDS_PINID='I5';
NET_NAME
'P5E_CPU0_P0_TX_BUF_C_DN<13>'
 '@T6G_MB_LIB.T6G(SCH_1):P5E_CPU0_P0_TX_BUF_C_DN'<13>:
 C_SIGNAL='@t6g_mb_lib.t6g(sch_1):p5e_cpu0_p0_tx_buf_c_dn(13)';
NODE_NAME     C6528 1
 '@T6G_MB_LIB.T6G(SCH_1):PAGE384_I125@PURE_QUANTA.Q_CAP_DIFFBUS(CHIPS)':
 '1': CDS_PINID='\1\';
NODE_NAME     J107 H6
 '@T6G_MB_LIB.T6G(SCH_1):PAGE317_I70@PURE_QUANTA.CONN112_10137002101LF(CHIPS)':
 'H6': CDS_PINID='H6';
NET_NAME
'P5E_CPU0_P0_TX_BUF_C_DN<14>'
 '@T6G_MB_LIB.T6G(SCH_1):P5E_CPU0_P0_TX_BUF_C_DN'<14>:
 C_SIGNAL='@t6g_mb_lib.t6g(sch_1):p5e_cpu0_p0_tx_buf_c_dn(14)';
NODE_NAME     C6530 1
 '@T6G_MB_LIB.T6G(SCH_1):PAGE384_I127@PURE_QUANTA.Q_CAP_DIFFBUS(CHIPS)':
 '1': CDS_PINID='\1\';
NODE_NAME     J107 I7
 '@T6G_MB_LIB.T6G(SCH_1):PAGE317_I70@PURE_QUANTA.CONN112_10137002101LF(CHIPS)':
 'I7': CDS_PINID='I7';
NET_NAME
'P5E_CPU0_P0_TX_BUF_C_DN<15>'
 '@T6G_MB_LIB.T6G(SCH_1):P5E_CPU0_P0_TX_BUF_C_DN'<15>:
 C_SIGNAL='@t6g_mb_lib.t6g(sch_1):p5e_cpu0_p0_tx_buf_c_dn(15)';
NODE_NAME     C6532 1
 '@T6G_MB_LIB.T6G(SCH_1):PAGE384_I130@PURE_QUANTA.Q_CAP_DIFFBUS(CHIPS)':
 '1': CDS_PINID='\1\';
NODE_NAME     J107 H8
 '@T6G_MB_LIB.T6G(SCH_1):PAGE317_I70@PURE_QUANTA.CONN112_10137002101LF(CHIPS)':
 'H8': CDS_PINID='H8';
NET_NAME
'P5E_CPU0_P0_TX_BUF_C_DN<1>'
 '@T6G_MB_LIB.T6G(SCH_1):P5E_CPU0_P0_TX_BUF_C_DN'<1>:
 C_SIGNAL='@t6g_mb_lib.t6g(sch_1):p5e_cpu0_p0_tx_buf_c_dn(1)';
NODE_NAME     C6504 1
 '@T6G_MB_LIB.T6G(SCH_1):PAGE384_I76@PURE_QUANTA.Q_CAP_DIFFBUS(CHIPS)':
 '1': CDS_PINID='\1\';
NODE_NAME     J108 H2
 '@T6G_MB_LIB.T6G(SCH_1):PAGE320_I72@PURE_QUANTA.CONN112_10137002101LF(CHIPS)':
 'H2': CDS_PINID='H2';
NET_NAME
'P5E_CPU0_P0_TX_BUF_C_DN<2>'
 '@T6G_MB_LIB.T6G(SCH_1):P5E_CPU0_P0_TX_BUF_C_DN'<2>:
 C_SIGNAL='@t6g_mb_lib.t6g(sch_1):p5e_cpu0_p0_tx_buf_c_dn(2)';
NODE_NAME     C6506 1
 '@T6G_MB_LIB.T6G(SCH_1):PAGE384_I72@PURE_QUANTA.Q_CAP_DIFFBUS(CHIPS)':
 '1': CDS_PINID='\1\';
NODE_NAME     J108 I3
 '@T6G_MB_LIB.T6G(SCH_1):PAGE320_I72@PURE_QUANTA.CONN112_10137002101LF(CHIPS)':
 'I3': CDS_PINID='I3';
NET_NAME
'P5E_CPU0_P0_TX_BUF_C_DN<3>'
 '@T6G_MB_LIB.T6G(SCH_1):P5E_CPU0_P0_TX_BUF_C_DN'<3>:
 C_SIGNAL='@t6g_mb_lib.t6g(sch_1):p5e_cpu0_p0_tx_buf_c_dn(3)';
NODE_NAME     C6508 1
 '@T6G_MB_LIB.T6G(SCH_1):PAGE384_I71@PURE_QUANTA.Q_CAP_DIFFBUS(CHIPS)':
 '1': CDS_PINID='\1\';
NODE_NAME     J108 H4
 '@T6G_MB_LIB.T6G(SCH_1):PAGE320_I72@PURE_QUANTA.CONN112_10137002101LF(CHIPS)':
 'H4': CDS_PINID='H4';
NET_NAME
'P5E_CPU0_P0_TX_BUF_C_DN<4>'
 '@T6G_MB_LIB.T6G(SCH_1):P5E_CPU0_P0_TX_BUF_C_DN'<4>:
 C_SIGNAL='@t6g_mb_lib.t6g(sch_1):p5e_cpu0_p0_tx_buf_c_dn(4)';
NODE_NAME     C6510 1
 '@T6G_MB_LIB.T6G(SCH_1):PAGE384_I66@PURE_QUANTA.Q_CAP_DIFFBUS(CHIPS)':
 '1': CDS_PINID='\1\';
NODE_NAME     J108 I5
 '@T6G_MB_LIB.T6G(SCH_1):PAGE320_I15@PURE_QUANTA.CONN112_10137002101LF(CHIPS)':
 'I5': CDS_PINID='I5';
NET_NAME
'P5E_CPU0_P0_TX_BUF_C_DN<5>'
 '@T6G_MB_LIB.T6G(SCH_1):P5E_CPU0_P0_TX_BUF_C_DN'<5>:
 C_SIGNAL='@t6g_mb_lib.t6g(sch_1):p5e_cpu0_p0_tx_buf_c_dn(5)';
NODE_NAME     C6512 1
 '@T6G_MB_LIB.T6G(SCH_1):PAGE384_I64@PURE_QUANTA.Q_CAP_DIFFBUS(CHIPS)':
 '1': CDS_PINID='\1\';
NODE_NAME     J108 H6
 '@T6G_MB_LIB.T6G(SCH_1):PAGE320_I15@PURE_QUANTA.CONN112_10137002101LF(CHIPS)':
 'H6': CDS_PINID='H6';
NET_NAME
'P5E_CPU0_P0_TX_BUF_C_DN<6>'
 '@T6G_MB_LIB.T6G(SCH_1):P5E_CPU0_P0_TX_BUF_C_DN'<6>:
 C_SIGNAL='@t6g_mb_lib.t6g(sch_1):p5e_cpu0_p0_tx_buf_c_dn(6)';
NODE_NAME     C6514 1
 '@T6G_MB_LIB.T6G(SCH_1):PAGE384_I61@PURE_QUANTA.Q_CAP_DIFFBUS(CHIPS)':
 '1': CDS_PINID='\1\';
NODE_NAME     J108 I7
 '@T6G_MB_LIB.T6G(SCH_1):PAGE320_I15@PURE_QUANTA.CONN112_10137002101LF(CHIPS)':
 'I7': CDS_PINID='I7';
NET_NAME
'P5E_CPU0_P0_TX_BUF_C_DN<7>'
 '@T6G_MB_LIB.T6G(SCH_1):P5E_CPU0_P0_TX_BUF_C_DN'<7>:
 C_SIGNAL='@t6g_mb_lib.t6g(sch_1):p5e_cpu0_p0_tx_buf_c_dn(7)';
NODE_NAME     C6516 1
 '@T6G_MB_LIB.T6G(SCH_1):PAGE384_I59@PURE_QUANTA.Q_CAP_DIFFBUS(CHIPS)':
 '1': CDS_PINID='\1\';
NODE_NAME     J108 H8
 '@T6G_MB_LIB.T6G(SCH_1):PAGE320_I15@PURE_QUANTA.CONN112_10137002101LF(CHIPS)':
 'H8': CDS_PINID='H8';
NET_NAME
'P5E_CPU0_P0_TX_BUF_C_DN<8>'
 '@T6G_MB_LIB.T6G(SCH_1):P5E_CPU0_P0_TX_BUF_C_DN'<8>:
 C_SIGNAL='@t6g_mb_lib.t6g(sch_1):p5e_cpu0_p0_tx_buf_c_dn(8)';
NODE_NAME     C6518 1
 '@T6G_MB_LIB.T6G(SCH_1):PAGE384_I100@PURE_QUANTA.Q_CAP_DIFFBUS(CHIPS)':
 '1': CDS_PINID='\1\';
NODE_NAME     J107 I1
 '@T6G_MB_LIB.T6G(SCH_1):PAGE317_I49@PURE_QUANTA.CONN112_10137002101LF(CHIPS)':
 'I1': CDS_PINID='I1';
NET_NAME
'P5E_CPU0_P0_TX_BUF_C_DN<9>'
 '@T6G_MB_LIB.T6G(SCH_1):P5E_CPU0_P0_TX_BUF_C_DN'<9>:
 C_SIGNAL='@t6g_mb_lib.t6g(sch_1):p5e_cpu0_p0_tx_buf_c_dn(9)';
NODE_NAME     C6520 1
 '@T6G_MB_LIB.T6G(SCH_1):PAGE384_I101@PURE_QUANTA.Q_CAP_DIFFBUS(CHIPS)':
 '1': CDS_PINID='\1\';
NODE_NAME     J107 H2
 '@T6G_MB_LIB.T6G(SCH_1):PAGE317_I49@PURE_QUANTA.CONN112_10137002101LF(CHIPS)':
 'H2': CDS_PINID='H2';
NET_NAME
'P5E_CPU0_P0_TX_BUF_C_DP<0>'
 '@T6G_MB_LIB.T6G(SCH_1):P5E_CPU0_P0_TX_BUF_C_DP'<0>:
 C_SIGNAL='@t6g_mb_lib.t6g(sch_1):p5e_cpu0_p0_tx_buf_c_dp(0)';
NODE_NAME     C6501 1
 '@T6G_MB_LIB.T6G(SCH_1):PAGE384_I77@PURE_QUANTA.Q_CAP_DIFFBUS(CHIPS)':
 '1': CDS_PINID='\1\';
NODE_NAME     J108 J1
 '@T6G_MB_LIB.T6G(SCH_1):PAGE320_I72@PURE_QUANTA.CONN112_10137002101LF(CHIPS)':
 'J1': CDS_PINID='J1';
NET_NAME
'P5E_CPU0_P0_TX_BUF_C_DP<10>'
 '@T6G_MB_LIB.T6G(SCH_1):P5E_CPU0_P0_TX_BUF_C_DP'<10>:
 C_SIGNAL='@t6g_mb_lib.t6g(sch_1):p5e_cpu0_p0_tx_buf_c_dp(10)';
NODE_NAME     C6521 1
 '@T6G_MB_LIB.T6G(SCH_1):PAGE384_I119@PURE_QUANTA.Q_CAP_DIFFBUS(CHIPS)':
 '1': CDS_PINID='\1\';
NODE_NAME     J107 J3
 '@T6G_MB_LIB.T6G(SCH_1):PAGE317_I49@PURE_QUANTA.CONN112_10137002101LF(CHIPS)':
 'J3': CDS_PINID='J3';
NET_NAME
'P5E_CPU0_P0_TX_BUF_C_DP<11>'
 '@T6G_MB_LIB.T6G(SCH_1):P5E_CPU0_P0_TX_BUF_C_DP'<11>:
 C_SIGNAL='@t6g_mb_lib.t6g(sch_1):p5e_cpu0_p0_tx_buf_c_dp(11)';
NODE_NAME     C6523 1
 '@T6G_MB_LIB.T6G(SCH_1):PAGE384_I120@PURE_QUANTA.Q_CAP_DIFFBUS(CHIPS)':
 '1': CDS_PINID='\1\';
NODE_NAME     J107 I4
 '@T6G_MB_LIB.T6G(SCH_1):PAGE317_I49@PURE_QUANTA.CONN112_10137002101LF(CHIPS)':
 'I4': CDS_PINID='I4';
NET_NAME
'P5E_CPU0_P0_TX_BUF_C_DP<12>'
 '@T6G_MB_LIB.T6G(SCH_1):P5E_CPU0_P0_TX_BUF_C_DP'<12>:
 C_SIGNAL='@t6g_mb_lib.t6g(sch_1):p5e_cpu0_p0_tx_buf_c_dp(12)';
NODE_NAME     C6525 1
 '@T6G_MB_LIB.T6G(SCH_1):PAGE384_I123@PURE_QUANTA.Q_CAP_DIFFBUS(CHIPS)':
 '1': CDS_PINID='\1\';
NODE_NAME     J107 J5
 '@T6G_MB_LIB.T6G(SCH_1):PAGE317_I70@PURE_QUANTA.CONN112_10137002101LF(CHIPS)':
 'J5': CDS_PINID='J5';
NET_NAME
'P5E_CPU0_P0_TX_BUF_C_DP<13>'
 '@T6G_MB_LIB.T6G(SCH_1):P5E_CPU0_P0_TX_BUF_C_DP'<13>:
 C_SIGNAL='@t6g_mb_lib.t6g(sch_1):p5e_cpu0_p0_tx_buf_c_dp(13)';
NODE_NAME     C6527 1
 '@T6G_MB_LIB.T6G(SCH_1):PAGE384_I124@PURE_QUANTA.Q_CAP_DIFFBUS(CHIPS)':
 '1': CDS_PINID='\1\';
NODE_NAME     J107 I6
 '@T6G_MB_LIB.T6G(SCH_1):PAGE317_I70@PURE_QUANTA.CONN112_10137002101LF(CHIPS)':
 'I6': CDS_PINID='I6';
NET_NAME
'P5E_CPU0_P0_TX_BUF_C_DP<14>'
 '@T6G_MB_LIB.T6G(SCH_1):P5E_CPU0_P0_TX_BUF_C_DP'<14>:
 C_SIGNAL='@t6g_mb_lib.t6g(sch_1):p5e_cpu0_p0_tx_buf_c_dp(14)';
NODE_NAME     C6529 1
 '@T6G_MB_LIB.T6G(SCH_1):PAGE384_I126@PURE_QUANTA.Q_CAP_DIFFBUS(CHIPS)':
 '1': CDS_PINID='\1\';
NODE_NAME     J107 J7
 '@T6G_MB_LIB.T6G(SCH_1):PAGE317_I70@PURE_QUANTA.CONN112_10137002101LF(CHIPS)':
 'J7': CDS_PINID='J7';
NET_NAME
'P5E_CPU0_P0_TX_BUF_C_DP<15>'
 '@T6G_MB_LIB.T6G(SCH_1):P5E_CPU0_P0_TX_BUF_C_DP'<15>:
 C_SIGNAL='@t6g_mb_lib.t6g(sch_1):p5e_cpu0_p0_tx_buf_c_dp(15)';
NODE_NAME     C6531 1
 '@T6G_MB_LIB.T6G(SCH_1):PAGE384_I129@PURE_QUANTA.Q_CAP_DIFFBUS(CHIPS)':
 '1': CDS_PINID='\1\';
NODE_NAME     J107 I8
 '@T6G_MB_LIB.T6G(SCH_1):PAGE317_I70@PURE_QUANTA.CONN112_10137002101LF(CHIPS)':
 'I8': CDS_PINID='I8';
NET_NAME
'P5E_CPU0_P0_TX_BUF_C_DP<1>'
 '@T6G_MB_LIB.T6G(SCH_1):P5E_CPU0_P0_TX_BUF_C_DP'<1>:
 C_SIGNAL='@t6g_mb_lib.t6g(sch_1):p5e_cpu0_p0_tx_buf_c_dp(1)';
NODE_NAME     C6503 1
 '@T6G_MB_LIB.T6G(SCH_1):PAGE384_I75@PURE_QUANTA.Q_CAP_DIFFBUS(CHIPS)':
 '1': CDS_PINID='\1\';
NODE_NAME     J108 I2
 '@T6G_MB_LIB.T6G(SCH_1):PAGE320_I72@PURE_QUANTA.CONN112_10137002101LF(CHIPS)':
 'I2': CDS_PINID='I2';
NET_NAME
'P5E_CPU0_P0_TX_BUF_C_DP<2>'
 '@T6G_MB_LIB.T6G(SCH_1):P5E_CPU0_P0_TX_BUF_C_DP'<2>:
 C_SIGNAL='@t6g_mb_lib.t6g(sch_1):p5e_cpu0_p0_tx_buf_c_dp(2)';
NODE_NAME     C6505 1
 '@T6G_MB_LIB.T6G(SCH_1):PAGE384_I74@PURE_QUANTA.Q_CAP_DIFFBUS(CHIPS)':
 '1': CDS_PINID='\1\';
NODE_NAME     J108 J3
 '@T6G_MB_LIB.T6G(SCH_1):PAGE320_I72@PURE_QUANTA.CONN112_10137002101LF(CHIPS)':
 'J3': CDS_PINID='J3';
NET_NAME
'P5E_CPU0_P0_TX_BUF_C_DP<3>'
 '@T6G_MB_LIB.T6G(SCH_1):P5E_CPU0_P0_TX_BUF_C_DP'<3>:
 C_SIGNAL='@t6g_mb_lib.t6g(sch_1):p5e_cpu0_p0_tx_buf_c_dp(3)';
NODE_NAME     C6507 1
 '@T6G_MB_LIB.T6G(SCH_1):PAGE384_I73@PURE_QUANTA.Q_CAP_DIFFBUS(CHIPS)':
 '1': CDS_PINID='\1\';
NODE_NAME     J108 I4
 '@T6G_MB_LIB.T6G(SCH_1):PAGE320_I72@PURE_QUANTA.CONN112_10137002101LF(CHIPS)':
 'I4': CDS_PINID='I4';
NET_NAME
'P5E_CPU0_P0_TX_BUF_C_DP<4>'
 '@T6G_MB_LIB.T6G(SCH_1):P5E_CPU0_P0_TX_BUF_C_DP'<4>:
 C_SIGNAL='@t6g_mb_lib.t6g(sch_1):p5e_cpu0_p0_tx_buf_c_dp(4)';
NODE_NAME     C6509 1
 '@T6G_MB_LIB.T6G(SCH_1):PAGE384_I65@PURE_QUANTA.Q_CAP_DIFFBUS(CHIPS)':
 '1': CDS_PINID='\1\';
NODE_NAME     J108 J5
 '@T6G_MB_LIB.T6G(SCH_1):PAGE320_I15@PURE_QUANTA.CONN112_10137002101LF(CHIPS)':
 'J5': CDS_PINID='J5';
NET_NAME
'P5E_CPU0_P0_TX_BUF_C_DP<5>'
 '@T6G_MB_LIB.T6G(SCH_1):P5E_CPU0_P0_TX_BUF_C_DP'<5>:
 C_SIGNAL='@t6g_mb_lib.t6g(sch_1):p5e_cpu0_p0_tx_buf_c_dp(5)';
NODE_NAME     C6511 1
 '@T6G_MB_LIB.T6G(SCH_1):PAGE384_I63@PURE_QUANTA.Q_CAP_DIFFBUS(CHIPS)':
 '1': CDS_PINID='\1\';
NODE_NAME     J108 I6
 '@T6G_MB_LIB.T6G(SCH_1):PAGE320_I15@PURE_QUANTA.CONN112_10137002101LF(CHIPS)':
 'I6': CDS_PINID='I6';
NET_NAME
'P5E_CPU0_P0_TX_BUF_C_DP<6>'
 '@T6G_MB_LIB.T6G(SCH_1):P5E_CPU0_P0_TX_BUF_C_DP'<6>:
 C_SIGNAL='@t6g_mb_lib.t6g(sch_1):p5e_cpu0_p0_tx_buf_c_dp(6)';
NODE_NAME     C6513 1
 '@T6G_MB_LIB.T6G(SCH_1):PAGE384_I60@PURE_QUANTA.Q_CAP_DIFFBUS(CHIPS)':
 '1': CDS_PINID='\1\';
NODE_NAME     J108 J7
 '@T6G_MB_LIB.T6G(SCH_1):PAGE320_I15@PURE_QUANTA.CONN112_10137002101LF(CHIPS)':
 'J7': CDS_PINID='J7';
NET_NAME
'P5E_CPU0_P0_TX_BUF_C_DP<7>'
 '@T6G_MB_LIB.T6G(SCH_1):P5E_CPU0_P0_TX_BUF_C_DP'<7>:
 C_SIGNAL='@t6g_mb_lib.t6g(sch_1):p5e_cpu0_p0_tx_buf_c_dp(7)';
NODE_NAME     C6515 1
 '@T6G_MB_LIB.T6G(SCH_1):PAGE384_I62@PURE_QUANTA.Q_CAP_DIFFBUS(CHIPS)':
 '1': CDS_PINID='\1\';
NODE_NAME     J108 I8
 '@T6G_MB_LIB.T6G(SCH_1):PAGE320_I15@PURE_QUANTA.CONN112_10137002101LF(CHIPS)':
 'I8': CDS_PINID='I8';
NET_NAME
'P5E_CPU0_P0_TX_BUF_C_DP<8>'
 '@T6G_MB_LIB.T6G(SCH_1):P5E_CPU0_P0_TX_BUF_C_DP'<8>:
 C_SIGNAL='@t6g_mb_lib.t6g(sch_1):p5e_cpu0_p0_tx_buf_c_dp(8)';
NODE_NAME     C6517 1
 '@T6G_MB_LIB.T6G(SCH_1):PAGE384_I99@PURE_QUANTA.Q_CAP_DIFFBUS(CHIPS)':
 '1': CDS_PINID='\1\';
NODE_NAME     J107 J1
 '@T6G_MB_LIB.T6G(SCH_1):PAGE317_I49@PURE_QUANTA.CONN112_10137002101LF(CHIPS)':
 'J1': CDS_PINID='J1';
NET_NAME
'P5E_CPU0_P0_TX_BUF_C_DP<9>'
 '@T6G_MB_LIB.T6G(SCH_1):P5E_CPU0_P0_TX_BUF_C_DP'<9>:
 C_SIGNAL='@t6g_mb_lib.t6g(sch_1):p5e_cpu0_p0_tx_buf_c_dp(9)';
NODE_NAME     C6519 1
 '@T6G_MB_LIB.T6G(SCH_1):PAGE384_I102@PURE_QUANTA.Q_CAP_DIFFBUS(CHIPS)':
 '1': CDS_PINID='\1\';
NODE_NAME     J107 I2
 '@T6G_MB_LIB.T6G(SCH_1):PAGE317_I49@PURE_QUANTA.CONN112_10137002101LF(CHIPS)':
 'I2': CDS_PINID='I2';
NET_NAME
'P5E_CPU0_P0_TX_BUF_DN<0>'
 '@T6G_MB_LIB.T6G(SCH_1):P5E_CPU0_P0_TX_BUF_DN'<0>:
 C_SIGNAL='@t6g_mb_lib.t6g(sch_1):p5e_cpu0_p0_tx_buf_dn(0)';
NODE_NAME     U6010 EW10
 '@T6G_MB_LIB.T6G(SCH_1):PAGE384_I2@PURE_QUANTA.PT5161LRS(CHIPS)':
 'B_PETN15': CDS_PINID='B_PETN15';
NODE_NAME     C6502 2
 '@T6G_MB_LIB.T6G(SCH_1):PAGE384_I78@PURE_QUANTA.Q_CAP_DIFFBUS(CHIPS)':
 '2': CDS_PINID='\2\';
NET_NAME
'P5E_CPU0_P0_TX_BUF_DN<10>'
 '@T6G_MB_LIB.T6G(SCH_1):P5E_CPU0_P0_TX_BUF_DN'<10>:
 C_SIGNAL='@t6g_mb_lib.t6g(sch_1):p5e_cpu0_p0_tx_buf_dn(10)';
NODE_NAME     U6010 BJ10
 '@T6G_MB_LIB.T6G(SCH_1):PAGE384_I1@PURE_QUANTA.PT5161LRS(CHIPS)':
 'B_PETN5': CDS_PINID='B_PETN5';
NODE_NAME     C6522 2
 '@T6G_MB_LIB.T6G(SCH_1):PAGE384_I118@PURE_QUANTA.Q_CAP_DIFFBUS(CHIPS)':
 '2': CDS_PINID='\2\';
NET_NAME
'P5E_CPU0_P0_TX_BUF_DN<11>'
 '@T6G_MB_LIB.T6G(SCH_1):P5E_CPU0_P0_TX_BUF_DN'<11>:
 C_SIGNAL='@t6g_mb_lib.t6g(sch_1):p5e_cpu0_p0_tx_buf_dn(11)';
NODE_NAME     U6010 BB10
 '@T6G_MB_LIB.T6G(SCH_1):PAGE384_I1@PURE_QUANTA.PT5161LRS(CHIPS)':
 'B_PETN4': CDS_PINID='B_PETN4';
NODE_NAME     C6524 2
 '@T6G_MB_LIB.T6G(SCH_1):PAGE384_I121@PURE_QUANTA.Q_CAP_DIFFBUS(CHIPS)':
 '2': CDS_PINID='\2\';
NET_NAME
'P5E_CPU0_P0_TX_BUF_DN<12>'
 '@T6G_MB_LIB.T6G(SCH_1):P5E_CPU0_P0_TX_BUF_DN'<12>:
 C_SIGNAL='@t6g_mb_lib.t6g(sch_1):p5e_cpu0_p0_tx_buf_dn(12)';
NODE_NAME     U6010 AR10
 '@T6G_MB_LIB.T6G(SCH_1):PAGE384_I1@PURE_QUANTA.PT5161LRS(CHIPS)':
 'B_PETN3': CDS_PINID='B_PETN3';
NODE_NAME     C6526 2
 '@T6G_MB_LIB.T6G(SCH_1):PAGE384_I122@PURE_QUANTA.Q_CAP_DIFFBUS(CHIPS)':
 '2': CDS_PINID='\2\';
NET_NAME
'P5E_CPU0_P0_TX_BUF_DN<13>'
 '@T6G_MB_LIB.T6G(SCH_1):P5E_CPU0_P0_TX_BUF_DN'<13>:
 C_SIGNAL='@t6g_mb_lib.t6g(sch_1):p5e_cpu0_p0_tx_buf_dn(13)';
NODE_NAME     U6010 AH10
 '@T6G_MB_LIB.T6G(SCH_1):PAGE384_I1@PURE_QUANTA.PT5161LRS(CHIPS)':
 'B_PETN2': CDS_PINID='B_PETN2';
NODE_NAME     C6528 2
 '@T6G_MB_LIB.T6G(SCH_1):PAGE384_I125@PURE_QUANTA.Q_CAP_DIFFBUS(CHIPS)':
 '2': CDS_PINID='\2\';
NET_NAME
'P5E_CPU0_P0_TX_BUF_DN<14>'
 '@T6G_MB_LIB.T6G(SCH_1):P5E_CPU0_P0_TX_BUF_DN'<14>:
 C_SIGNAL='@t6g_mb_lib.t6g(sch_1):p5e_cpu0_p0_tx_buf_dn(14)';
NODE_NAME     U6010 AA10
 '@T6G_MB_LIB.T6G(SCH_1):PAGE384_I1@PURE_QUANTA.PT5161LRS(CHIPS)':
 'B_PETN1': CDS_PINID='B_PETN1';
NODE_NAME     C6530 2
 '@T6G_MB_LIB.T6G(SCH_1):PAGE384_I127@PURE_QUANTA.Q_CAP_DIFFBUS(CHIPS)':
 '2': CDS_PINID='\2\';
NET_NAME
'P5E_CPU0_P0_TX_BUF_DN<15>'
 '@T6G_MB_LIB.T6G(SCH_1):P5E_CPU0_P0_TX_BUF_DN'<15>:
 C_SIGNAL='@t6g_mb_lib.t6g(sch_1):p5e_cpu0_p0_tx_buf_dn(15)';
NODE_NAME     U6010 P10
 '@T6G_MB_LIB.T6G(SCH_1):PAGE384_I1@PURE_QUANTA.PT5161LRS(CHIPS)':
 'B_PETN0': CDS_PINID='B_PETN0';
NODE_NAME     C6532 2
 '@T6G_MB_LIB.T6G(SCH_1):PAGE384_I130@PURE_QUANTA.Q_CAP_DIFFBUS(CHIPS)':
 '2': CDS_PINID='\2\';
NET_NAME
'P5E_CPU0_P0_TX_BUF_DN<1>'
 '@T6G_MB_LIB.T6G(SCH_1):P5E_CPU0_P0_TX_BUF_DN'<1>:
 C_SIGNAL='@t6g_mb_lib.t6g(sch_1):p5e_cpu0_p0_tx_buf_dn(1)';
NODE_NAME     U6010 EM10
 '@T6G_MB_LIB.T6G(SCH_1):PAGE384_I2@PURE_QUANTA.PT5161LRS(CHIPS)':
 'B_PETN14': CDS_PINID='B_PETN14';
NODE_NAME     C6504 2
 '@T6G_MB_LIB.T6G(SCH_1):PAGE384_I76@PURE_QUANTA.Q_CAP_DIFFBUS(CHIPS)':
 '2': CDS_PINID='\2\';
NET_NAME
'P5E_CPU0_P0_TX_BUF_DN<2>'
 '@T6G_MB_LIB.T6G(SCH_1):P5E_CPU0_P0_TX_BUF_DN'<2>:
 C_SIGNAL='@t6g_mb_lib.t6g(sch_1):p5e_cpu0_p0_tx_buf_dn(2)';
NODE_NAME     U6010 EE10
 '@T6G_MB_LIB.T6G(SCH_1):PAGE384_I2@PURE_QUANTA.PT5161LRS(CHIPS)':
 'B_PETN13': CDS_PINID='B_PETN13';
NODE_NAME     C6506 2
 '@T6G_MB_LIB.T6G(SCH_1):PAGE384_I72@PURE_QUANTA.Q_CAP_DIFFBUS(CHIPS)':
 '2': CDS_PINID='\2\';
NET_NAME
'P5E_CPU0_P0_TX_BUF_DN<3>'
 '@T6G_MB_LIB.T6G(SCH_1):P5E_CPU0_P0_TX_BUF_DN'<3>:
 C_SIGNAL='@t6g_mb_lib.t6g(sch_1):p5e_cpu0_p0_tx_buf_dn(3)';
NODE_NAME     U6010 DV10
 '@T6G_MB_LIB.T6G(SCH_1):PAGE384_I2@PURE_QUANTA.PT5161LRS(CHIPS)':
 'B_PETN12': CDS_PINID='B_PETN12';
NODE_NAME     C6508 2
 '@T6G_MB_LIB.T6G(SCH_1):PAGE384_I71@PURE_QUANTA.Q_CAP_DIFFBUS(CHIPS)':
 '2': CDS_PINID='\2\';
NET_NAME
'P5E_CPU0_P0_TX_BUF_DN<4>'
 '@T6G_MB_LIB.T6G(SCH_1):P5E_CPU0_P0_TX_BUF_DN'<4>:
 C_SIGNAL='@t6g_mb_lib.t6g(sch_1):p5e_cpu0_p0_tx_buf_dn(4)';
NODE_NAME     U6010 DL10
 '@T6G_MB_LIB.T6G(SCH_1):PAGE384_I2@PURE_QUANTA.PT5161LRS(CHIPS)':
 'B_PETN11': CDS_PINID='B_PETN11';
NODE_NAME     C6510 2
 '@T6G_MB_LIB.T6G(SCH_1):PAGE384_I66@PURE_QUANTA.Q_CAP_DIFFBUS(CHIPS)':
 '2': CDS_PINID='\2\';
NET_NAME
'P5E_CPU0_P0_TX_BUF_DN<5>'
 '@T6G_MB_LIB.T6G(SCH_1):P5E_CPU0_P0_TX_BUF_DN'<5>:
 C_SIGNAL='@t6g_mb_lib.t6g(sch_1):p5e_cpu0_p0_tx_buf_dn(5)';
NODE_NAME     U6010 DD10
 '@T6G_MB_LIB.T6G(SCH_1):PAGE384_I2@PURE_QUANTA.PT5161LRS(CHIPS)':
 'B_PETN10': CDS_PINID='B_PETN10';
NODE_NAME     C6512 2
 '@T6G_MB_LIB.T6G(SCH_1):PAGE384_I64@PURE_QUANTA.Q_CAP_DIFFBUS(CHIPS)':
 '2': CDS_PINID='\2\';
NET_NAME
'P5E_CPU0_P0_TX_BUF_DN<6>'
 '@T6G_MB_LIB.T6G(SCH_1):P5E_CPU0_P0_TX_BUF_DN'<6>:
 C_SIGNAL='@t6g_mb_lib.t6g(sch_1):p5e_cpu0_p0_tx_buf_dn(6)';
NODE_NAME     U6010 CU10
 '@T6G_MB_LIB.T6G(SCH_1):PAGE384_I2@PURE_QUANTA.PT5161LRS(CHIPS)':
 'B_PETN9': CDS_PINID='B_PETN9';
NODE_NAME     C6514 2
 '@T6G_MB_LIB.T6G(SCH_1):PAGE384_I61@PURE_QUANTA.Q_CAP_DIFFBUS(CHIPS)':
 '2': CDS_PINID='\2\';
NET_NAME
'P5E_CPU0_P0_TX_BUF_DN<7>'
 '@T6G_MB_LIB.T6G(SCH_1):P5E_CPU0_P0_TX_BUF_DN'<7>:
 C_SIGNAL='@t6g_mb_lib.t6g(sch_1):p5e_cpu0_p0_tx_buf_dn(7)';
NODE_NAME     U6010 CK10
 '@T6G_MB_LIB.T6G(SCH_1):PAGE384_I2@PURE_QUANTA.PT5161LRS(CHIPS)':
 'B_PETN8': CDS_PINID='B_PETN8';
NODE_NAME     C6516 2
 '@T6G_MB_LIB.T6G(SCH_1):PAGE384_I59@PURE_QUANTA.Q_CAP_DIFFBUS(CHIPS)':
 '2': CDS_PINID='\2\';
NET_NAME
'P5E_CPU0_P0_TX_BUF_DN<8>'
 '@T6G_MB_LIB.T6G(SCH_1):P5E_CPU0_P0_TX_BUF_DN'<8>:
 C_SIGNAL='@t6g_mb_lib.t6g(sch_1):p5e_cpu0_p0_tx_buf_dn(8)';
NODE_NAME     U6010 CC10
 '@T6G_MB_LIB.T6G(SCH_1):PAGE384_I1@PURE_QUANTA.PT5161LRS(CHIPS)':
 'B_PETN7': CDS_PINID='B_PETN7';
NODE_NAME     C6518 2
 '@T6G_MB_LIB.T6G(SCH_1):PAGE384_I100@PURE_QUANTA.Q_CAP_DIFFBUS(CHIPS)':
 '2': CDS_PINID='\2\';
NET_NAME
'P5E_CPU0_P0_TX_BUF_DN<9>'
 '@T6G_MB_LIB.T6G(SCH_1):P5E_CPU0_P0_TX_BUF_DN'<9>:
 C_SIGNAL='@t6g_mb_lib.t6g(sch_1):p5e_cpu0_p0_tx_buf_dn(9)';
NODE_NAME     U6010 BT10
 '@T6G_MB_LIB.T6G(SCH_1):PAGE384_I1@PURE_QUANTA.PT5161LRS(CHIPS)':
 'B_PETN6': CDS_PINID='B_PETN6';
NODE_NAME     C6520 2
 '@T6G_MB_LIB.T6G(SCH_1):PAGE384_I101@PURE_QUANTA.Q_CAP_DIFFBUS(CHIPS)':
 '2': CDS_PINID='\2\';
NET_NAME
'P5E_CPU0_P0_TX_BUF_DP<0>'
 '@T6G_MB_LIB.T6G(SCH_1):P5E_CPU0_P0_TX_BUF_DP'<0>:
 C_SIGNAL='@t6g_mb_lib.t6g(sch_1):p5e_cpu0_p0_tx_buf_dp(0)';
NODE_NAME     U6010 EU7
 '@T6G_MB_LIB.T6G(SCH_1):PAGE384_I2@PURE_QUANTA.PT5161LRS(CHIPS)':
 'B_PETP15': CDS_PINID='B_PETP15';
NODE_NAME     C6501 2
 '@T6G_MB_LIB.T6G(SCH_1):PAGE384_I77@PURE_QUANTA.Q_CAP_DIFFBUS(CHIPS)':
 '2': CDS_PINID='\2\';
NET_NAME
'P5E_CPU0_P0_TX_BUF_DP<10>'
 '@T6G_MB_LIB.T6G(SCH_1):P5E_CPU0_P0_TX_BUF_DP'<10>:
 C_SIGNAL='@t6g_mb_lib.t6g(sch_1):p5e_cpu0_p0_tx_buf_dp(10)';
NODE_NAME     U6010 BG7
 '@T6G_MB_LIB.T6G(SCH_1):PAGE384_I1@PURE_QUANTA.PT5161LRS(CHIPS)':
 'B_PETP5': CDS_PINID='B_PETP5';
NODE_NAME     C6521 2
 '@T6G_MB_LIB.T6G(SCH_1):PAGE384_I119@PURE_QUANTA.Q_CAP_DIFFBUS(CHIPS)':
 '2': CDS_PINID='\2\';
NET_NAME
'P5E_CPU0_P0_TX_BUF_DP<11>'
 '@T6G_MB_LIB.T6G(SCH_1):P5E_CPU0_P0_TX_BUF_DP'<11>:
 C_SIGNAL='@t6g_mb_lib.t6g(sch_1):p5e_cpu0_p0_tx_buf_dp(11)';
NODE_NAME     U6010 AY7
 '@T6G_MB_LIB.T6G(SCH_1):PAGE384_I1@PURE_QUANTA.PT5161LRS(CHIPS)':
 'B_PETP4': CDS_PINID='B_PETP4';
NODE_NAME     C6523 2
 '@T6G_MB_LIB.T6G(SCH_1):PAGE384_I120@PURE_QUANTA.Q_CAP_DIFFBUS(CHIPS)':
 '2': CDS_PINID='\2\';
NET_NAME
'P5E_CPU0_P0_TX_BUF_DP<12>'
 '@T6G_MB_LIB.T6G(SCH_1):P5E_CPU0_P0_TX_BUF_DP'<12>:
 C_SIGNAL='@t6g_mb_lib.t6g(sch_1):p5e_cpu0_p0_tx_buf_dp(12)';
NODE_NAME     U6010 AN7
 '@T6G_MB_LIB.T6G(SCH_1):PAGE384_I1@PURE_QUANTA.PT5161LRS(CHIPS)':
 'B_PETP3': CDS_PINID='B_PETP3';
NODE_NAME     C6525 2
 '@T6G_MB_LIB.T6G(SCH_1):PAGE384_I123@PURE_QUANTA.Q_CAP_DIFFBUS(CHIPS)':
 '2': CDS_PINID='\2\';
NET_NAME
'P5E_CPU0_P0_TX_BUF_DP<13>'
 '@T6G_MB_LIB.T6G(SCH_1):P5E_CPU0_P0_TX_BUF_DP'<13>:
 C_SIGNAL='@t6g_mb_lib.t6g(sch_1):p5e_cpu0_p0_tx_buf_dp(13)';
NODE_NAME     U6010 AF7
 '@T6G_MB_LIB.T6G(SCH_1):PAGE384_I1@PURE_QUANTA.PT5161LRS(CHIPS)':
 'B_PETP2': CDS_PINID='B_PETP2';
NODE_NAME     C6527 2
 '@T6G_MB_LIB.T6G(SCH_1):PAGE384_I124@PURE_QUANTA.Q_CAP_DIFFBUS(CHIPS)':
 '2': CDS_PINID='\2\';
NET_NAME
'P5E_CPU0_P0_TX_BUF_DP<14>'
 '@T6G_MB_LIB.T6G(SCH_1):P5E_CPU0_P0_TX_BUF_DP'<14>:
 C_SIGNAL='@t6g_mb_lib.t6g(sch_1):p5e_cpu0_p0_tx_buf_dp(14)';
NODE_NAME     U6010 W7
 '@T6G_MB_LIB.T6G(SCH_1):PAGE384_I1@PURE_QUANTA.PT5161LRS(CHIPS)':
 'B_PETP1': CDS_PINID='B_PETP1';
NODE_NAME     C6529 2
 '@T6G_MB_LIB.T6G(SCH_1):PAGE384_I126@PURE_QUANTA.Q_CAP_DIFFBUS(CHIPS)':
 '2': CDS_PINID='\2\';
NET_NAME
'P5E_CPU0_P0_TX_BUF_DP<15>'
 '@T6G_MB_LIB.T6G(SCH_1):P5E_CPU0_P0_TX_BUF_DP'<15>:
 C_SIGNAL='@t6g_mb_lib.t6g(sch_1):p5e_cpu0_p0_tx_buf_dp(15)';
NODE_NAME     U6010 M7
 '@T6G_MB_LIB.T6G(SCH_1):PAGE384_I1@PURE_QUANTA.PT5161LRS(CHIPS)':
 'B_PETP0': CDS_PINID='B_PETP0';
NODE_NAME     C6531 2
 '@T6G_MB_LIB.T6G(SCH_1):PAGE384_I129@PURE_QUANTA.Q_CAP_DIFFBUS(CHIPS)':
 '2': CDS_PINID='\2\';
NET_NAME
'P5E_CPU0_P0_TX_BUF_DP<1>'
 '@T6G_MB_LIB.T6G(SCH_1):P5E_CPU0_P0_TX_BUF_DP'<1>:
 C_SIGNAL='@t6g_mb_lib.t6g(sch_1):p5e_cpu0_p0_tx_buf_dp(1)';
NODE_NAME     U6010 EK7
 '@T6G_MB_LIB.T6G(SCH_1):PAGE384_I2@PURE_QUANTA.PT5161LRS(CHIPS)':
 'B_PETP14': CDS_PINID='B_PETP14';
NODE_NAME     C6503 2
 '@T6G_MB_LIB.T6G(SCH_1):PAGE384_I75@PURE_QUANTA.Q_CAP_DIFFBUS(CHIPS)':
 '2': CDS_PINID='\2\';
NET_NAME
'P5E_CPU0_P0_TX_BUF_DP<2>'
 '@T6G_MB_LIB.T6G(SCH_1):P5E_CPU0_P0_TX_BUF_DP'<2>:
 C_SIGNAL='@t6g_mb_lib.t6g(sch_1):p5e_cpu0_p0_tx_buf_dp(2)';
NODE_NAME     U6010 EC7
 '@T6G_MB_LIB.T6G(SCH_1):PAGE384_I2@PURE_QUANTA.PT5161LRS(CHIPS)':
 'B_PETP13': CDS_PINID='B_PETP13';
NODE_NAME     C6505 2
 '@T6G_MB_LIB.T6G(SCH_1):PAGE384_I74@PURE_QUANTA.Q_CAP_DIFFBUS(CHIPS)':
 '2': CDS_PINID='\2\';
NET_NAME
'P5E_CPU0_P0_TX_BUF_DP<3>'
 '@T6G_MB_LIB.T6G(SCH_1):P5E_CPU0_P0_TX_BUF_DP'<3>:
 C_SIGNAL='@t6g_mb_lib.t6g(sch_1):p5e_cpu0_p0_tx_buf_dp(3)';
NODE_NAME     U6010 DT7
 '@T6G_MB_LIB.T6G(SCH_1):PAGE384_I2@PURE_QUANTA.PT5161LRS(CHIPS)':
 'B_PETP12': CDS_PINID='B_PETP12';
NODE_NAME     C6507 2
 '@T6G_MB_LIB.T6G(SCH_1):PAGE384_I73@PURE_QUANTA.Q_CAP_DIFFBUS(CHIPS)':
 '2': CDS_PINID='\2\';
NET_NAME
'P5E_CPU0_P0_TX_BUF_DP<4>'
 '@T6G_MB_LIB.T6G(SCH_1):P5E_CPU0_P0_TX_BUF_DP'<4>:
 C_SIGNAL='@t6g_mb_lib.t6g(sch_1):p5e_cpu0_p0_tx_buf_dp(4)';
NODE_NAME     U6010 DJ7
 '@T6G_MB_LIB.T6G(SCH_1):PAGE384_I2@PURE_QUANTA.PT5161LRS(CHIPS)':
 'B_PETP11': CDS_PINID='B_PETP11';
NODE_NAME     C6509 2
 '@T6G_MB_LIB.T6G(SCH_1):PAGE384_I65@PURE_QUANTA.Q_CAP_DIFFBUS(CHIPS)':
 '2': CDS_PINID='\2\';
NET_NAME
'P5E_CPU0_P0_TX_BUF_DP<5>'
 '@T6G_MB_LIB.T6G(SCH_1):P5E_CPU0_P0_TX_BUF_DP'<5>:
 C_SIGNAL='@t6g_mb_lib.t6g(sch_1):p5e_cpu0_p0_tx_buf_dp(5)';
NODE_NAME     U6010 DB7
 '@T6G_MB_LIB.T6G(SCH_1):PAGE384_I2@PURE_QUANTA.PT5161LRS(CHIPS)':
 'B_PETP10': CDS_PINID='B_PETP10';
NODE_NAME     C6511 2
 '@T6G_MB_LIB.T6G(SCH_1):PAGE384_I63@PURE_QUANTA.Q_CAP_DIFFBUS(CHIPS)':
 '2': CDS_PINID='\2\';
NET_NAME
'P5E_CPU0_P0_TX_BUF_DP<6>'
 '@T6G_MB_LIB.T6G(SCH_1):P5E_CPU0_P0_TX_BUF_DP'<6>:
 C_SIGNAL='@t6g_mb_lib.t6g(sch_1):p5e_cpu0_p0_tx_buf_dp(6)';
NODE_NAME     U6010 CR7
 '@T6G_MB_LIB.T6G(SCH_1):PAGE384_I2@PURE_QUANTA.PT5161LRS(CHIPS)':
 'B_PETP9': CDS_PINID='B_PETP9';
NODE_NAME     C6513 2
 '@T6G_MB_LIB.T6G(SCH_1):PAGE384_I60@PURE_QUANTA.Q_CAP_DIFFBUS(CHIPS)':
 '2': CDS_PINID='\2\';
NET_NAME
'P5E_CPU0_P0_TX_BUF_DP<7>'
 '@T6G_MB_LIB.T6G(SCH_1):P5E_CPU0_P0_TX_BUF_DP'<7>:
 C_SIGNAL='@t6g_mb_lib.t6g(sch_1):p5e_cpu0_p0_tx_buf_dp(7)';
NODE_NAME     U6010 CH7
 '@T6G_MB_LIB.T6G(SCH_1):PAGE384_I2@PURE_QUANTA.PT5161LRS(CHIPS)':
 'B_PETP8': CDS_PINID='B_PETP8';
NODE_NAME     C6515 2
 '@T6G_MB_LIB.T6G(SCH_1):PAGE384_I62@PURE_QUANTA.Q_CAP_DIFFBUS(CHIPS)':
 '2': CDS_PINID='\2\';
NET_NAME
'P5E_CPU0_P0_TX_BUF_DP<8>'
 '@T6G_MB_LIB.T6G(SCH_1):P5E_CPU0_P0_TX_BUF_DP'<8>:
 C_SIGNAL='@t6g_mb_lib.t6g(sch_1):p5e_cpu0_p0_tx_buf_dp(8)';
NODE_NAME     U6010 CA7
 '@T6G_MB_LIB.T6G(SCH_1):PAGE384_I1@PURE_QUANTA.PT5161LRS(CHIPS)':
 'B_PETP7': CDS_PINID='B_PETP7';
NODE_NAME     C6517 2
 '@T6G_MB_LIB.T6G(SCH_1):PAGE384_I99@PURE_QUANTA.Q_CAP_DIFFBUS(CHIPS)':
 '2': CDS_PINID='\2\';
NET_NAME
'P5E_CPU0_P0_TX_BUF_DP<9>'
 '@T6G_MB_LIB.T6G(SCH_1):P5E_CPU0_P0_TX_BUF_DP'<9>:
 C_SIGNAL='@t6g_mb_lib.t6g(sch_1):p5e_cpu0_p0_tx_buf_dp(9)';
NODE_NAME     U6010 BP7
 '@T6G_MB_LIB.T6G(SCH_1):PAGE384_I1@PURE_QUANTA.PT5161LRS(CHIPS)':
 'B_PETP6': CDS_PINID='B_PETP6';
NODE_NAME     C6519 2
 '@T6G_MB_LIB.T6G(SCH_1):PAGE384_I102@PURE_QUANTA.Q_CAP_DIFFBUS(CHIPS)':
 '2': CDS_PINID='\2\';
NET_NAME
'P5E_CPU0_P0_TX_C_DN<0>'
 '@T6G_MB_LIB.T6G(SCH_1):P5E_CPU0_P0_TX_C_DN'<0>:
 C_SIGNAL='@t6g_mb_lib.t6g(sch_1):p5e_cpu0_p0_tx_c_dn(0)';
NODE_NAME     C932 1
 '@T6G_MB_LIB.T6G(SCH_1):PAGE351_I21@PURE_QUANTA.Q_CAP_DIFFBUS(CHIPS)':
 '1': CDS_PINID='\1\';
NODE_NAME     U6010 EV34
 '@T6G_MB_LIB.T6G(SCH_1):PAGE381_I4@PURE_QUANTA.PT5161LRS(CHIPS)':
 'B_PERP15': CDS_PINID='B_PERP15';
NET_NAME
'P5E_CPU0_P0_TX_C_DN<10>'
 '@T6G_MB_LIB.T6G(SCH_1):P5E_CPU0_P0_TX_C_DN'<10>:
 C_SIGNAL='@t6g_mb_lib.t6g(sch_1):p5e_cpu0_p0_tx_c_dn(10)';
NODE_NAME     C912 1
 '@T6G_MB_LIB.T6G(SCH_1):PAGE351_I58@PURE_QUANTA.Q_CAP_DIFFBUS(CHIPS)':
 '1': CDS_PINID='\1\';
NODE_NAME     U6010 BH34
 '@T6G_MB_LIB.T6G(SCH_1):PAGE381_I3@PURE_QUANTA.PT5161LRS(CHIPS)':
 'B_PERP5': CDS_PINID='B_PERP5';
NET_NAME
'P5E_CPU0_P0_TX_C_DN<11>'
 '@T6G_MB_LIB.T6G(SCH_1):P5E_CPU0_P0_TX_C_DN'<11>:
 C_SIGNAL='@t6g_mb_lib.t6g(sch_1):p5e_cpu0_p0_tx_c_dn(11)';
NODE_NAME     C910 1
 '@T6G_MB_LIB.T6G(SCH_1):PAGE351_I60@PURE_QUANTA.Q_CAP_DIFFBUS(CHIPS)':
 '1': CDS_PINID='\1\';
NODE_NAME     U6010 BA34
 '@T6G_MB_LIB.T6G(SCH_1):PAGE381_I3@PURE_QUANTA.PT5161LRS(CHIPS)':
 'B_PERP4': CDS_PINID='B_PERP4';
NET_NAME
'P5E_CPU0_P0_TX_C_DN<12>'
 '@T6G_MB_LIB.T6G(SCH_1):P5E_CPU0_P0_TX_C_DN'<12>:
 C_SIGNAL='@t6g_mb_lib.t6g(sch_1):p5e_cpu0_p0_tx_c_dn(12)';
NODE_NAME     C908 1
 '@T6G_MB_LIB.T6G(SCH_1):PAGE351_I62@PURE_QUANTA.Q_CAP_DIFFBUS(CHIPS)':
 '1': CDS_PINID='\1\';
NODE_NAME     U6010 AP34
 '@T6G_MB_LIB.T6G(SCH_1):PAGE381_I3@PURE_QUANTA.PT5161LRS(CHIPS)':
 'B_PERP3': CDS_PINID='B_PERP3';
NET_NAME
'P5E_CPU0_P0_TX_C_DN<13>'
 '@T6G_MB_LIB.T6G(SCH_1):P5E_CPU0_P0_TX_C_DN'<13>:
 C_SIGNAL='@t6g_mb_lib.t6g(sch_1):p5e_cpu0_p0_tx_c_dn(13)';
NODE_NAME     C906 1
 '@T6G_MB_LIB.T6G(SCH_1):PAGE351_I63@PURE_QUANTA.Q_CAP_DIFFBUS(CHIPS)':
 '1': CDS_PINID='\1\';
NODE_NAME     U6010 AJ35
 '@T6G_MB_LIB.T6G(SCH_1):PAGE381_I3@PURE_QUANTA.PT5161LRS(CHIPS)':
 'B_PERN2': CDS_PINID='B_PERN2';
NET_NAME
'P5E_CPU0_P0_TX_C_DN<14>'
 '@T6G_MB_LIB.T6G(SCH_1):P5E_CPU0_P0_TX_C_DN'<14>:
 C_SIGNAL='@t6g_mb_lib.t6g(sch_1):p5e_cpu0_p0_tx_c_dn(14)';
NODE_NAME     C904 1
 '@T6G_MB_LIB.T6G(SCH_1):PAGE351_I66@PURE_QUANTA.Q_CAP_DIFFBUS(CHIPS)':
 '1': CDS_PINID='\1\';
NODE_NAME     U6010 Y34
 '@T6G_MB_LIB.T6G(SCH_1):PAGE381_I3@PURE_QUANTA.PT5161LRS(CHIPS)':
 'B_PERP1': CDS_PINID='B_PERP1';
NET_NAME
'P5E_CPU0_P0_TX_C_DN<15>'
 '@T6G_MB_LIB.T6G(SCH_1):P5E_CPU0_P0_TX_C_DN'<15>:
 C_SIGNAL='@t6g_mb_lib.t6g(sch_1):p5e_cpu0_p0_tx_c_dn(15)';
NODE_NAME     C902 1
 '@T6G_MB_LIB.T6G(SCH_1):PAGE351_I68@PURE_QUANTA.Q_CAP_DIFFBUS(CHIPS)':
 '1': CDS_PINID='\1\';
NODE_NAME     U6010 N34
 '@T6G_MB_LIB.T6G(SCH_1):PAGE381_I3@PURE_QUANTA.PT5161LRS(CHIPS)':
 'B_PERP0': CDS_PINID='B_PERP0';
NET_NAME
'P5E_CPU0_P0_TX_C_DN<1>'
 '@T6G_MB_LIB.T6G(SCH_1):P5E_CPU0_P0_TX_C_DN'<1>:
 C_SIGNAL='@t6g_mb_lib.t6g(sch_1):p5e_cpu0_p0_tx_c_dn(1)';
NODE_NAME     C930 1
 '@T6G_MB_LIB.T6G(SCH_1):PAGE351_I24@PURE_QUANTA.Q_CAP_DIFFBUS(CHIPS)':
 '1': CDS_PINID='\1\';
NODE_NAME     U6010 EN35
 '@T6G_MB_LIB.T6G(SCH_1):PAGE381_I4@PURE_QUANTA.PT5161LRS(CHIPS)':
 'B_PERN14': CDS_PINID='B_PERN14';
NET_NAME
'P5E_CPU0_P0_TX_C_DN<2>'
 '@T6G_MB_LIB.T6G(SCH_1):P5E_CPU0_P0_TX_C_DN'<2>:
 C_SIGNAL='@t6g_mb_lib.t6g(sch_1):p5e_cpu0_p0_tx_c_dn(2)';
NODE_NAME     C928 1
 '@T6G_MB_LIB.T6G(SCH_1):PAGE351_I25@PURE_QUANTA.Q_CAP_DIFFBUS(CHIPS)':
 '1': CDS_PINID='\1\';
NODE_NAME     U6010 ED34
 '@T6G_MB_LIB.T6G(SCH_1):PAGE381_I4@PURE_QUANTA.PT5161LRS(CHIPS)':
 'B_PERP13': CDS_PINID='B_PERP13';
NET_NAME
'P5E_CPU0_P0_TX_C_DN<3>'
 '@T6G_MB_LIB.T6G(SCH_1):P5E_CPU0_P0_TX_C_DN'<3>:
 C_SIGNAL='@t6g_mb_lib.t6g(sch_1):p5e_cpu0_p0_tx_c_dn(3)';
NODE_NAME     C926 1
 '@T6G_MB_LIB.T6G(SCH_1):PAGE351_I28@PURE_QUANTA.Q_CAP_DIFFBUS(CHIPS)':
 '1': CDS_PINID='\1\';
NODE_NAME     U6010 DU34
 '@T6G_MB_LIB.T6G(SCH_1):PAGE381_I4@PURE_QUANTA.PT5161LRS(CHIPS)':
 'B_PERP12': CDS_PINID='B_PERP12';
NET_NAME
'P5E_CPU0_P0_TX_C_DN<4>'
 '@T6G_MB_LIB.T6G(SCH_1):P5E_CPU0_P0_TX_C_DN'<4>:
 C_SIGNAL='@t6g_mb_lib.t6g(sch_1):p5e_cpu0_p0_tx_c_dn(4)';
NODE_NAME     C924 1
 '@T6G_MB_LIB.T6G(SCH_1):PAGE351_I30@PURE_QUANTA.Q_CAP_DIFFBUS(CHIPS)':
 '1': CDS_PINID='\1\';
NODE_NAME     U6010 DK34
 '@T6G_MB_LIB.T6G(SCH_1):PAGE381_I4@PURE_QUANTA.PT5161LRS(CHIPS)':
 'B_PERP11': CDS_PINID='B_PERP11';
NET_NAME
'P5E_CPU0_P0_TX_C_DN<5>'
 '@T6G_MB_LIB.T6G(SCH_1):P5E_CPU0_P0_TX_C_DN'<5>:
 C_SIGNAL='@t6g_mb_lib.t6g(sch_1):p5e_cpu0_p0_tx_c_dn(5)';
NODE_NAME     C922 1
 '@T6G_MB_LIB.T6G(SCH_1):PAGE351_I32@PURE_QUANTA.Q_CAP_DIFFBUS(CHIPS)':
 '1': CDS_PINID='\1\';
NODE_NAME     U6010 DC34
 '@T6G_MB_LIB.T6G(SCH_1):PAGE381_I4@PURE_QUANTA.PT5161LRS(CHIPS)':
 'B_PERP10': CDS_PINID='B_PERP10';
NET_NAME
'P5E_CPU0_P0_TX_C_DN<6>'
 '@T6G_MB_LIB.T6G(SCH_1):P5E_CPU0_P0_TX_C_DN'<6>:
 C_SIGNAL='@t6g_mb_lib.t6g(sch_1):p5e_cpu0_p0_tx_c_dn(6)';
NODE_NAME     C920 1
 '@T6G_MB_LIB.T6G(SCH_1):PAGE351_I34@PURE_QUANTA.Q_CAP_DIFFBUS(CHIPS)':
 '1': CDS_PINID='\1\';
NODE_NAME     U6010 CT34
 '@T6G_MB_LIB.T6G(SCH_1):PAGE381_I4@PURE_QUANTA.PT5161LRS(CHIPS)':
 'B_PERP9': CDS_PINID='B_PERP9';
NET_NAME
'P5E_CPU0_P0_TX_C_DN<7>'
 '@T6G_MB_LIB.T6G(SCH_1):P5E_CPU0_P0_TX_C_DN'<7>:
 C_SIGNAL='@t6g_mb_lib.t6g(sch_1):p5e_cpu0_p0_tx_c_dn(7)';
NODE_NAME     C918 1
 '@T6G_MB_LIB.T6G(SCH_1):PAGE351_I35@PURE_QUANTA.Q_CAP_DIFFBUS(CHIPS)':
 '1': CDS_PINID='\1\';
NODE_NAME     U6010 CJ34
 '@T6G_MB_LIB.T6G(SCH_1):PAGE381_I4@PURE_QUANTA.PT5161LRS(CHIPS)':
 'B_PERP8': CDS_PINID='B_PERP8';
NET_NAME
'P5E_CPU0_P0_TX_C_DN<8>'
 '@T6G_MB_LIB.T6G(SCH_1):P5E_CPU0_P0_TX_C_DN'<8>:
 C_SIGNAL='@t6g_mb_lib.t6g(sch_1):p5e_cpu0_p0_tx_c_dn(8)';
NODE_NAME     C916 1
 '@T6G_MB_LIB.T6G(SCH_1):PAGE351_I53@PURE_QUANTA.Q_CAP_DIFFBUS(CHIPS)':
 '1': CDS_PINID='\1\';
NODE_NAME     U6010 CB34
 '@T6G_MB_LIB.T6G(SCH_1):PAGE381_I3@PURE_QUANTA.PT5161LRS(CHIPS)':
 'B_PERP7': CDS_PINID='B_PERP7';
NET_NAME
'P5E_CPU0_P0_TX_C_DN<9>'
 '@T6G_MB_LIB.T6G(SCH_1):P5E_CPU0_P0_TX_C_DN'<9>:
 C_SIGNAL='@t6g_mb_lib.t6g(sch_1):p5e_cpu0_p0_tx_c_dn(9)';
NODE_NAME     C914 1
 '@T6G_MB_LIB.T6G(SCH_1):PAGE351_I56@PURE_QUANTA.Q_CAP_DIFFBUS(CHIPS)':
 '1': CDS_PINID='\1\';
NODE_NAME     U6010 BR34
 '@T6G_MB_LIB.T6G(SCH_1):PAGE381_I3@PURE_QUANTA.PT5161LRS(CHIPS)':
 'B_PERP6': CDS_PINID='B_PERP6';
NET_NAME
'P5E_CPU0_P0_TX_C_DP<0>'
 '@T6G_MB_LIB.T6G(SCH_1):P5E_CPU0_P0_TX_C_DP'<0>:
 C_SIGNAL='@t6g_mb_lib.t6g(sch_1):p5e_cpu0_p0_tx_c_dp(0)';
NODE_NAME     C933 1
 '@T6G_MB_LIB.T6G(SCH_1):PAGE351_I22@PURE_QUANTA.Q_CAP_DIFFBUS(CHIPS)':
 '1': CDS_PINID='\1\';
NODE_NAME     U6010 EY35
 '@T6G_MB_LIB.T6G(SCH_1):PAGE381_I4@PURE_QUANTA.PT5161LRS(CHIPS)':
 'B_PERN15': CDS_PINID='B_PERN15';
NET_NAME
'P5E_CPU0_P0_TX_C_DP<10>'
 '@T6G_MB_LIB.T6G(SCH_1):P5E_CPU0_P0_TX_C_DP'<10>:
 C_SIGNAL='@t6g_mb_lib.t6g(sch_1):p5e_cpu0_p0_tx_c_dp(10)';
NODE_NAME     C913 1
 '@T6G_MB_LIB.T6G(SCH_1):PAGE351_I57@PURE_QUANTA.Q_CAP_DIFFBUS(CHIPS)':
 '1': CDS_PINID='\1\';
NODE_NAME     U6010 BK35
 '@T6G_MB_LIB.T6G(SCH_1):PAGE381_I3@PURE_QUANTA.PT5161LRS(CHIPS)':
 'B_PERN5': CDS_PINID='B_PERN5';
NET_NAME
'P5E_CPU0_P0_TX_C_DP<11>'
 '@T6G_MB_LIB.T6G(SCH_1):P5E_CPU0_P0_TX_C_DP'<11>:
 C_SIGNAL='@t6g_mb_lib.t6g(sch_1):p5e_cpu0_p0_tx_c_dp(11)';
NODE_NAME     C911 1
 '@T6G_MB_LIB.T6G(SCH_1):PAGE351_I59@PURE_QUANTA.Q_CAP_DIFFBUS(CHIPS)':
 '1': CDS_PINID='\1\';
NODE_NAME     U6010 BC35
 '@T6G_MB_LIB.T6G(SCH_1):PAGE381_I3@PURE_QUANTA.PT5161LRS(CHIPS)':
 'B_PERN4': CDS_PINID='B_PERN4';
NET_NAME
'P5E_CPU0_P0_TX_C_DP<12>'
 '@T6G_MB_LIB.T6G(SCH_1):P5E_CPU0_P0_TX_C_DP'<12>:
 C_SIGNAL='@t6g_mb_lib.t6g(sch_1):p5e_cpu0_p0_tx_c_dp(12)';
NODE_NAME     C909 1
 '@T6G_MB_LIB.T6G(SCH_1):PAGE351_I61@PURE_QUANTA.Q_CAP_DIFFBUS(CHIPS)':
 '1': CDS_PINID='\1\';
NODE_NAME     U6010 AT35
 '@T6G_MB_LIB.T6G(SCH_1):PAGE381_I3@PURE_QUANTA.PT5161LRS(CHIPS)':
 'B_PERN3': CDS_PINID='B_PERN3';
NET_NAME
'P5E_CPU0_P0_TX_C_DP<13>'
 '@T6G_MB_LIB.T6G(SCH_1):P5E_CPU0_P0_TX_C_DP'<13>:
 C_SIGNAL='@t6g_mb_lib.t6g(sch_1):p5e_cpu0_p0_tx_c_dp(13)';
NODE_NAME     C907 1
 '@T6G_MB_LIB.T6G(SCH_1):PAGE351_I64@PURE_QUANTA.Q_CAP_DIFFBUS(CHIPS)':
 '1': CDS_PINID='\1\';
NODE_NAME     U6010 AG34
 '@T6G_MB_LIB.T6G(SCH_1):PAGE381_I3@PURE_QUANTA.PT5161LRS(CHIPS)':
 'B_PERP2': CDS_PINID='B_PERP2';
NET_NAME
'P5E_CPU0_P0_TX_C_DP<14>'
 '@T6G_MB_LIB.T6G(SCH_1):P5E_CPU0_P0_TX_C_DP'<14>:
 C_SIGNAL='@t6g_mb_lib.t6g(sch_1):p5e_cpu0_p0_tx_c_dp(14)';
NODE_NAME     C905 1
 '@T6G_MB_LIB.T6G(SCH_1):PAGE351_I65@PURE_QUANTA.Q_CAP_DIFFBUS(CHIPS)':
 '1': CDS_PINID='\1\';
NODE_NAME     U6010 AB35
 '@T6G_MB_LIB.T6G(SCH_1):PAGE381_I3@PURE_QUANTA.PT5161LRS(CHIPS)':
 'B_PERN1': CDS_PINID='B_PERN1';
NET_NAME
'P5E_CPU0_P0_TX_C_DP<15>'
 '@T6G_MB_LIB.T6G(SCH_1):P5E_CPU0_P0_TX_C_DP'<15>:
 C_SIGNAL='@t6g_mb_lib.t6g(sch_1):p5e_cpu0_p0_tx_c_dp(15)';
NODE_NAME     C903 1
 '@T6G_MB_LIB.T6G(SCH_1):PAGE351_I67@PURE_QUANTA.Q_CAP_DIFFBUS(CHIPS)':
 '1': CDS_PINID='\1\';
NODE_NAME     U6010 R35
 '@T6G_MB_LIB.T6G(SCH_1):PAGE381_I3@PURE_QUANTA.PT5161LRS(CHIPS)':
 'B_PERN0': CDS_PINID='B_PERN0';
NET_NAME
'P5E_CPU0_P0_TX_C_DP<1>'
 '@T6G_MB_LIB.T6G(SCH_1):P5E_CPU0_P0_TX_C_DP'<1>:
 C_SIGNAL='@t6g_mb_lib.t6g(sch_1):p5e_cpu0_p0_tx_c_dp(1)';
NODE_NAME     C931 1
 '@T6G_MB_LIB.T6G(SCH_1):PAGE351_I23@PURE_QUANTA.Q_CAP_DIFFBUS(CHIPS)':
 '1': CDS_PINID='\1\';
NODE_NAME     U6010 EL34
 '@T6G_MB_LIB.T6G(SCH_1):PAGE381_I4@PURE_QUANTA.PT5161LRS(CHIPS)':
 'B_PERP14': CDS_PINID='B_PERP14';
NET_NAME
'P5E_CPU0_P0_TX_C_DP<2>'
 '@T6G_MB_LIB.T6G(SCH_1):P5E_CPU0_P0_TX_C_DP'<2>:
 C_SIGNAL='@t6g_mb_lib.t6g(sch_1):p5e_cpu0_p0_tx_c_dp(2)';
NODE_NAME     C929 1
 '@T6G_MB_LIB.T6G(SCH_1):PAGE351_I26@PURE_QUANTA.Q_CAP_DIFFBUS(CHIPS)':
 '1': CDS_PINID='\1\';
NODE_NAME     U6010 EF35
 '@T6G_MB_LIB.T6G(SCH_1):PAGE381_I4@PURE_QUANTA.PT5161LRS(CHIPS)':
 'B_PERN13': CDS_PINID='B_PERN13';
NET_NAME
'P5E_CPU0_P0_TX_C_DP<3>'
 '@T6G_MB_LIB.T6G(SCH_1):P5E_CPU0_P0_TX_C_DP'<3>:
 C_SIGNAL='@t6g_mb_lib.t6g(sch_1):p5e_cpu0_p0_tx_c_dp(3)';
NODE_NAME     C927 1
 '@T6G_MB_LIB.T6G(SCH_1):PAGE351_I27@PURE_QUANTA.Q_CAP_DIFFBUS(CHIPS)':
 '1': CDS_PINID='\1\';
NODE_NAME     U6010 DW35
 '@T6G_MB_LIB.T6G(SCH_1):PAGE381_I4@PURE_QUANTA.PT5161LRS(CHIPS)':
 'B_PERN12': CDS_PINID='B_PERN12';
NET_NAME
'P5E_CPU0_P0_TX_C_DP<4>'
 '@T6G_MB_LIB.T6G(SCH_1):P5E_CPU0_P0_TX_C_DP'<4>:
 C_SIGNAL='@t6g_mb_lib.t6g(sch_1):p5e_cpu0_p0_tx_c_dp(4)';
NODE_NAME     C925 1
 '@T6G_MB_LIB.T6G(SCH_1):PAGE351_I29@PURE_QUANTA.Q_CAP_DIFFBUS(CHIPS)':
 '1': CDS_PINID='\1\';
NODE_NAME     U6010 DM35
 '@T6G_MB_LIB.T6G(SCH_1):PAGE381_I4@PURE_QUANTA.PT5161LRS(CHIPS)':
 'B_PERN11': CDS_PINID='B_PERN11';
NET_NAME
'P5E_CPU0_P0_TX_C_DP<5>'
 '@T6G_MB_LIB.T6G(SCH_1):P5E_CPU0_P0_TX_C_DP'<5>:
 C_SIGNAL='@t6g_mb_lib.t6g(sch_1):p5e_cpu0_p0_tx_c_dp(5)';
NODE_NAME     C923 1
 '@T6G_MB_LIB.T6G(SCH_1):PAGE351_I31@PURE_QUANTA.Q_CAP_DIFFBUS(CHIPS)':
 '1': CDS_PINID='\1\';
NODE_NAME     U6010 DE35
 '@T6G_MB_LIB.T6G(SCH_1):PAGE381_I4@PURE_QUANTA.PT5161LRS(CHIPS)':
 'B_PERN10': CDS_PINID='B_PERN10';
NET_NAME
'P5E_CPU0_P0_TX_C_DP<6>'
 '@T6G_MB_LIB.T6G(SCH_1):P5E_CPU0_P0_TX_C_DP'<6>:
 C_SIGNAL='@t6g_mb_lib.t6g(sch_1):p5e_cpu0_p0_tx_c_dp(6)';
NODE_NAME     C921 1
 '@T6G_MB_LIB.T6G(SCH_1):PAGE351_I33@PURE_QUANTA.Q_CAP_DIFFBUS(CHIPS)':
 '1': CDS_PINID='\1\';
NODE_NAME     U6010 CV35
 '@T6G_MB_LIB.T6G(SCH_1):PAGE381_I4@PURE_QUANTA.PT5161LRS(CHIPS)':
 'B_PERN9': CDS_PINID='B_PERN9';
NET_NAME
'P5E_CPU0_P0_TX_C_DP<7>'
 '@T6G_MB_LIB.T6G(SCH_1):P5E_CPU0_P0_TX_C_DP'<7>:
 C_SIGNAL='@t6g_mb_lib.t6g(sch_1):p5e_cpu0_p0_tx_c_dp(7)';
NODE_NAME     C919 1
 '@T6G_MB_LIB.T6G(SCH_1):PAGE351_I36@PURE_QUANTA.Q_CAP_DIFFBUS(CHIPS)':
 '1': CDS_PINID='\1\';
NODE_NAME     U6010 CL35
 '@T6G_MB_LIB.T6G(SCH_1):PAGE381_I4@PURE_QUANTA.PT5161LRS(CHIPS)':
 'B_PERN8': CDS_PINID='B_PERN8';
NET_NAME
'P5E_CPU0_P0_TX_C_DP<8>'
 '@T6G_MB_LIB.T6G(SCH_1):P5E_CPU0_P0_TX_C_DP'<8>:
 C_SIGNAL='@t6g_mb_lib.t6g(sch_1):p5e_cpu0_p0_tx_c_dp(8)';
NODE_NAME     C917 1
 '@T6G_MB_LIB.T6G(SCH_1):PAGE351_I54@PURE_QUANTA.Q_CAP_DIFFBUS(CHIPS)':
 '1': CDS_PINID='\1\';
NODE_NAME     U6010 CD35
 '@T6G_MB_LIB.T6G(SCH_1):PAGE381_I3@PURE_QUANTA.PT5161LRS(CHIPS)':
 'B_PERN7': CDS_PINID='B_PERN7';
NET_NAME
'P5E_CPU0_P0_TX_C_DP<9>'
 '@T6G_MB_LIB.T6G(SCH_1):P5E_CPU0_P0_TX_C_DP'<9>:
 C_SIGNAL='@t6g_mb_lib.t6g(sch_1):p5e_cpu0_p0_tx_c_dp(9)';
NODE_NAME     C915 1
 '@T6G_MB_LIB.T6G(SCH_1):PAGE351_I55@PURE_QUANTA.Q_CAP_DIFFBUS(CHIPS)':
 '1': CDS_PINID='\1\';
NODE_NAME     U6010 BU35
 '@T6G_MB_LIB.T6G(SCH_1):PAGE381_I3@PURE_QUANTA.PT5161LRS(CHIPS)':
 'B_PERN6': CDS_PINID='B_PERN6';
NET_NAME
'P5E_CPU0_P0_TX_DN<0>'
 '@T6G_MB_LIB.T6G(SCH_1):P5E_CPU0_P0_TX_DN'<0>:
 C_SIGNAL='@t6g_mb_lib.t6g(sch_1):p5e_cpu0_p0_tx_dn(0)';
NODE_NAME     U25 CN52
 '@T6G_MB_LIB.T6G(SCH_1):PAGE24_I148@PURE_QUANTA.GENOA_SP5(CHIPS)':
 'P0_TXN0||SATA00_TXN': CDS_PINID='\p0_txn0||sata00_txn\';
NODE_NAME     C932 2
 '@T6G_MB_LIB.T6G(SCH_1):PAGE351_I21@PURE_QUANTA.Q_CAP_DIFFBUS(CHIPS)':
 '2': CDS_PINID='\2\';
NET_NAME
'P5E_CPU0_P0_TX_DN<10>'
 '@T6G_MB_LIB.T6G(SCH_1):P5E_CPU0_P0_TX_DN'<10>:
 C_SIGNAL='@t6g_mb_lib.t6g(sch_1):p5e_cpu0_p0_tx_dn(10)';
NODE_NAME     U25 CR43
 '@T6G_MB_LIB.T6G(SCH_1):PAGE24_I148@PURE_QUANTA.GENOA_SP5(CHIPS)':
 'P0_TXN10||SATA12_TXN': CDS_PINID='\p0_txn10||sata12_txn\';
NODE_NAME     C912 2
 '@T6G_MB_LIB.T6G(SCH_1):PAGE351_I58@PURE_QUANTA.Q_CAP_DIFFBUS(CHIPS)':
 '2': CDS_PINID='\2\';
NET_NAME
'P5E_CPU0_P0_TX_DN<11>'
 '@T6G_MB_LIB.T6G(SCH_1):P5E_CPU0_P0_TX_DN'<11>:
 C_SIGNAL='@t6g_mb_lib.t6g(sch_1):p5e_cpu0_p0_tx_dn(11)';
NODE_NAME     U25 CU43
 '@T6G_MB_LIB.T6G(SCH_1):PAGE24_I148@PURE_QUANTA.GENOA_SP5(CHIPS)':
 'P0_TXN11||SATA13_TXN': CDS_PINID='\p0_txn11||sata13_txn\';
NODE_NAME     C910 2
 '@T6G_MB_LIB.T6G(SCH_1):PAGE351_I60@PURE_QUANTA.Q_CAP_DIFFBUS(CHIPS)':
 '2': CDS_PINID='\2\';
NET_NAME
'P5E_CPU0_P0_TX_DN<12>'
 '@T6G_MB_LIB.T6G(SCH_1):P5E_CPU0_P0_TX_DN'<12>:
 C_SIGNAL='@t6g_mb_lib.t6g(sch_1):p5e_cpu0_p0_tx_dn(12)';
NODE_NAME     U25 CN43
 '@T6G_MB_LIB.T6G(SCH_1):PAGE24_I148@PURE_QUANTA.GENOA_SP5(CHIPS)':
 'P0_TXN12||SATA14_TXN': CDS_PINID='\p0_txn12||sata14_txn\';
NODE_NAME     C908 2
 '@T6G_MB_LIB.T6G(SCH_1):PAGE351_I62@PURE_QUANTA.Q_CAP_DIFFBUS(CHIPS)':
 '2': CDS_PINID='\2\';
NET_NAME
'P5E_CPU0_P0_TX_DN<13>'
 '@T6G_MB_LIB.T6G(SCH_1):P5E_CPU0_P0_TX_DN'<13>:
 C_SIGNAL='@t6g_mb_lib.t6g(sch_1):p5e_cpu0_p0_tx_dn(13)';
NODE_NAME     U25 CT40
 '@T6G_MB_LIB.T6G(SCH_1):PAGE24_I148@PURE_QUANTA.GENOA_SP5(CHIPS)':
 'P0_TXN13||SATA15_TXN': CDS_PINID='\p0_txn13||sata15_txn\';
NODE_NAME     C906 2
 '@T6G_MB_LIB.T6G(SCH_1):PAGE351_I63@PURE_QUANTA.Q_CAP_DIFFBUS(CHIPS)':
 '2': CDS_PINID='\2\';
NET_NAME
'P5E_CPU0_P0_TX_DN<14>'
 '@T6G_MB_LIB.T6G(SCH_1):P5E_CPU0_P0_TX_DN'<14>:
 C_SIGNAL='@t6g_mb_lib.t6g(sch_1):p5e_cpu0_p0_tx_dn(14)';
NODE_NAME     U25 CP40
 '@T6G_MB_LIB.T6G(SCH_1):PAGE24_I148@PURE_QUANTA.GENOA_SP5(CHIPS)':
 'P0_TXN14||SATA16_TXN': CDS_PINID='\p0_txn14||sata16_txn\';
NODE_NAME     C904 2
 '@T6G_MB_LIB.T6G(SCH_1):PAGE351_I66@PURE_QUANTA.Q_CAP_DIFFBUS(CHIPS)':
 '2': CDS_PINID='\2\';
NET_NAME
'P5E_CPU0_P0_TX_DN<15>'
 '@T6G_MB_LIB.T6G(SCH_1):P5E_CPU0_P0_TX_DN'<15>:
 C_SIGNAL='@t6g_mb_lib.t6g(sch_1):p5e_cpu0_p0_tx_dn(15)';
NODE_NAME     U25 CM40
 '@T6G_MB_LIB.T6G(SCH_1):PAGE24_I148@PURE_QUANTA.GENOA_SP5(CHIPS)':
 'P0_TXN15||SATA17_TXN': CDS_PINID='\p0_txn15||sata17_txn\';
NODE_NAME     C902 2
 '@T6G_MB_LIB.T6G(SCH_1):PAGE351_I68@PURE_QUANTA.Q_CAP_DIFFBUS(CHIPS)':
 '2': CDS_PINID='\2\';
NET_NAME
'P5E_CPU0_P0_TX_DN<1>'
 '@T6G_MB_LIB.T6G(SCH_1):P5E_CPU0_P0_TX_DN'<1>:
 C_SIGNAL='@t6g_mb_lib.t6g(sch_1):p5e_cpu0_p0_tx_dn(1)';
NODE_NAME     U25 CR52
 '@T6G_MB_LIB.T6G(SCH_1):PAGE24_I148@PURE_QUANTA.GENOA_SP5(CHIPS)':
 'P0_TXN1||SATA01_TXN': CDS_PINID='\p0_txn1||sata01_txn\';
NODE_NAME     C930 2
 '@T6G_MB_LIB.T6G(SCH_1):PAGE351_I24@PURE_QUANTA.Q_CAP_DIFFBUS(CHIPS)':
 '2': CDS_PINID='\2\';
NET_NAME
'P5E_CPU0_P0_TX_DN<2>'
 '@T6G_MB_LIB.T6G(SCH_1):P5E_CPU0_P0_TX_DN'<2>:
 C_SIGNAL='@t6g_mb_lib.t6g(sch_1):p5e_cpu0_p0_tx_dn(2)';
NODE_NAME     U25 CL52
 '@T6G_MB_LIB.T6G(SCH_1):PAGE24_I148@PURE_QUANTA.GENOA_SP5(CHIPS)':
 'P0_TXN2||SATA02_TXN': CDS_PINID='\p0_txn2||sata02_txn\';
NODE_NAME     C928 2
 '@T6G_MB_LIB.T6G(SCH_1):PAGE351_I25@PURE_QUANTA.Q_CAP_DIFFBUS(CHIPS)':
 '2': CDS_PINID='\2\';
NET_NAME
'P5E_CPU0_P0_TX_DN<3>'
 '@T6G_MB_LIB.T6G(SCH_1):P5E_CPU0_P0_TX_DN'<3>:
 C_SIGNAL='@t6g_mb_lib.t6g(sch_1):p5e_cpu0_p0_tx_dn(3)';
NODE_NAME     U25 CN49
 '@T6G_MB_LIB.T6G(SCH_1):PAGE24_I148@PURE_QUANTA.GENOA_SP5(CHIPS)':
 'P0_TXN3||SATA03_TXN': CDS_PINID='\p0_txn3||sata03_txn\';
NODE_NAME     C926 2
 '@T6G_MB_LIB.T6G(SCH_1):PAGE351_I28@PURE_QUANTA.Q_CAP_DIFFBUS(CHIPS)':
 '2': CDS_PINID='\2\';
NET_NAME
'P5E_CPU0_P0_TX_DN<4>'
 '@T6G_MB_LIB.T6G(SCH_1):P5E_CPU0_P0_TX_DN'<4>:
 C_SIGNAL='@t6g_mb_lib.t6g(sch_1):p5e_cpu0_p0_tx_dn(4)';
NODE_NAME     U25 CR49
 '@T6G_MB_LIB.T6G(SCH_1):PAGE24_I148@PURE_QUANTA.GENOA_SP5(CHIPS)':
 'P0_TXN4||SATA04_TXN': CDS_PINID='\p0_txn4||sata04_txn\';
NODE_NAME     C924 2
 '@T6G_MB_LIB.T6G(SCH_1):PAGE351_I30@PURE_QUANTA.Q_CAP_DIFFBUS(CHIPS)':
 '2': CDS_PINID='\2\';
NET_NAME
'P5E_CPU0_P0_TX_DN<5>'
 '@T6G_MB_LIB.T6G(SCH_1):P5E_CPU0_P0_TX_DN'<5>:
 C_SIGNAL='@t6g_mb_lib.t6g(sch_1):p5e_cpu0_p0_tx_dn(5)';
NODE_NAME     U25 CU49
 '@T6G_MB_LIB.T6G(SCH_1):PAGE24_I148@PURE_QUANTA.GENOA_SP5(CHIPS)':
 'P0_TXN5||SATA05_TXN': CDS_PINID='\p0_txn5||sata05_txn\';
NODE_NAME     C922 2
 '@T6G_MB_LIB.T6G(SCH_1):PAGE351_I32@PURE_QUANTA.Q_CAP_DIFFBUS(CHIPS)':
 '2': CDS_PINID='\2\';
NET_NAME
'P5E_CPU0_P0_TX_DN<6>'
 '@T6G_MB_LIB.T6G(SCH_1):P5E_CPU0_P0_TX_DN'<6>:
 C_SIGNAL='@t6g_mb_lib.t6g(sch_1):p5e_cpu0_p0_tx_dn(6)';
NODE_NAME     U25 CL49
 '@T6G_MB_LIB.T6G(SCH_1):PAGE24_I148@PURE_QUANTA.GENOA_SP5(CHIPS)':
 'P0_TXN6||SATA06_TXN': CDS_PINID='\p0_txn6||sata06_txn\';
NODE_NAME     C920 2
 '@T6G_MB_LIB.T6G(SCH_1):PAGE351_I34@PURE_QUANTA.Q_CAP_DIFFBUS(CHIPS)':
 '2': CDS_PINID='\2\';
NET_NAME
'P5E_CPU0_P0_TX_DN<7>'
 '@T6G_MB_LIB.T6G(SCH_1):P5E_CPU0_P0_TX_DN'<7>:
 C_SIGNAL='@t6g_mb_lib.t6g(sch_1):p5e_cpu0_p0_tx_dn(7)';
NODE_NAME     U25 CR46
 '@T6G_MB_LIB.T6G(SCH_1):PAGE24_I148@PURE_QUANTA.GENOA_SP5(CHIPS)':
 'P0_TXN7||SATA07_TXN': CDS_PINID='\p0_txn7||sata07_txn\';
NODE_NAME     C918 2
 '@T6G_MB_LIB.T6G(SCH_1):PAGE351_I35@PURE_QUANTA.Q_CAP_DIFFBUS(CHIPS)':
 '2': CDS_PINID='\2\';
NET_NAME
'P5E_CPU0_P0_TX_DN<8>'
 '@T6G_MB_LIB.T6G(SCH_1):P5E_CPU0_P0_TX_DN'<8>:
 C_SIGNAL='@t6g_mb_lib.t6g(sch_1):p5e_cpu0_p0_tx_dn(8)';
NODE_NAME     U25 CU46
 '@T6G_MB_LIB.T6G(SCH_1):PAGE24_I148@PURE_QUANTA.GENOA_SP5(CHIPS)':
 'P0_TXN8||SATA10_TXN': CDS_PINID='\p0_txn8||sata10_txn\';
NODE_NAME     C916 2
 '@T6G_MB_LIB.T6G(SCH_1):PAGE351_I53@PURE_QUANTA.Q_CAP_DIFFBUS(CHIPS)':
 '2': CDS_PINID='\2\';
NET_NAME
'P5E_CPU0_P0_TX_DN<9>'
 '@T6G_MB_LIB.T6G(SCH_1):P5E_CPU0_P0_TX_DN'<9>:
 C_SIGNAL='@t6g_mb_lib.t6g(sch_1):p5e_cpu0_p0_tx_dn(9)';
NODE_NAME     U25 CN46
 '@T6G_MB_LIB.T6G(SCH_1):PAGE24_I148@PURE_QUANTA.GENOA_SP5(CHIPS)':
 'P0_TXN9||SATA11_TXN': CDS_PINID='\p0_txn9||sata11_txn\';
NODE_NAME     C914 2
 '@T6G_MB_LIB.T6G(SCH_1):PAGE351_I56@PURE_QUANTA.Q_CAP_DIFFBUS(CHIPS)':
 '2': CDS_PINID='\2\';
NET_NAME
'P5E_CPU0_P0_TX_DP<0>'
 '@T6G_MB_LIB.T6G(SCH_1):P5E_CPU0_P0_TX_DP'<0>:
 C_SIGNAL='@t6g_mb_lib.t6g(sch_1):p5e_cpu0_p0_tx_dp(0)';
NODE_NAME     U25 CN53
 '@T6G_MB_LIB.T6G(SCH_1):PAGE24_I148@PURE_QUANTA.GENOA_SP5(CHIPS)':
 'P0_TXP0||SATA00_TXP': CDS_PINID='\p0_txp0||sata00_txp\';
NODE_NAME     C933 2
 '@T6G_MB_LIB.T6G(SCH_1):PAGE351_I22@PURE_QUANTA.Q_CAP_DIFFBUS(CHIPS)':
 '2': CDS_PINID='\2\';
NET_NAME
'P5E_CPU0_P0_TX_DP<10>'
 '@T6G_MB_LIB.T6G(SCH_1):P5E_CPU0_P0_TX_DP'<10>:
 C_SIGNAL='@t6g_mb_lib.t6g(sch_1):p5e_cpu0_p0_tx_dp(10)';
NODE_NAME     U25 CR44
 '@T6G_MB_LIB.T6G(SCH_1):PAGE24_I148@PURE_QUANTA.GENOA_SP5(CHIPS)':
 'P0_TXP10||SATA12_TXP': CDS_PINID='\p0_txp10||sata12_txp\';
NODE_NAME     C913 2
 '@T6G_MB_LIB.T6G(SCH_1):PAGE351_I57@PURE_QUANTA.Q_CAP_DIFFBUS(CHIPS)':
 '2': CDS_PINID='\2\';
NET_NAME
'P5E_CPU0_P0_TX_DP<11>'
 '@T6G_MB_LIB.T6G(SCH_1):P5E_CPU0_P0_TX_DP'<11>:
 C_SIGNAL='@t6g_mb_lib.t6g(sch_1):p5e_cpu0_p0_tx_dp(11)';
NODE_NAME     U25 CU44
 '@T6G_MB_LIB.T6G(SCH_1):PAGE24_I148@PURE_QUANTA.GENOA_SP5(CHIPS)':
 'P0_TXP11||SATA13_TXP': CDS_PINID='\p0_txp11||sata13_txp\';
NODE_NAME     C911 2
 '@T6G_MB_LIB.T6G(SCH_1):PAGE351_I59@PURE_QUANTA.Q_CAP_DIFFBUS(CHIPS)':
 '2': CDS_PINID='\2\';
NET_NAME
'P5E_CPU0_P0_TX_DP<12>'
 '@T6G_MB_LIB.T6G(SCH_1):P5E_CPU0_P0_TX_DP'<12>:
 C_SIGNAL='@t6g_mb_lib.t6g(sch_1):p5e_cpu0_p0_tx_dp(12)';
NODE_NAME     U25 CN44
 '@T6G_MB_LIB.T6G(SCH_1):PAGE24_I148@PURE_QUANTA.GENOA_SP5(CHIPS)':
 'P0_TXP12||SATA14_TXP': CDS_PINID='\p0_txp12||sata14_txp\';
NODE_NAME     C909 2
 '@T6G_MB_LIB.T6G(SCH_1):PAGE351_I61@PURE_QUANTA.Q_CAP_DIFFBUS(CHIPS)':
 '2': CDS_PINID='\2\';
NET_NAME
'P5E_CPU0_P0_TX_DP<13>'
 '@T6G_MB_LIB.T6G(SCH_1):P5E_CPU0_P0_TX_DP'<13>:
 C_SIGNAL='@t6g_mb_lib.t6g(sch_1):p5e_cpu0_p0_tx_dp(13)';
NODE_NAME     U25 CT41
 '@T6G_MB_LIB.T6G(SCH_1):PAGE24_I148@PURE_QUANTA.GENOA_SP5(CHIPS)':
 'P0_TXP13||SATA15_TXP': CDS_PINID='\p0_txp13||sata15_txp\';
NODE_NAME     C907 2
 '@T6G_MB_LIB.T6G(SCH_1):PAGE351_I64@PURE_QUANTA.Q_CAP_DIFFBUS(CHIPS)':
 '2': CDS_PINID='\2\';
NET_NAME
'P5E_CPU0_P0_TX_DP<14>'
 '@T6G_MB_LIB.T6G(SCH_1):P5E_CPU0_P0_TX_DP'<14>:
 C_SIGNAL='@t6g_mb_lib.t6g(sch_1):p5e_cpu0_p0_tx_dp(14)';
NODE_NAME     U25 CP41
 '@T6G_MB_LIB.T6G(SCH_1):PAGE24_I148@PURE_QUANTA.GENOA_SP5(CHIPS)':
 'P0_TXP14||SATA16_TXP': CDS_PINID='\p0_txp14||sata16_txp\';
NODE_NAME     C905 2
 '@T6G_MB_LIB.T6G(SCH_1):PAGE351_I65@PURE_QUANTA.Q_CAP_DIFFBUS(CHIPS)':
 '2': CDS_PINID='\2\';
NET_NAME
'P5E_CPU0_P0_TX_DP<15>'
 '@T6G_MB_LIB.T6G(SCH_1):P5E_CPU0_P0_TX_DP'<15>:
 C_SIGNAL='@t6g_mb_lib.t6g(sch_1):p5e_cpu0_p0_tx_dp(15)';
NODE_NAME     U25 CM41
 '@T6G_MB_LIB.T6G(SCH_1):PAGE24_I148@PURE_QUANTA.GENOA_SP5(CHIPS)':
 'P0_TXP15||SATA17_TXP': CDS_PINID='\p0_txp15||sata17_txp\';
NODE_NAME     C903 2
 '@T6G_MB_LIB.T6G(SCH_1):PAGE351_I67@PURE_QUANTA.Q_CAP_DIFFBUS(CHIPS)':
 '2': CDS_PINID='\2\';
NET_NAME
'P5E_CPU0_P0_TX_DP<1>'
 '@T6G_MB_LIB.T6G(SCH_1):P5E_CPU0_P0_TX_DP'<1>:
 C_SIGNAL='@t6g_mb_lib.t6g(sch_1):p5e_cpu0_p0_tx_dp(1)';
NODE_NAME     U25 CR53
 '@T6G_MB_LIB.T6G(SCH_1):PAGE24_I148@PURE_QUANTA.GENOA_SP5(CHIPS)':
 'P0_TXP1||SATA01_TXP': CDS_PINID='\p0_txp1||sata01_txp\';
NODE_NAME     C931 2
 '@T6G_MB_LIB.T6G(SCH_1):PAGE351_I23@PURE_QUANTA.Q_CAP_DIFFBUS(CHIPS)':
 '2': CDS_PINID='\2\';
NET_NAME
'P5E_CPU0_P0_TX_DP<2>'
 '@T6G_MB_LIB.T6G(SCH_1):P5E_CPU0_P0_TX_DP'<2>:
 C_SIGNAL='@t6g_mb_lib.t6g(sch_1):p5e_cpu0_p0_tx_dp(2)';
NODE_NAME     U25 CL53
 '@T6G_MB_LIB.T6G(SCH_1):PAGE24_I148@PURE_QUANTA.GENOA_SP5(CHIPS)':
 'P0_TXP2||SATA02_TXP': CDS_PINID='\p0_txp2||sata02_txp\';
NODE_NAME     C929 2
 '@T6G_MB_LIB.T6G(SCH_1):PAGE351_I26@PURE_QUANTA.Q_CAP_DIFFBUS(CHIPS)':
 '2': CDS_PINID='\2\';
NET_NAME
'P5E_CPU0_P0_TX_DP<3>'
 '@T6G_MB_LIB.T6G(SCH_1):P5E_CPU0_P0_TX_DP'<3>:
 C_SIGNAL='@t6g_mb_lib.t6g(sch_1):p5e_cpu0_p0_tx_dp(3)';
NODE_NAME     U25 CN50
 '@T6G_MB_LIB.T6G(SCH_1):PAGE24_I148@PURE_QUANTA.GENOA_SP5(CHIPS)':
 'P0_TXP3||SATA03_TXP': CDS_PINID='\p0_txp3||sata03_txp\';
NODE_NAME     C927 2
 '@T6G_MB_LIB.T6G(SCH_1):PAGE351_I27@PURE_QUANTA.Q_CAP_DIFFBUS(CHIPS)':
 '2': CDS_PINID='\2\';
NET_NAME
'P5E_CPU0_P0_TX_DP<4>'
 '@T6G_MB_LIB.T6G(SCH_1):P5E_CPU0_P0_TX_DP'<4>:
 C_SIGNAL='@t6g_mb_lib.t6g(sch_1):p5e_cpu0_p0_tx_dp(4)';
NODE_NAME     U25 CR50
 '@T6G_MB_LIB.T6G(SCH_1):PAGE24_I148@PURE_QUANTA.GENOA_SP5(CHIPS)':
 'P0_TXP4||SATA04_TXP': CDS_PINID='\p0_txp4||sata04_txp\';
NODE_NAME     C925 2
 '@T6G_MB_LIB.T6G(SCH_1):PAGE351_I29@PURE_QUANTA.Q_CAP_DIFFBUS(CHIPS)':
 '2': CDS_PINID='\2\';
NET_NAME
'P5E_CPU0_P0_TX_DP<5>'
 '@T6G_MB_LIB.T6G(SCH_1):P5E_CPU0_P0_TX_DP'<5>:
 C_SIGNAL='@t6g_mb_lib.t6g(sch_1):p5e_cpu0_p0_tx_dp(5)';
NODE_NAME     U25 CU50
 '@T6G_MB_LIB.T6G(SCH_1):PAGE24_I148@PURE_QUANTA.GENOA_SP5(CHIPS)':
 'P0_TXP5||SATA05_TXP': CDS_PINID='\p0_txp5||sata05_txp\';
NODE_NAME     C923 2
 '@T6G_MB_LIB.T6G(SCH_1):PAGE351_I31@PURE_QUANTA.Q_CAP_DIFFBUS(CHIPS)':
 '2': CDS_PINID='\2\';
NET_NAME
'P5E_CPU0_P0_TX_DP<6>'
 '@T6G_MB_LIB.T6G(SCH_1):P5E_CPU0_P0_TX_DP'<6>:
 C_SIGNAL='@t6g_mb_lib.t6g(sch_1):p5e_cpu0_p0_tx_dp(6)';
NODE_NAME     U25 CL50
 '@T6G_MB_LIB.T6G(SCH_1):PAGE24_I148@PURE_QUANTA.GENOA_SP5(CHIPS)':
 'P0_TXP6||SATA06_TXP': CDS_PINID='\p0_txp6||sata06_txp\';
NODE_NAME     C921 2
 '@T6G_MB_LIB.T6G(SCH_1):PAGE351_I33@PURE_QUANTA.Q_CAP_DIFFBUS(CHIPS)':
 '2': CDS_PINID='\2\';
NET_NAME
'P5E_CPU0_P0_TX_DP<7>'
 '@T6G_MB_LIB.T6G(SCH_1):P5E_CPU0_P0_TX_DP'<7>:
 C_SIGNAL='@t6g_mb_lib.t6g(sch_1):p5e_cpu0_p0_tx_dp(7)';
NODE_NAME     U25 CR47
 '@T6G_MB_LIB.T6G(SCH_1):PAGE24_I148@PURE_QUANTA.GENOA_SP5(CHIPS)':
 'P0_TXP7||SATA07_TXP': CDS_PINID='\p0_txp7||sata07_txp\';
NODE_NAME     C919 2
 '@T6G_MB_LIB.T6G(SCH_1):PAGE351_I36@PURE_QUANTA.Q_CAP_DIFFBUS(CHIPS)':
 '2': CDS_PINID='\2\';
NET_NAME
'P5E_CPU0_P0_TX_DP<8>'
 '@T6G_MB_LIB.T6G(SCH_1):P5E_CPU0_P0_TX_DP'<8>:
 C_SIGNAL='@t6g_mb_lib.t6g(sch_1):p5e_cpu0_p0_tx_dp(8)';
NODE_NAME     U25 CU47
 '@T6G_MB_LIB.T6G(SCH_1):PAGE24_I148@PURE_QUANTA.GENOA_SP5(CHIPS)':
 'P0_TXP8||SATA10_TXP': CDS_PINID='\p0_txp8||sata10_txp\';
NODE_NAME     C917 2
 '@T6G_MB_LIB.T6G(SCH_1):PAGE351_I54@PURE_QUANTA.Q_CAP_DIFFBUS(CHIPS)':
 '2': CDS_PINID='\2\';
NET_NAME
'P5E_CPU0_P0_TX_DP<9>'
 '@T6G_MB_LIB.T6G(SCH_1):P5E_CPU0_P0_TX_DP'<9>:
 C_SIGNAL='@t6g_mb_lib.t6g(sch_1):p5e_cpu0_p0_tx_dp(9)';
NODE_NAME     U25 CN47
 '@T6G_MB_LIB.T6G(SCH_1):PAGE24_I148@PURE_QUANTA.GENOA_SP5(CHIPS)':
 'P0_TXP9||SATA11_TXP': CDS_PINID='\p0_txp9||sata11_txp\';
NODE_NAME     C915 2
 '@T6G_MB_LIB.T6G(SCH_1):PAGE351_I55@PURE_QUANTA.Q_CAP_DIFFBUS(CHIPS)':
 '2': CDS_PINID='\2\';
NET_NAME
'P5E_CPU0_P1_RX_BUF_DN<0>'
 '@T6G_MB_LIB.T6G(SCH_1):P5E_CPU0_P1_RX_BUF_DN'<0>:
 C_SIGNAL='@t6g_mb_lib.t6g(sch_1):p5e_cpu0_p1_rx_buf_dn(0)';
NODE_NAME     U6011 EV2
 '@T6G_MB_LIB.T6G(SCH_1):PAGE406_I38@PURE_QUANTA.PT5161LRS(CHIPS)':
 'A_PERN15': CDS_PINID='A_PERN15';
NODE_NAME     J108 F1
 '@T6G_MB_LIB.T6G(SCH_1):PAGE320_I72@PURE_QUANTA.CONN112_10137002101LF(CHIPS)':
 'F1': CDS_PINID='F1';
NET_NAME
'P5E_CPU0_P1_RX_BUF_DN<10>'
 '@T6G_MB_LIB.T6G(SCH_1):P5E_CPU0_P1_RX_BUF_DN'<10>:
 C_SIGNAL='@t6g_mb_lib.t6g(sch_1):p5e_cpu0_p1_rx_buf_dn(10)';
NODE_NAME     U6011 BH2
 '@T6G_MB_LIB.T6G(SCH_1):PAGE406_I1@PURE_QUANTA.PT5161LRS(CHIPS)':
 'A_PERN5': CDS_PINID='A_PERN5';
NODE_NAME     J107 F3
 '@T6G_MB_LIB.T6G(SCH_1):PAGE317_I49@PURE_QUANTA.CONN112_10137002101LF(CHIPS)':
 'F3': CDS_PINID='F3';
NET_NAME
'P5E_CPU0_P1_RX_BUF_DN<11>'
 '@T6G_MB_LIB.T6G(SCH_1):P5E_CPU0_P1_RX_BUF_DN'<11>:
 C_SIGNAL='@t6g_mb_lib.t6g(sch_1):p5e_cpu0_p1_rx_buf_dn(11)';
NODE_NAME     U6011 BA2
 '@T6G_MB_LIB.T6G(SCH_1):PAGE406_I1@PURE_QUANTA.PT5161LRS(CHIPS)':
 'A_PERN4': CDS_PINID='A_PERN4';
NODE_NAME     J107 E4
 '@T6G_MB_LIB.T6G(SCH_1):PAGE317_I49@PURE_QUANTA.CONN112_10137002101LF(CHIPS)':
 'E4': CDS_PINID='E4';
NET_NAME
'P5E_CPU0_P1_RX_BUF_DN<12>'
 '@T6G_MB_LIB.T6G(SCH_1):P5E_CPU0_P1_RX_BUF_DN'<12>:
 C_SIGNAL='@t6g_mb_lib.t6g(sch_1):p5e_cpu0_p1_rx_buf_dn(12)';
NODE_NAME     U6011 AP2
 '@T6G_MB_LIB.T6G(SCH_1):PAGE406_I1@PURE_QUANTA.PT5161LRS(CHIPS)':
 'A_PERN3': CDS_PINID='A_PERN3';
NODE_NAME     J107 F5
 '@T6G_MB_LIB.T6G(SCH_1):PAGE317_I70@PURE_QUANTA.CONN112_10137002101LF(CHIPS)':
 'F5': CDS_PINID='F5';
NET_NAME
'P5E_CPU0_P1_RX_BUF_DN<13>'
 '@T6G_MB_LIB.T6G(SCH_1):P5E_CPU0_P1_RX_BUF_DN'<13>:
 C_SIGNAL='@t6g_mb_lib.t6g(sch_1):p5e_cpu0_p1_rx_buf_dn(13)';
NODE_NAME     U6011 AG2
 '@T6G_MB_LIB.T6G(SCH_1):PAGE406_I1@PURE_QUANTA.PT5161LRS(CHIPS)':
 'A_PERN2': CDS_PINID='A_PERN2';
NODE_NAME     J107 E6
 '@T6G_MB_LIB.T6G(SCH_1):PAGE317_I70@PURE_QUANTA.CONN112_10137002101LF(CHIPS)':
 'E6': CDS_PINID='E6';
NET_NAME
'P5E_CPU0_P1_RX_BUF_DN<14>'
 '@T6G_MB_LIB.T6G(SCH_1):P5E_CPU0_P1_RX_BUF_DN'<14>:
 C_SIGNAL='@t6g_mb_lib.t6g(sch_1):p5e_cpu0_p1_rx_buf_dn(14)';
NODE_NAME     U6011 Y2
 '@T6G_MB_LIB.T6G(SCH_1):PAGE406_I1@PURE_QUANTA.PT5161LRS(CHIPS)':
 'A_PERN1': CDS_PINID='A_PERN1';
NODE_NAME     J107 F7
 '@T6G_MB_LIB.T6G(SCH_1):PAGE317_I70@PURE_QUANTA.CONN112_10137002101LF(CHIPS)':
 'F7': CDS_PINID='F7';
NET_NAME
'P5E_CPU0_P1_RX_BUF_DN<15>'
 '@T6G_MB_LIB.T6G(SCH_1):P5E_CPU0_P1_RX_BUF_DN'<15>:
 C_SIGNAL='@t6g_mb_lib.t6g(sch_1):p5e_cpu0_p1_rx_buf_dn(15)';
NODE_NAME     U6011 N2
 '@T6G_MB_LIB.T6G(SCH_1):PAGE406_I1@PURE_QUANTA.PT5161LRS(CHIPS)':
 'A_PERN0': CDS_PINID='A_PERN0';
NODE_NAME     J107 E8
 '@T6G_MB_LIB.T6G(SCH_1):PAGE317_I70@PURE_QUANTA.CONN112_10137002101LF(CHIPS)':
 'E8': CDS_PINID='E8';
NET_NAME
'P5E_CPU0_P1_RX_BUF_DN<1>'
 '@T6G_MB_LIB.T6G(SCH_1):P5E_CPU0_P1_RX_BUF_DN'<1>:
 C_SIGNAL='@t6g_mb_lib.t6g(sch_1):p5e_cpu0_p1_rx_buf_dn(1)';
NODE_NAME     U6011 EL2
 '@T6G_MB_LIB.T6G(SCH_1):PAGE406_I38@PURE_QUANTA.PT5161LRS(CHIPS)':
 'A_PERN14': CDS_PINID='A_PERN14';
NODE_NAME     J108 E2
 '@T6G_MB_LIB.T6G(SCH_1):PAGE320_I72@PURE_QUANTA.CONN112_10137002101LF(CHIPS)':
 'E2': CDS_PINID='E2';
NET_NAME
'P5E_CPU0_P1_RX_BUF_DN<2>'
 '@T6G_MB_LIB.T6G(SCH_1):P5E_CPU0_P1_RX_BUF_DN'<2>:
 C_SIGNAL='@t6g_mb_lib.t6g(sch_1):p5e_cpu0_p1_rx_buf_dn(2)';
NODE_NAME     U6011 ED2
 '@T6G_MB_LIB.T6G(SCH_1):PAGE406_I38@PURE_QUANTA.PT5161LRS(CHIPS)':
 'A_PERN13': CDS_PINID='A_PERN13';
NODE_NAME     J108 F3
 '@T6G_MB_LIB.T6G(SCH_1):PAGE320_I72@PURE_QUANTA.CONN112_10137002101LF(CHIPS)':
 'F3': CDS_PINID='F3';
NET_NAME
'P5E_CPU0_P1_RX_BUF_DN<3>'
 '@T6G_MB_LIB.T6G(SCH_1):P5E_CPU0_P1_RX_BUF_DN'<3>:
 C_SIGNAL='@t6g_mb_lib.t6g(sch_1):p5e_cpu0_p1_rx_buf_dn(3)';
NODE_NAME     U6011 DU2
 '@T6G_MB_LIB.T6G(SCH_1):PAGE406_I38@PURE_QUANTA.PT5161LRS(CHIPS)':
 'A_PERN12': CDS_PINID='A_PERN12';
NODE_NAME     J108 E4
 '@T6G_MB_LIB.T6G(SCH_1):PAGE320_I72@PURE_QUANTA.CONN112_10137002101LF(CHIPS)':
 'E4': CDS_PINID='E4';
NET_NAME
'P5E_CPU0_P1_RX_BUF_DN<4>'
 '@T6G_MB_LIB.T6G(SCH_1):P5E_CPU0_P1_RX_BUF_DN'<4>:
 C_SIGNAL='@t6g_mb_lib.t6g(sch_1):p5e_cpu0_p1_rx_buf_dn(4)';
NODE_NAME     U6011 DK2
 '@T6G_MB_LIB.T6G(SCH_1):PAGE406_I38@PURE_QUANTA.PT5161LRS(CHIPS)':
 'A_PERN11': CDS_PINID='A_PERN11';
NODE_NAME     J108 F5
 '@T6G_MB_LIB.T6G(SCH_1):PAGE320_I15@PURE_QUANTA.CONN112_10137002101LF(CHIPS)':
 'F5': CDS_PINID='F5';
NET_NAME
'P5E_CPU0_P1_RX_BUF_DN<5>'
 '@T6G_MB_LIB.T6G(SCH_1):P5E_CPU0_P1_RX_BUF_DN'<5>:
 C_SIGNAL='@t6g_mb_lib.t6g(sch_1):p5e_cpu0_p1_rx_buf_dn(5)';
NODE_NAME     U6011 DC2
 '@T6G_MB_LIB.T6G(SCH_1):PAGE406_I38@PURE_QUANTA.PT5161LRS(CHIPS)':
 'A_PERN10': CDS_PINID='A_PERN10';
NODE_NAME     J108 E6
 '@T6G_MB_LIB.T6G(SCH_1):PAGE320_I15@PURE_QUANTA.CONN112_10137002101LF(CHIPS)':
 'E6': CDS_PINID='E6';
NET_NAME
'P5E_CPU0_P1_RX_BUF_DN<6>'
 '@T6G_MB_LIB.T6G(SCH_1):P5E_CPU0_P1_RX_BUF_DN'<6>:
 C_SIGNAL='@t6g_mb_lib.t6g(sch_1):p5e_cpu0_p1_rx_buf_dn(6)';
NODE_NAME     U6011 CT2
 '@T6G_MB_LIB.T6G(SCH_1):PAGE406_I38@PURE_QUANTA.PT5161LRS(CHIPS)':
 'A_PERN9': CDS_PINID='A_PERN9';
NODE_NAME     J108 F7
 '@T6G_MB_LIB.T6G(SCH_1):PAGE320_I15@PURE_QUANTA.CONN112_10137002101LF(CHIPS)':
 'F7': CDS_PINID='F7';
NET_NAME
'P5E_CPU0_P1_RX_BUF_DN<7>'
 '@T6G_MB_LIB.T6G(SCH_1):P5E_CPU0_P1_RX_BUF_DN'<7>:
 C_SIGNAL='@t6g_mb_lib.t6g(sch_1):p5e_cpu0_p1_rx_buf_dn(7)';
NODE_NAME     U6011 CJ2
 '@T6G_MB_LIB.T6G(SCH_1):PAGE406_I38@PURE_QUANTA.PT5161LRS(CHIPS)':
 'A_PERN8': CDS_PINID='A_PERN8';
NODE_NAME     J108 E8
 '@T6G_MB_LIB.T6G(SCH_1):PAGE320_I15@PURE_QUANTA.CONN112_10137002101LF(CHIPS)':
 'E8': CDS_PINID='E8';
NET_NAME
'P5E_CPU0_P1_RX_BUF_DN<8>'
 '@T6G_MB_LIB.T6G(SCH_1):P5E_CPU0_P1_RX_BUF_DN'<8>:
 C_SIGNAL='@t6g_mb_lib.t6g(sch_1):p5e_cpu0_p1_rx_buf_dn(8)';
NODE_NAME     U6011 CB2
 '@T6G_MB_LIB.T6G(SCH_1):PAGE406_I1@PURE_QUANTA.PT5161LRS(CHIPS)':
 'A_PERN7': CDS_PINID='A_PERN7';
NODE_NAME     J107 F1
 '@T6G_MB_LIB.T6G(SCH_1):PAGE317_I49@PURE_QUANTA.CONN112_10137002101LF(CHIPS)':
 'F1': CDS_PINID='F1';
NET_NAME
'P5E_CPU0_P1_RX_BUF_DN<9>'
 '@T6G_MB_LIB.T6G(SCH_1):P5E_CPU0_P1_RX_BUF_DN'<9>:
 C_SIGNAL='@t6g_mb_lib.t6g(sch_1):p5e_cpu0_p1_rx_buf_dn(9)';
NODE_NAME     U6011 BR2
 '@T6G_MB_LIB.T6G(SCH_1):PAGE406_I1@PURE_QUANTA.PT5161LRS(CHIPS)':
 'A_PERN6': CDS_PINID='A_PERN6';
NODE_NAME     J107 E2
 '@T6G_MB_LIB.T6G(SCH_1):PAGE317_I49@PURE_QUANTA.CONN112_10137002101LF(CHIPS)':
 'E2': CDS_PINID='E2';
NET_NAME
'P5E_CPU0_P1_RX_BUF_DP<0>'
 '@T6G_MB_LIB.T6G(SCH_1):P5E_CPU0_P1_RX_BUF_DP'<0>:
 C_SIGNAL='@t6g_mb_lib.t6g(sch_1):p5e_cpu0_p1_rx_buf_dp(0)';
NODE_NAME     U6011 EY1
 '@T6G_MB_LIB.T6G(SCH_1):PAGE406_I38@PURE_QUANTA.PT5161LRS(CHIPS)':
 'A_PERP15': CDS_PINID='A_PERP15';
NODE_NAME     J108 G1
 '@T6G_MB_LIB.T6G(SCH_1):PAGE320_I72@PURE_QUANTA.CONN112_10137002101LF(CHIPS)':
 'G1': CDS_PINID='G1';
NET_NAME
'P5E_CPU0_P1_RX_BUF_DP<10>'
 '@T6G_MB_LIB.T6G(SCH_1):P5E_CPU0_P1_RX_BUF_DP'<10>:
 C_SIGNAL='@t6g_mb_lib.t6g(sch_1):p5e_cpu0_p1_rx_buf_dp(10)';
NODE_NAME     U6011 BK1
 '@T6G_MB_LIB.T6G(SCH_1):PAGE406_I1@PURE_QUANTA.PT5161LRS(CHIPS)':
 'A_PERP5': CDS_PINID='A_PERP5';
NODE_NAME     J107 G3
 '@T6G_MB_LIB.T6G(SCH_1):PAGE317_I49@PURE_QUANTA.CONN112_10137002101LF(CHIPS)':
 'G3': CDS_PINID='G3';
NET_NAME
'P5E_CPU0_P1_RX_BUF_DP<11>'
 '@T6G_MB_LIB.T6G(SCH_1):P5E_CPU0_P1_RX_BUF_DP'<11>:
 C_SIGNAL='@t6g_mb_lib.t6g(sch_1):p5e_cpu0_p1_rx_buf_dp(11)';
NODE_NAME     U6011 BC1
 '@T6G_MB_LIB.T6G(SCH_1):PAGE406_I1@PURE_QUANTA.PT5161LRS(CHIPS)':
 'A_PERP4': CDS_PINID='A_PERP4';
NODE_NAME     J107 F4
 '@T6G_MB_LIB.T6G(SCH_1):PAGE317_I49@PURE_QUANTA.CONN112_10137002101LF(CHIPS)':
 'F4': CDS_PINID='F4';
NET_NAME
'P5E_CPU0_P1_RX_BUF_DP<12>'
 '@T6G_MB_LIB.T6G(SCH_1):P5E_CPU0_P1_RX_BUF_DP'<12>:
 C_SIGNAL='@t6g_mb_lib.t6g(sch_1):p5e_cpu0_p1_rx_buf_dp(12)';
NODE_NAME     U6011 AT1
 '@T6G_MB_LIB.T6G(SCH_1):PAGE406_I1@PURE_QUANTA.PT5161LRS(CHIPS)':
 'A_PERP3': CDS_PINID='A_PERP3';
NODE_NAME     J107 G5
 '@T6G_MB_LIB.T6G(SCH_1):PAGE317_I70@PURE_QUANTA.CONN112_10137002101LF(CHIPS)':
 'G5': CDS_PINID='G5';
NET_NAME
'P5E_CPU0_P1_RX_BUF_DP<13>'
 '@T6G_MB_LIB.T6G(SCH_1):P5E_CPU0_P1_RX_BUF_DP'<13>:
 C_SIGNAL='@t6g_mb_lib.t6g(sch_1):p5e_cpu0_p1_rx_buf_dp(13)';
NODE_NAME     U6011 AJ1
 '@T6G_MB_LIB.T6G(SCH_1):PAGE406_I1@PURE_QUANTA.PT5161LRS(CHIPS)':
 'A_PERP2': CDS_PINID='A_PERP2';
NODE_NAME     J107 F6
 '@T6G_MB_LIB.T6G(SCH_1):PAGE317_I70@PURE_QUANTA.CONN112_10137002101LF(CHIPS)':
 'F6': CDS_PINID='F6';
NET_NAME
'P5E_CPU0_P1_RX_BUF_DP<14>'
 '@T6G_MB_LIB.T6G(SCH_1):P5E_CPU0_P1_RX_BUF_DP'<14>:
 C_SIGNAL='@t6g_mb_lib.t6g(sch_1):p5e_cpu0_p1_rx_buf_dp(14)';
NODE_NAME     U6011 AB1
 '@T6G_MB_LIB.T6G(SCH_1):PAGE406_I1@PURE_QUANTA.PT5161LRS(CHIPS)':
 'A_PERP1': CDS_PINID='A_PERP1';
NODE_NAME     J107 G7
 '@T6G_MB_LIB.T6G(SCH_1):PAGE317_I70@PURE_QUANTA.CONN112_10137002101LF(CHIPS)':
 'G7': CDS_PINID='G7';
NET_NAME
'P5E_CPU0_P1_RX_BUF_DP<15>'
 '@T6G_MB_LIB.T6G(SCH_1):P5E_CPU0_P1_RX_BUF_DP'<15>:
 C_SIGNAL='@t6g_mb_lib.t6g(sch_1):p5e_cpu0_p1_rx_buf_dp(15)';
NODE_NAME     U6011 R1
 '@T6G_MB_LIB.T6G(SCH_1):PAGE406_I1@PURE_QUANTA.PT5161LRS(CHIPS)':
 'A_PERP0': CDS_PINID='A_PERP0';
NODE_NAME     J107 F8
 '@T6G_MB_LIB.T6G(SCH_1):PAGE317_I70@PURE_QUANTA.CONN112_10137002101LF(CHIPS)':
 'F8': CDS_PINID='F8';
NET_NAME
'P5E_CPU0_P1_RX_BUF_DP<1>'
 '@T6G_MB_LIB.T6G(SCH_1):P5E_CPU0_P1_RX_BUF_DP'<1>:
 C_SIGNAL='@t6g_mb_lib.t6g(sch_1):p5e_cpu0_p1_rx_buf_dp(1)';
NODE_NAME     U6011 EN1
 '@T6G_MB_LIB.T6G(SCH_1):PAGE406_I38@PURE_QUANTA.PT5161LRS(CHIPS)':
 'A_PERP14': CDS_PINID='A_PERP14';
NODE_NAME     J108 F2
 '@T6G_MB_LIB.T6G(SCH_1):PAGE320_I72@PURE_QUANTA.CONN112_10137002101LF(CHIPS)':
 'F2': CDS_PINID='F2';
NET_NAME
'P5E_CPU0_P1_RX_BUF_DP<2>'
 '@T6G_MB_LIB.T6G(SCH_1):P5E_CPU0_P1_RX_BUF_DP'<2>:
 C_SIGNAL='@t6g_mb_lib.t6g(sch_1):p5e_cpu0_p1_rx_buf_dp(2)';
NODE_NAME     U6011 EF1
 '@T6G_MB_LIB.T6G(SCH_1):PAGE406_I38@PURE_QUANTA.PT5161LRS(CHIPS)':
 'A_PERP13': CDS_PINID='A_PERP13';
NODE_NAME     J108 G3
 '@T6G_MB_LIB.T6G(SCH_1):PAGE320_I72@PURE_QUANTA.CONN112_10137002101LF(CHIPS)':
 'G3': CDS_PINID='G3';
NET_NAME
'P5E_CPU0_P1_RX_BUF_DP<3>'
 '@T6G_MB_LIB.T6G(SCH_1):P5E_CPU0_P1_RX_BUF_DP'<3>:
 C_SIGNAL='@t6g_mb_lib.t6g(sch_1):p5e_cpu0_p1_rx_buf_dp(3)';
NODE_NAME     U6011 DW1
 '@T6G_MB_LIB.T6G(SCH_1):PAGE406_I38@PURE_QUANTA.PT5161LRS(CHIPS)':
 'A_PERP12': CDS_PINID='A_PERP12';
NODE_NAME     J108 F4
 '@T6G_MB_LIB.T6G(SCH_1):PAGE320_I72@PURE_QUANTA.CONN112_10137002101LF(CHIPS)':
 'F4': CDS_PINID='F4';
NET_NAME
'P5E_CPU0_P1_RX_BUF_DP<4>'
 '@T6G_MB_LIB.T6G(SCH_1):P5E_CPU0_P1_RX_BUF_DP'<4>:
 C_SIGNAL='@t6g_mb_lib.t6g(sch_1):p5e_cpu0_p1_rx_buf_dp(4)';
NODE_NAME     U6011 DM1
 '@T6G_MB_LIB.T6G(SCH_1):PAGE406_I38@PURE_QUANTA.PT5161LRS(CHIPS)':
 'A_PERP11': CDS_PINID='A_PERP11';
NODE_NAME     J108 G5
 '@T6G_MB_LIB.T6G(SCH_1):PAGE320_I15@PURE_QUANTA.CONN112_10137002101LF(CHIPS)':
 'G5': CDS_PINID='G5';
NET_NAME
'P5E_CPU0_P1_RX_BUF_DP<5>'
 '@T6G_MB_LIB.T6G(SCH_1):P5E_CPU0_P1_RX_BUF_DP'<5>:
 C_SIGNAL='@t6g_mb_lib.t6g(sch_1):p5e_cpu0_p1_rx_buf_dp(5)';
NODE_NAME     U6011 DE1
 '@T6G_MB_LIB.T6G(SCH_1):PAGE406_I38@PURE_QUANTA.PT5161LRS(CHIPS)':
 'A_PERP10': CDS_PINID='A_PERP10';
NODE_NAME     J108 F6
 '@T6G_MB_LIB.T6G(SCH_1):PAGE320_I15@PURE_QUANTA.CONN112_10137002101LF(CHIPS)':
 'F6': CDS_PINID='F6';
NET_NAME
'P5E_CPU0_P1_RX_BUF_DP<6>'
 '@T6G_MB_LIB.T6G(SCH_1):P5E_CPU0_P1_RX_BUF_DP'<6>:
 C_SIGNAL='@t6g_mb_lib.t6g(sch_1):p5e_cpu0_p1_rx_buf_dp(6)';
NODE_NAME     U6011 CV1
 '@T6G_MB_LIB.T6G(SCH_1):PAGE406_I38@PURE_QUANTA.PT5161LRS(CHIPS)':
 'A_PERP9': CDS_PINID='A_PERP9';
NODE_NAME     J108 G7
 '@T6G_MB_LIB.T6G(SCH_1):PAGE320_I15@PURE_QUANTA.CONN112_10137002101LF(CHIPS)':
 'G7': CDS_PINID='G7';
NET_NAME
'P5E_CPU0_P1_RX_BUF_DP<7>'
 '@T6G_MB_LIB.T6G(SCH_1):P5E_CPU0_P1_RX_BUF_DP'<7>:
 C_SIGNAL='@t6g_mb_lib.t6g(sch_1):p5e_cpu0_p1_rx_buf_dp(7)';
NODE_NAME     U6011 CL1
 '@T6G_MB_LIB.T6G(SCH_1):PAGE406_I38@PURE_QUANTA.PT5161LRS(CHIPS)':
 'A_PERP8': CDS_PINID='A_PERP8';
NODE_NAME     J108 F8
 '@T6G_MB_LIB.T6G(SCH_1):PAGE320_I15@PURE_QUANTA.CONN112_10137002101LF(CHIPS)':
 'F8': CDS_PINID='F8';
NET_NAME
'P5E_CPU0_P1_RX_BUF_DP<8>'
 '@T6G_MB_LIB.T6G(SCH_1):P5E_CPU0_P1_RX_BUF_DP'<8>:
 C_SIGNAL='@t6g_mb_lib.t6g(sch_1):p5e_cpu0_p1_rx_buf_dp(8)';
NODE_NAME     U6011 CD1
 '@T6G_MB_LIB.T6G(SCH_1):PAGE406_I1@PURE_QUANTA.PT5161LRS(CHIPS)':
 'A_PERP7': CDS_PINID='A_PERP7';
NODE_NAME     J107 G1
 '@T6G_MB_LIB.T6G(SCH_1):PAGE317_I49@PURE_QUANTA.CONN112_10137002101LF(CHIPS)':
 'G1': CDS_PINID='G1';
NET_NAME
'P5E_CPU0_P1_RX_BUF_DP<9>'
 '@T6G_MB_LIB.T6G(SCH_1):P5E_CPU0_P1_RX_BUF_DP'<9>:
 C_SIGNAL='@t6g_mb_lib.t6g(sch_1):p5e_cpu0_p1_rx_buf_dp(9)';
NODE_NAME     U6011 BU1
 '@T6G_MB_LIB.T6G(SCH_1):PAGE406_I1@PURE_QUANTA.PT5161LRS(CHIPS)':
 'A_PERP6': CDS_PINID='A_PERP6';
NODE_NAME     J107 F2
 '@T6G_MB_LIB.T6G(SCH_1):PAGE317_I49@PURE_QUANTA.CONN112_10137002101LF(CHIPS)':
 'F2': CDS_PINID='F2';
NET_NAME
'P5E_CPU0_P1_RX_DN<0>'
 '@T6G_MB_LIB.T6G(SCH_1):P5E_CPU0_P1_RX_DN'<0>:
 C_SIGNAL='@t6g_mb_lib.t6g(sch_1):p5e_cpu0_p1_rx_dn(0)';
NODE_NAME     U25 CE53
 '@T6G_MB_LIB.T6G(SCH_1):PAGE24_I149@PURE_QUANTA.GENOA_SP5(CHIPS)':
 'P1_RXN0': CDS_PINID='P1_RXN0';
NODE_NAME     U6011 EW29
 '@T6G_MB_LIB.T6G(SCH_1):PAGE405_I38@PURE_QUANTA.PT5161LRS(CHIPS)':
 'A_PETN15': CDS_PINID='A_PETN15';
NET_NAME
'P5E_CPU0_P1_RX_DN<10>'
 '@T6G_MB_LIB.T6G(SCH_1):P5E_CPU0_P1_RX_DN'<10>:
 C_SIGNAL='@t6g_mb_lib.t6g(sch_1):p5e_cpu0_p1_rx_dn(10)';
NODE_NAME     U25 CG44
 '@T6G_MB_LIB.T6G(SCH_1):PAGE24_I149@PURE_QUANTA.GENOA_SP5(CHIPS)':
 'P1_RXN10': CDS_PINID='P1_RXN10';
NODE_NAME     U6011 BJ29
 '@T6G_MB_LIB.T6G(SCH_1):PAGE405_I1@PURE_QUANTA.PT5161LRS(CHIPS)':
 'A_PETN5': CDS_PINID='A_PETN5';
NET_NAME
'P5E_CPU0_P1_RX_DN<11>'
 '@T6G_MB_LIB.T6G(SCH_1):P5E_CPU0_P1_RX_DN'<11>:
 C_SIGNAL='@t6g_mb_lib.t6g(sch_1):p5e_cpu0_p1_rx_dn(11)';
NODE_NAME     U25 CJ44
 '@T6G_MB_LIB.T6G(SCH_1):PAGE24_I149@PURE_QUANTA.GENOA_SP5(CHIPS)':
 'P1_RXN11': CDS_PINID='P1_RXN11';
NODE_NAME     U6011 BB29
 '@T6G_MB_LIB.T6G(SCH_1):PAGE405_I1@PURE_QUANTA.PT5161LRS(CHIPS)':
 'A_PETN4': CDS_PINID='A_PETN4';
NET_NAME
'P5E_CPU0_P1_RX_DN<12>'
 '@T6G_MB_LIB.T6G(SCH_1):P5E_CPU0_P1_RX_DN'<12>:
 C_SIGNAL='@t6g_mb_lib.t6g(sch_1):p5e_cpu0_p1_rx_dn(12)';
NODE_NAME     U25 CC44
 '@T6G_MB_LIB.T6G(SCH_1):PAGE24_I149@PURE_QUANTA.GENOA_SP5(CHIPS)':
 'P1_RXN12': CDS_PINID='P1_RXN12';
NODE_NAME     U6011 AR29
 '@T6G_MB_LIB.T6G(SCH_1):PAGE405_I1@PURE_QUANTA.PT5161LRS(CHIPS)':
 'A_PETN3': CDS_PINID='A_PETN3';
NET_NAME
'P5E_CPU0_P1_RX_DN<13>'
 '@T6G_MB_LIB.T6G(SCH_1):P5E_CPU0_P1_RX_DN'<13>:
 C_SIGNAL='@t6g_mb_lib.t6g(sch_1):p5e_cpu0_p1_rx_dn(13)';
NODE_NAME     U25 CH41
 '@T6G_MB_LIB.T6G(SCH_1):PAGE24_I149@PURE_QUANTA.GENOA_SP5(CHIPS)':
 'P1_RXN13': CDS_PINID='P1_RXN13';
NODE_NAME     U6011 AH29
 '@T6G_MB_LIB.T6G(SCH_1):PAGE405_I1@PURE_QUANTA.PT5161LRS(CHIPS)':
 'A_PETN2': CDS_PINID='A_PETN2';
NET_NAME
'P5E_CPU0_P1_RX_DN<14>'
 '@T6G_MB_LIB.T6G(SCH_1):P5E_CPU0_P1_RX_DN'<14>:
 C_SIGNAL='@t6g_mb_lib.t6g(sch_1):p5e_cpu0_p1_rx_dn(14)';
NODE_NAME     U25 CF41
 '@T6G_MB_LIB.T6G(SCH_1):PAGE24_I149@PURE_QUANTA.GENOA_SP5(CHIPS)':
 'P1_RXN14': CDS_PINID='P1_RXN14';
NODE_NAME     U6011 AA29
 '@T6G_MB_LIB.T6G(SCH_1):PAGE405_I1@PURE_QUANTA.PT5161LRS(CHIPS)':
 'A_PETN1': CDS_PINID='A_PETN1';
NET_NAME
'P5E_CPU0_P1_RX_DN<15>'
 '@T6G_MB_LIB.T6G(SCH_1):P5E_CPU0_P1_RX_DN'<15>:
 C_SIGNAL='@t6g_mb_lib.t6g(sch_1):p5e_cpu0_p1_rx_dn(15)';
NODE_NAME     U25 CD41
 '@T6G_MB_LIB.T6G(SCH_1):PAGE24_I149@PURE_QUANTA.GENOA_SP5(CHIPS)':
 'P1_RXN15': CDS_PINID='P1_RXN15';
NODE_NAME     U6011 P29
 '@T6G_MB_LIB.T6G(SCH_1):PAGE405_I1@PURE_QUANTA.PT5161LRS(CHIPS)':
 'A_PETN0': CDS_PINID='A_PETN0';
NET_NAME
'P5E_CPU0_P1_RX_DN<1>'
 '@T6G_MB_LIB.T6G(SCH_1):P5E_CPU0_P1_RX_DN'<1>:
 C_SIGNAL='@t6g_mb_lib.t6g(sch_1):p5e_cpu0_p1_rx_dn(1)';
NODE_NAME     U25 CG53
 '@T6G_MB_LIB.T6G(SCH_1):PAGE24_I149@PURE_QUANTA.GENOA_SP5(CHIPS)':
 'P1_RXN1': CDS_PINID='P1_RXN1';
NODE_NAME     U6011 EM29
 '@T6G_MB_LIB.T6G(SCH_1):PAGE405_I38@PURE_QUANTA.PT5161LRS(CHIPS)':
 'A_PETN14': CDS_PINID='A_PETN14';
NET_NAME
'P5E_CPU0_P1_RX_DN<2>'
 '@T6G_MB_LIB.T6G(SCH_1):P5E_CPU0_P1_RX_DN'<2>:
 C_SIGNAL='@t6g_mb_lib.t6g(sch_1):p5e_cpu0_p1_rx_dn(2)';
NODE_NAME     U25 CC53
 '@T6G_MB_LIB.T6G(SCH_1):PAGE24_I149@PURE_QUANTA.GENOA_SP5(CHIPS)':
 'P1_RXN2': CDS_PINID='P1_RXN2';
NODE_NAME     U6011 EE29
 '@T6G_MB_LIB.T6G(SCH_1):PAGE405_I38@PURE_QUANTA.PT5161LRS(CHIPS)':
 'A_PETN13': CDS_PINID='A_PETN13';
NET_NAME
'P5E_CPU0_P1_RX_DN<3>'
 '@T6G_MB_LIB.T6G(SCH_1):P5E_CPU0_P1_RX_DN'<3>:
 C_SIGNAL='@t6g_mb_lib.t6g(sch_1):p5e_cpu0_p1_rx_dn(3)';
NODE_NAME     U25 CE50
 '@T6G_MB_LIB.T6G(SCH_1):PAGE24_I149@PURE_QUANTA.GENOA_SP5(CHIPS)':
 'P1_RXN3': CDS_PINID='P1_RXN3';
NODE_NAME     U6011 DV29
 '@T6G_MB_LIB.T6G(SCH_1):PAGE405_I38@PURE_QUANTA.PT5161LRS(CHIPS)':
 'A_PETN12': CDS_PINID='A_PETN12';
NET_NAME
'P5E_CPU0_P1_RX_DN<4>'
 '@T6G_MB_LIB.T6G(SCH_1):P5E_CPU0_P1_RX_DN'<4>:
 C_SIGNAL='@t6g_mb_lib.t6g(sch_1):p5e_cpu0_p1_rx_dn(4)';
NODE_NAME     U25 CG50
 '@T6G_MB_LIB.T6G(SCH_1):PAGE24_I149@PURE_QUANTA.GENOA_SP5(CHIPS)':
 'P1_RXN4': CDS_PINID='P1_RXN4';
NODE_NAME     U6011 DL29
 '@T6G_MB_LIB.T6G(SCH_1):PAGE405_I38@PURE_QUANTA.PT5161LRS(CHIPS)':
 'A_PETN11': CDS_PINID='A_PETN11';
NET_NAME
'P5E_CPU0_P1_RX_DN<5>'
 '@T6G_MB_LIB.T6G(SCH_1):P5E_CPU0_P1_RX_DN'<5>:
 C_SIGNAL='@t6g_mb_lib.t6g(sch_1):p5e_cpu0_p1_rx_dn(5)';
NODE_NAME     U25 CC50
 '@T6G_MB_LIB.T6G(SCH_1):PAGE24_I149@PURE_QUANTA.GENOA_SP5(CHIPS)':
 'P1_RXN5': CDS_PINID='P1_RXN5';
NODE_NAME     U6011 DD29
 '@T6G_MB_LIB.T6G(SCH_1):PAGE405_I38@PURE_QUANTA.PT5161LRS(CHIPS)':
 'A_PETN10': CDS_PINID='A_PETN10';
NET_NAME
'P5E_CPU0_P1_RX_DN<6>'
 '@T6G_MB_LIB.T6G(SCH_1):P5E_CPU0_P1_RX_DN'<6>:
 C_SIGNAL='@t6g_mb_lib.t6g(sch_1):p5e_cpu0_p1_rx_dn(6)';
NODE_NAME     U25 CE47
 '@T6G_MB_LIB.T6G(SCH_1):PAGE24_I149@PURE_QUANTA.GENOA_SP5(CHIPS)':
 'P1_RXN6': CDS_PINID='P1_RXN6';
NODE_NAME     U6011 CU29
 '@T6G_MB_LIB.T6G(SCH_1):PAGE405_I38@PURE_QUANTA.PT5161LRS(CHIPS)':
 'A_PETN9': CDS_PINID='A_PETN9';
NET_NAME
'P5E_CPU0_P1_RX_DN<7>'
 '@T6G_MB_LIB.T6G(SCH_1):P5E_CPU0_P1_RX_DN'<7>:
 C_SIGNAL='@t6g_mb_lib.t6g(sch_1):p5e_cpu0_p1_rx_dn(7)';
NODE_NAME     U25 CG47
 '@T6G_MB_LIB.T6G(SCH_1):PAGE24_I149@PURE_QUANTA.GENOA_SP5(CHIPS)':
 'P1_RXN7': CDS_PINID='P1_RXN7';
NODE_NAME     U6011 CK29
 '@T6G_MB_LIB.T6G(SCH_1):PAGE405_I38@PURE_QUANTA.PT5161LRS(CHIPS)':
 'A_PETN8': CDS_PINID='A_PETN8';
NET_NAME
'P5E_CPU0_P1_RX_DN<8>'
 '@T6G_MB_LIB.T6G(SCH_1):P5E_CPU0_P1_RX_DN'<8>:
 C_SIGNAL='@t6g_mb_lib.t6g(sch_1):p5e_cpu0_p1_rx_dn(8)';
NODE_NAME     U25 CC47
 '@T6G_MB_LIB.T6G(SCH_1):PAGE24_I149@PURE_QUANTA.GENOA_SP5(CHIPS)':
 'P1_RXN8': CDS_PINID='P1_RXN8';
NODE_NAME     U6011 CC29
 '@T6G_MB_LIB.T6G(SCH_1):PAGE405_I1@PURE_QUANTA.PT5161LRS(CHIPS)':
 'A_PETN7': CDS_PINID='A_PETN7';
NET_NAME
'P5E_CPU0_P1_RX_DN<9>'
 '@T6G_MB_LIB.T6G(SCH_1):P5E_CPU0_P1_RX_DN'<9>:
 C_SIGNAL='@t6g_mb_lib.t6g(sch_1):p5e_cpu0_p1_rx_dn(9)';
NODE_NAME     U25 CE44
 '@T6G_MB_LIB.T6G(SCH_1):PAGE24_I149@PURE_QUANTA.GENOA_SP5(CHIPS)':
 'P1_RXN9': CDS_PINID='P1_RXN9';
NODE_NAME     U6011 BT29
 '@T6G_MB_LIB.T6G(SCH_1):PAGE405_I1@PURE_QUANTA.PT5161LRS(CHIPS)':
 'A_PETN6': CDS_PINID='A_PETN6';
NET_NAME
'P5E_CPU0_P1_RX_DP<0>'
 '@T6G_MB_LIB.T6G(SCH_1):P5E_CPU0_P1_RX_DP'<0>:
 C_SIGNAL='@t6g_mb_lib.t6g(sch_1):p5e_cpu0_p1_rx_dp(0)';
NODE_NAME     U25 CE52
 '@T6G_MB_LIB.T6G(SCH_1):PAGE24_I149@PURE_QUANTA.GENOA_SP5(CHIPS)':
 'P1_RXP0': CDS_PINID='P1_RXP0';
NODE_NAME     U6011 EU26
 '@T6G_MB_LIB.T6G(SCH_1):PAGE405_I38@PURE_QUANTA.PT5161LRS(CHIPS)':
 'A_PETP15': CDS_PINID='A_PETP15';
NET_NAME
'P5E_CPU0_P1_RX_DP<10>'
 '@T6G_MB_LIB.T6G(SCH_1):P5E_CPU0_P1_RX_DP'<10>:
 C_SIGNAL='@t6g_mb_lib.t6g(sch_1):p5e_cpu0_p1_rx_dp(10)';
NODE_NAME     U25 CG43
 '@T6G_MB_LIB.T6G(SCH_1):PAGE24_I149@PURE_QUANTA.GENOA_SP5(CHIPS)':
 'P1_RXP10': CDS_PINID='P1_RXP10';
NODE_NAME     U6011 BG26
 '@T6G_MB_LIB.T6G(SCH_1):PAGE405_I1@PURE_QUANTA.PT5161LRS(CHIPS)':
 'A_PETP5': CDS_PINID='A_PETP5';
NET_NAME
'P5E_CPU0_P1_RX_DP<11>'
 '@T6G_MB_LIB.T6G(SCH_1):P5E_CPU0_P1_RX_DP'<11>:
 C_SIGNAL='@t6g_mb_lib.t6g(sch_1):p5e_cpu0_p1_rx_dp(11)';
NODE_NAME     U25 CJ43
 '@T6G_MB_LIB.T6G(SCH_1):PAGE24_I149@PURE_QUANTA.GENOA_SP5(CHIPS)':
 'P1_RXP11': CDS_PINID='P1_RXP11';
NODE_NAME     U6011 AY26
 '@T6G_MB_LIB.T6G(SCH_1):PAGE405_I1@PURE_QUANTA.PT5161LRS(CHIPS)':
 'A_PETP4': CDS_PINID='A_PETP4';
NET_NAME
'P5E_CPU0_P1_RX_DP<12>'
 '@T6G_MB_LIB.T6G(SCH_1):P5E_CPU0_P1_RX_DP'<12>:
 C_SIGNAL='@t6g_mb_lib.t6g(sch_1):p5e_cpu0_p1_rx_dp(12)';
NODE_NAME     U25 CC43
 '@T6G_MB_LIB.T6G(SCH_1):PAGE24_I149@PURE_QUANTA.GENOA_SP5(CHIPS)':
 'P1_RXP12': CDS_PINID='P1_RXP12';
NODE_NAME     U6011 AN26
 '@T6G_MB_LIB.T6G(SCH_1):PAGE405_I1@PURE_QUANTA.PT5161LRS(CHIPS)':
 'A_PETP3': CDS_PINID='A_PETP3';
NET_NAME
'P5E_CPU0_P1_RX_DP<13>'
 '@T6G_MB_LIB.T6G(SCH_1):P5E_CPU0_P1_RX_DP'<13>:
 C_SIGNAL='@t6g_mb_lib.t6g(sch_1):p5e_cpu0_p1_rx_dp(13)';
NODE_NAME     U25 CH40
 '@T6G_MB_LIB.T6G(SCH_1):PAGE24_I149@PURE_QUANTA.GENOA_SP5(CHIPS)':
 'P1_RXP13': CDS_PINID='P1_RXP13';
NODE_NAME     U6011 AF26
 '@T6G_MB_LIB.T6G(SCH_1):PAGE405_I1@PURE_QUANTA.PT5161LRS(CHIPS)':
 'A_PETP2': CDS_PINID='A_PETP2';
NET_NAME
'P5E_CPU0_P1_RX_DP<14>'
 '@T6G_MB_LIB.T6G(SCH_1):P5E_CPU0_P1_RX_DP'<14>:
 C_SIGNAL='@t6g_mb_lib.t6g(sch_1):p5e_cpu0_p1_rx_dp(14)';
NODE_NAME     U25 CF40
 '@T6G_MB_LIB.T6G(SCH_1):PAGE24_I149@PURE_QUANTA.GENOA_SP5(CHIPS)':
 'P1_RXP14': CDS_PINID='P1_RXP14';
NODE_NAME     U6011 W26
 '@T6G_MB_LIB.T6G(SCH_1):PAGE405_I1@PURE_QUANTA.PT5161LRS(CHIPS)':
 'A_PETP1': CDS_PINID='A_PETP1';
NET_NAME
'P5E_CPU0_P1_RX_DP<15>'
 '@T6G_MB_LIB.T6G(SCH_1):P5E_CPU0_P1_RX_DP'<15>:
 C_SIGNAL='@t6g_mb_lib.t6g(sch_1):p5e_cpu0_p1_rx_dp(15)';
NODE_NAME     U25 CD40
 '@T6G_MB_LIB.T6G(SCH_1):PAGE24_I149@PURE_QUANTA.GENOA_SP5(CHIPS)':
 'P1_RXP15': CDS_PINID='P1_RXP15';
NODE_NAME     U6011 M26
 '@T6G_MB_LIB.T6G(SCH_1):PAGE405_I1@PURE_QUANTA.PT5161LRS(CHIPS)':
 'A_PETP0': CDS_PINID='A_PETP0';
NET_NAME
'P5E_CPU0_P1_RX_DP<1>'
 '@T6G_MB_LIB.T6G(SCH_1):P5E_CPU0_P1_RX_DP'<1>:
 C_SIGNAL='@t6g_mb_lib.t6g(sch_1):p5e_cpu0_p1_rx_dp(1)';
NODE_NAME     U25 CG52
 '@T6G_MB_LIB.T6G(SCH_1):PAGE24_I149@PURE_QUANTA.GENOA_SP5(CHIPS)':
 'P1_RXP1': CDS_PINID='P1_RXP1';
NODE_NAME     U6011 EK26
 '@T6G_MB_LIB.T6G(SCH_1):PAGE405_I38@PURE_QUANTA.PT5161LRS(CHIPS)':
 'A_PETP14': CDS_PINID='A_PETP14';
NET_NAME
'P5E_CPU0_P1_RX_DP<2>'
 '@T6G_MB_LIB.T6G(SCH_1):P5E_CPU0_P1_RX_DP'<2>:
 C_SIGNAL='@t6g_mb_lib.t6g(sch_1):p5e_cpu0_p1_rx_dp(2)';
NODE_NAME     U25 CC52
 '@T6G_MB_LIB.T6G(SCH_1):PAGE24_I149@PURE_QUANTA.GENOA_SP5(CHIPS)':
 'P1_RXP2': CDS_PINID='P1_RXP2';
NODE_NAME     U6011 EC26
 '@T6G_MB_LIB.T6G(SCH_1):PAGE405_I38@PURE_QUANTA.PT5161LRS(CHIPS)':
 'A_PETP13': CDS_PINID='A_PETP13';
NET_NAME
'P5E_CPU0_P1_RX_DP<3>'
 '@T6G_MB_LIB.T6G(SCH_1):P5E_CPU0_P1_RX_DP'<3>:
 C_SIGNAL='@t6g_mb_lib.t6g(sch_1):p5e_cpu0_p1_rx_dp(3)';
NODE_NAME     U25 CE49
 '@T6G_MB_LIB.T6G(SCH_1):PAGE24_I149@PURE_QUANTA.GENOA_SP5(CHIPS)':
 'P1_RXP3': CDS_PINID='P1_RXP3';
NODE_NAME     U6011 DT26
 '@T6G_MB_LIB.T6G(SCH_1):PAGE405_I38@PURE_QUANTA.PT5161LRS(CHIPS)':
 'A_PETP12': CDS_PINID='A_PETP12';
NET_NAME
'P5E_CPU0_P1_RX_DP<4>'
 '@T6G_MB_LIB.T6G(SCH_1):P5E_CPU0_P1_RX_DP'<4>:
 C_SIGNAL='@t6g_mb_lib.t6g(sch_1):p5e_cpu0_p1_rx_dp(4)';
NODE_NAME     U25 CG49
 '@T6G_MB_LIB.T6G(SCH_1):PAGE24_I149@PURE_QUANTA.GENOA_SP5(CHIPS)':
 'P1_RXP4': CDS_PINID='P1_RXP4';
NODE_NAME     U6011 DJ26
 '@T6G_MB_LIB.T6G(SCH_1):PAGE405_I38@PURE_QUANTA.PT5161LRS(CHIPS)':
 'A_PETP11': CDS_PINID='A_PETP11';
NET_NAME
'P5E_CPU0_P1_RX_DP<5>'
 '@T6G_MB_LIB.T6G(SCH_1):P5E_CPU0_P1_RX_DP'<5>:
 C_SIGNAL='@t6g_mb_lib.t6g(sch_1):p5e_cpu0_p1_rx_dp(5)';
NODE_NAME     U25 CC49
 '@T6G_MB_LIB.T6G(SCH_1):PAGE24_I149@PURE_QUANTA.GENOA_SP5(CHIPS)':
 'P1_RXP5': CDS_PINID='P1_RXP5';
NODE_NAME     U6011 DB26
 '@T6G_MB_LIB.T6G(SCH_1):PAGE405_I38@PURE_QUANTA.PT5161LRS(CHIPS)':
 'A_PETP10': CDS_PINID='A_PETP10';
NET_NAME
'P5E_CPU0_P1_RX_DP<6>'
 '@T6G_MB_LIB.T6G(SCH_1):P5E_CPU0_P1_RX_DP'<6>:
 C_SIGNAL='@t6g_mb_lib.t6g(sch_1):p5e_cpu0_p1_rx_dp(6)';
NODE_NAME     U25 CE46
 '@T6G_MB_LIB.T6G(SCH_1):PAGE24_I149@PURE_QUANTA.GENOA_SP5(CHIPS)':
 'P1_RXP6': CDS_PINID='P1_RXP6';
NODE_NAME     U6011 CR26
 '@T6G_MB_LIB.T6G(SCH_1):PAGE405_I38@PURE_QUANTA.PT5161LRS(CHIPS)':
 'A_PETP9': CDS_PINID='A_PETP9';
NET_NAME
'P5E_CPU0_P1_RX_DP<7>'
 '@T6G_MB_LIB.T6G(SCH_1):P5E_CPU0_P1_RX_DP'<7>:
 C_SIGNAL='@t6g_mb_lib.t6g(sch_1):p5e_cpu0_p1_rx_dp(7)';
NODE_NAME     U25 CG46
 '@T6G_MB_LIB.T6G(SCH_1):PAGE24_I149@PURE_QUANTA.GENOA_SP5(CHIPS)':
 'P1_RXP7': CDS_PINID='P1_RXP7';
NODE_NAME     U6011 CH26
 '@T6G_MB_LIB.T6G(SCH_1):PAGE405_I38@PURE_QUANTA.PT5161LRS(CHIPS)':
 'A_PETP8': CDS_PINID='A_PETP8';
NET_NAME
'P5E_CPU0_P1_RX_DP<8>'
 '@T6G_MB_LIB.T6G(SCH_1):P5E_CPU0_P1_RX_DP'<8>:
 C_SIGNAL='@t6g_mb_lib.t6g(sch_1):p5e_cpu0_p1_rx_dp(8)';
NODE_NAME     U25 CC46
 '@T6G_MB_LIB.T6G(SCH_1):PAGE24_I149@PURE_QUANTA.GENOA_SP5(CHIPS)':
 'P1_RXP8': CDS_PINID='P1_RXP8';
NODE_NAME     U6011 CA26
 '@T6G_MB_LIB.T6G(SCH_1):PAGE405_I1@PURE_QUANTA.PT5161LRS(CHIPS)':
 'A_PETP7': CDS_PINID='A_PETP7';
NET_NAME
'P5E_CPU0_P1_RX_DP<9>'
 '@T6G_MB_LIB.T6G(SCH_1):P5E_CPU0_P1_RX_DP'<9>:
 C_SIGNAL='@t6g_mb_lib.t6g(sch_1):p5e_cpu0_p1_rx_dp(9)';
NODE_NAME     U25 CE43
 '@T6G_MB_LIB.T6G(SCH_1):PAGE24_I149@PURE_QUANTA.GENOA_SP5(CHIPS)':
 'P1_RXP9': CDS_PINID='P1_RXP9';
NODE_NAME     U6011 BP26
 '@T6G_MB_LIB.T6G(SCH_1):PAGE405_I1@PURE_QUANTA.PT5161LRS(CHIPS)':
 'A_PETP6': CDS_PINID='A_PETP6';
NET_NAME
'P5E_CPU0_P1_TX_BUF_C_DN<0>'
 '@T6G_MB_LIB.T6G(SCH_1):P5E_CPU0_P1_TX_BUF_C_DN'<0>:
 C_SIGNAL='@t6g_mb_lib.t6g(sch_1):p5e_cpu0_p1_tx_buf_c_dn(0)';
NODE_NAME     C6534 1
 '@T6G_MB_LIB.T6G(SCH_1):PAGE407_I47@PURE_QUANTA.Q_CAP_DIFFBUS(CHIPS)':
 '1': CDS_PINID='\1\';
NODE_NAME     J108 L1
 '@T6G_MB_LIB.T6G(SCH_1):PAGE320_I72@PURE_QUANTA.CONN112_10137002101LF(CHIPS)':
 'L1': CDS_PINID='L1';
NET_NAME
'P5E_CPU0_P1_TX_BUF_C_DN<10>'
 '@T6G_MB_LIB.T6G(SCH_1):P5E_CPU0_P1_TX_BUF_C_DN'<10>:
 C_SIGNAL='@t6g_mb_lib.t6g(sch_1):p5e_cpu0_p1_tx_buf_c_dn(10)';
NODE_NAME     C6554 1
 '@T6G_MB_LIB.T6G(SCH_1):PAGE407_I97@PURE_QUANTA.Q_CAP_DIFFBUS(CHIPS)':
 '1': CDS_PINID='\1\';
NODE_NAME     J107 L3
 '@T6G_MB_LIB.T6G(SCH_1):PAGE317_I49@PURE_QUANTA.CONN112_10137002101LF(CHIPS)':
 'L3': CDS_PINID='L3';
NET_NAME
'P5E_CPU0_P1_TX_BUF_C_DN<11>'
 '@T6G_MB_LIB.T6G(SCH_1):P5E_CPU0_P1_TX_BUF_C_DN'<11>:
 C_SIGNAL='@t6g_mb_lib.t6g(sch_1):p5e_cpu0_p1_tx_buf_c_dn(11)';
NODE_NAME     C6556 1
 '@T6G_MB_LIB.T6G(SCH_1):PAGE407_I94@PURE_QUANTA.Q_CAP_DIFFBUS(CHIPS)':
 '1': CDS_PINID='\1\';
NODE_NAME     J107 K4
 '@T6G_MB_LIB.T6G(SCH_1):PAGE317_I49@PURE_QUANTA.CONN112_10137002101LF(CHIPS)':
 'K4': CDS_PINID='K4';
NET_NAME
'P5E_CPU0_P1_TX_BUF_C_DN<12>'
 '@T6G_MB_LIB.T6G(SCH_1):P5E_CPU0_P1_TX_BUF_C_DN'<12>:
 C_SIGNAL='@t6g_mb_lib.t6g(sch_1):p5e_cpu0_p1_tx_buf_c_dn(12)';
NODE_NAME     C6558 1
 '@T6G_MB_LIB.T6G(SCH_1):PAGE407_I92@PURE_QUANTA.Q_CAP_DIFFBUS(CHIPS)':
 '1': CDS_PINID='\1\';
NODE_NAME     J107 L5
 '@T6G_MB_LIB.T6G(SCH_1):PAGE317_I70@PURE_QUANTA.CONN112_10137002101LF(CHIPS)':
 'L5': CDS_PINID='L5';
NET_NAME
'P5E_CPU0_P1_TX_BUF_C_DN<13>'
 '@T6G_MB_LIB.T6G(SCH_1):P5E_CPU0_P1_TX_BUF_C_DN'<13>:
 C_SIGNAL='@t6g_mb_lib.t6g(sch_1):p5e_cpu0_p1_tx_buf_c_dn(13)';
NODE_NAME     C6560 1
 '@T6G_MB_LIB.T6G(SCH_1):PAGE407_I90@PURE_QUANTA.Q_CAP_DIFFBUS(CHIPS)':
 '1': CDS_PINID='\1\';
NODE_NAME     J107 K6
 '@T6G_MB_LIB.T6G(SCH_1):PAGE317_I70@PURE_QUANTA.CONN112_10137002101LF(CHIPS)':
 'K6': CDS_PINID='K6';
NET_NAME
'P5E_CPU0_P1_TX_BUF_C_DN<14>'
 '@T6G_MB_LIB.T6G(SCH_1):P5E_CPU0_P1_TX_BUF_C_DN'<14>:
 C_SIGNAL='@t6g_mb_lib.t6g(sch_1):p5e_cpu0_p1_tx_buf_c_dn(14)';
NODE_NAME     C6562 1
 '@T6G_MB_LIB.T6G(SCH_1):PAGE407_I88@PURE_QUANTA.Q_CAP_DIFFBUS(CHIPS)':
 '1': CDS_PINID='\1\';
NODE_NAME     J107 L7
 '@T6G_MB_LIB.T6G(SCH_1):PAGE317_I70@PURE_QUANTA.CONN112_10137002101LF(CHIPS)':
 'L7': CDS_PINID='L7';
NET_NAME
'P5E_CPU0_P1_TX_BUF_C_DN<15>'
 '@T6G_MB_LIB.T6G(SCH_1):P5E_CPU0_P1_TX_BUF_C_DN'<15>:
 C_SIGNAL='@t6g_mb_lib.t6g(sch_1):p5e_cpu0_p1_tx_buf_c_dn(15)';
NODE_NAME     C6564 1
 '@T6G_MB_LIB.T6G(SCH_1):PAGE407_I86@PURE_QUANTA.Q_CAP_DIFFBUS(CHIPS)':
 '1': CDS_PINID='\1\';
NODE_NAME     J107 K8
 '@T6G_MB_LIB.T6G(SCH_1):PAGE317_I70@PURE_QUANTA.CONN112_10137002101LF(CHIPS)':
 'K8': CDS_PINID='K8';
NET_NAME
'P5E_CPU0_P1_TX_BUF_C_DN<1>'
 '@T6G_MB_LIB.T6G(SCH_1):P5E_CPU0_P1_TX_BUF_C_DN'<1>:
 C_SIGNAL='@t6g_mb_lib.t6g(sch_1):p5e_cpu0_p1_tx_buf_c_dn(1)';
NODE_NAME     C6536 1
 '@T6G_MB_LIB.T6G(SCH_1):PAGE407_I44@PURE_QUANTA.Q_CAP_DIFFBUS(CHIPS)':
 '1': CDS_PINID='\1\';
NODE_NAME     J108 K2
 '@T6G_MB_LIB.T6G(SCH_1):PAGE320_I72@PURE_QUANTA.CONN112_10137002101LF(CHIPS)':
 'K2': CDS_PINID='K2';
NET_NAME
'P5E_CPU0_P1_TX_BUF_C_DN<2>'
 '@T6G_MB_LIB.T6G(SCH_1):P5E_CPU0_P1_TX_BUF_C_DN'<2>:
 C_SIGNAL='@t6g_mb_lib.t6g(sch_1):p5e_cpu0_p1_tx_buf_c_dn(2)';
NODE_NAME     C6538 1
 '@T6G_MB_LIB.T6G(SCH_1):PAGE407_I26@PURE_QUANTA.Q_CAP_DIFFBUS(CHIPS)':
 '1': CDS_PINID='\1\';
NODE_NAME     J108 L3
 '@T6G_MB_LIB.T6G(SCH_1):PAGE320_I72@PURE_QUANTA.CONN112_10137002101LF(CHIPS)':
 'L3': CDS_PINID='L3';
NET_NAME
'P5E_CPU0_P1_TX_BUF_C_DN<3>'
 '@T6G_MB_LIB.T6G(SCH_1):P5E_CPU0_P1_TX_BUF_C_DN'<3>:
 C_SIGNAL='@t6g_mb_lib.t6g(sch_1):p5e_cpu0_p1_tx_buf_c_dn(3)';
NODE_NAME     C6540 1
 '@T6G_MB_LIB.T6G(SCH_1):PAGE407_I24@PURE_QUANTA.Q_CAP_DIFFBUS(CHIPS)':
 '1': CDS_PINID='\1\';
NODE_NAME     J108 K4
 '@T6G_MB_LIB.T6G(SCH_1):PAGE320_I72@PURE_QUANTA.CONN112_10137002101LF(CHIPS)':
 'K4': CDS_PINID='K4';
NET_NAME
'P5E_CPU0_P1_TX_BUF_C_DN<4>'
 '@T6G_MB_LIB.T6G(SCH_1):P5E_CPU0_P1_TX_BUF_C_DN'<4>:
 C_SIGNAL='@t6g_mb_lib.t6g(sch_1):p5e_cpu0_p1_tx_buf_c_dn(4)';
NODE_NAME     C6542 1
 '@T6G_MB_LIB.T6G(SCH_1):PAGE407_I23@PURE_QUANTA.Q_CAP_DIFFBUS(CHIPS)':
 '1': CDS_PINID='\1\';
NODE_NAME     J108 L5
 '@T6G_MB_LIB.T6G(SCH_1):PAGE320_I15@PURE_QUANTA.CONN112_10137002101LF(CHIPS)':
 'L5': CDS_PINID='L5';
NET_NAME
'P5E_CPU0_P1_TX_BUF_C_DN<5>'
 '@T6G_MB_LIB.T6G(SCH_1):P5E_CPU0_P1_TX_BUF_C_DN'<5>:
 C_SIGNAL='@t6g_mb_lib.t6g(sch_1):p5e_cpu0_p1_tx_buf_c_dn(5)';
NODE_NAME     C6544 1
 '@T6G_MB_LIB.T6G(SCH_1):PAGE407_I21@PURE_QUANTA.Q_CAP_DIFFBUS(CHIPS)':
 '1': CDS_PINID='\1\';
NODE_NAME     J108 K6
 '@T6G_MB_LIB.T6G(SCH_1):PAGE320_I15@PURE_QUANTA.CONN112_10137002101LF(CHIPS)':
 'K6': CDS_PINID='K6';
NET_NAME
'P5E_CPU0_P1_TX_BUF_C_DN<6>'
 '@T6G_MB_LIB.T6G(SCH_1):P5E_CPU0_P1_TX_BUF_C_DN'<6>:
 C_SIGNAL='@t6g_mb_lib.t6g(sch_1):p5e_cpu0_p1_tx_buf_c_dn(6)';
NODE_NAME     C6546 1
 '@T6G_MB_LIB.T6G(SCH_1):PAGE407_I19@PURE_QUANTA.Q_CAP_DIFFBUS(CHIPS)':
 '1': CDS_PINID='\1\';
NODE_NAME     J108 L7
 '@T6G_MB_LIB.T6G(SCH_1):PAGE320_I15@PURE_QUANTA.CONN112_10137002101LF(CHIPS)':
 'L7': CDS_PINID='L7';
NET_NAME
'P5E_CPU0_P1_TX_BUF_C_DN<7>'
 '@T6G_MB_LIB.T6G(SCH_1):P5E_CPU0_P1_TX_BUF_C_DN'<7>:
 C_SIGNAL='@t6g_mb_lib.t6g(sch_1):p5e_cpu0_p1_tx_buf_c_dn(7)';
NODE_NAME     C6548 1
 '@T6G_MB_LIB.T6G(SCH_1):PAGE407_I15@PURE_QUANTA.Q_CAP_DIFFBUS(CHIPS)':
 '1': CDS_PINID='\1\';
NODE_NAME     J108 K8
 '@T6G_MB_LIB.T6G(SCH_1):PAGE320_I15@PURE_QUANTA.CONN112_10137002101LF(CHIPS)':
 'K8': CDS_PINID='K8';
NET_NAME
'P5E_CPU0_P1_TX_BUF_C_DN<8>'
 '@T6G_MB_LIB.T6G(SCH_1):P5E_CPU0_P1_TX_BUF_C_DN'<8>:
 C_SIGNAL='@t6g_mb_lib.t6g(sch_1):p5e_cpu0_p1_tx_buf_c_dn(8)';
NODE_NAME     C6550 1
 '@T6G_MB_LIB.T6G(SCH_1):PAGE407_I104@PURE_QUANTA.Q_CAP_DIFFBUS(CHIPS)':
 '1': CDS_PINID='\1\';
NODE_NAME     J107 L1
 '@T6G_MB_LIB.T6G(SCH_1):PAGE317_I49@PURE_QUANTA.CONN112_10137002101LF(CHIPS)':
 'L1': CDS_PINID='L1';
NET_NAME
'P5E_CPU0_P1_TX_BUF_C_DN<9>'
 '@T6G_MB_LIB.T6G(SCH_1):P5E_CPU0_P1_TX_BUF_C_DN'<9>:
 C_SIGNAL='@t6g_mb_lib.t6g(sch_1):p5e_cpu0_p1_tx_buf_c_dn(9)';
NODE_NAME     C6552 1
 '@T6G_MB_LIB.T6G(SCH_1):PAGE407_I103@PURE_QUANTA.Q_CAP_DIFFBUS(CHIPS)':
 '1': CDS_PINID='\1\';
NODE_NAME     J107 K2
 '@T6G_MB_LIB.T6G(SCH_1):PAGE317_I49@PURE_QUANTA.CONN112_10137002101LF(CHIPS)':
 'K2': CDS_PINID='K2';
NET_NAME
'P5E_CPU0_P1_TX_BUF_C_DP<0>'
 '@T6G_MB_LIB.T6G(SCH_1):P5E_CPU0_P1_TX_BUF_C_DP'<0>:
 C_SIGNAL='@t6g_mb_lib.t6g(sch_1):p5e_cpu0_p1_tx_buf_c_dp(0)';
NODE_NAME     C6533 1
 '@T6G_MB_LIB.T6G(SCH_1):PAGE407_I46@PURE_QUANTA.Q_CAP_DIFFBUS(CHIPS)':
 '1': CDS_PINID='\1\';
NODE_NAME     J108 M1
 '@T6G_MB_LIB.T6G(SCH_1):PAGE320_I72@PURE_QUANTA.CONN112_10137002101LF(CHIPS)':
 'M1': CDS_PINID='M1';
NET_NAME
'P5E_CPU0_P1_TX_BUF_C_DP<10>'
 '@T6G_MB_LIB.T6G(SCH_1):P5E_CPU0_P1_TX_BUF_C_DP'<10>:
 C_SIGNAL='@t6g_mb_lib.t6g(sch_1):p5e_cpu0_p1_tx_buf_c_dp(10)';
NODE_NAME     C6553 1
 '@T6G_MB_LIB.T6G(SCH_1):PAGE407_I96@PURE_QUANTA.Q_CAP_DIFFBUS(CHIPS)':
 '1': CDS_PINID='\1\';
NODE_NAME     J107 M3
 '@T6G_MB_LIB.T6G(SCH_1):PAGE317_I49@PURE_QUANTA.CONN112_10137002101LF(CHIPS)':
 'M3': CDS_PINID='M3';
NET_NAME
'P5E_CPU0_P1_TX_BUF_C_DP<11>'
 '@T6G_MB_LIB.T6G(SCH_1):P5E_CPU0_P1_TX_BUF_C_DP'<11>:
 C_SIGNAL='@t6g_mb_lib.t6g(sch_1):p5e_cpu0_p1_tx_buf_c_dp(11)';
NODE_NAME     C6555 1
 '@T6G_MB_LIB.T6G(SCH_1):PAGE407_I95@PURE_QUANTA.Q_CAP_DIFFBUS(CHIPS)':
 '1': CDS_PINID='\1\';
NODE_NAME     J107 L4
 '@T6G_MB_LIB.T6G(SCH_1):PAGE317_I49@PURE_QUANTA.CONN112_10137002101LF(CHIPS)':
 'L4': CDS_PINID='L4';
NET_NAME
'P5E_CPU0_P1_TX_BUF_C_DP<12>'
 '@T6G_MB_LIB.T6G(SCH_1):P5E_CPU0_P1_TX_BUF_C_DP'<12>:
 C_SIGNAL='@t6g_mb_lib.t6g(sch_1):p5e_cpu0_p1_tx_buf_c_dp(12)';
NODE_NAME     C6557 1
 '@T6G_MB_LIB.T6G(SCH_1):PAGE407_I93@PURE_QUANTA.Q_CAP_DIFFBUS(CHIPS)':
 '1': CDS_PINID='\1\';
NODE_NAME     J107 M5
 '@T6G_MB_LIB.T6G(SCH_1):PAGE317_I70@PURE_QUANTA.CONN112_10137002101LF(CHIPS)':
 'M5': CDS_PINID='M5';
NET_NAME
'P5E_CPU0_P1_TX_BUF_C_DP<13>'
 '@T6G_MB_LIB.T6G(SCH_1):P5E_CPU0_P1_TX_BUF_C_DP'<13>:
 C_SIGNAL='@t6g_mb_lib.t6g(sch_1):p5e_cpu0_p1_tx_buf_c_dp(13)';
NODE_NAME     C6559 1
 '@T6G_MB_LIB.T6G(SCH_1):PAGE407_I91@PURE_QUANTA.Q_CAP_DIFFBUS(CHIPS)':
 '1': CDS_PINID='\1\';
NODE_NAME     J107 L6
 '@T6G_MB_LIB.T6G(SCH_1):PAGE317_I70@PURE_QUANTA.CONN112_10137002101LF(CHIPS)':
 'L6': CDS_PINID='L6';
NET_NAME
'P5E_CPU0_P1_TX_BUF_C_DP<14>'
 '@T6G_MB_LIB.T6G(SCH_1):P5E_CPU0_P1_TX_BUF_C_DP'<14>:
 C_SIGNAL='@t6g_mb_lib.t6g(sch_1):p5e_cpu0_p1_tx_buf_c_dp(14)';
NODE_NAME     C6561 1
 '@T6G_MB_LIB.T6G(SCH_1):PAGE407_I89@PURE_QUANTA.Q_CAP_DIFFBUS(CHIPS)':
 '1': CDS_PINID='\1\';
NODE_NAME     J107 M7
 '@T6G_MB_LIB.T6G(SCH_1):PAGE317_I70@PURE_QUANTA.CONN112_10137002101LF(CHIPS)':
 'M7': CDS_PINID='M7';
NET_NAME
'P5E_CPU0_P1_TX_BUF_C_DP<15>'
 '@T6G_MB_LIB.T6G(SCH_1):P5E_CPU0_P1_TX_BUF_C_DP'<15>:
 C_SIGNAL='@t6g_mb_lib.t6g(sch_1):p5e_cpu0_p1_tx_buf_c_dp(15)';
NODE_NAME     C6563 1
 '@T6G_MB_LIB.T6G(SCH_1):PAGE407_I87@PURE_QUANTA.Q_CAP_DIFFBUS(CHIPS)':
 '1': CDS_PINID='\1\';
NODE_NAME     J107 L8
 '@T6G_MB_LIB.T6G(SCH_1):PAGE317_I70@PURE_QUANTA.CONN112_10137002101LF(CHIPS)':
 'L8': CDS_PINID='L8';
NET_NAME
'P5E_CPU0_P1_TX_BUF_C_DP<1>'
 '@T6G_MB_LIB.T6G(SCH_1):P5E_CPU0_P1_TX_BUF_C_DP'<1>:
 C_SIGNAL='@t6g_mb_lib.t6g(sch_1):p5e_cpu0_p1_tx_buf_c_dp(1)';
NODE_NAME     C6535 1
 '@T6G_MB_LIB.T6G(SCH_1):PAGE407_I45@PURE_QUANTA.Q_CAP_DIFFBUS(CHIPS)':
 '1': CDS_PINID='\1\';
NODE_NAME     J108 L2
 '@T6G_MB_LIB.T6G(SCH_1):PAGE320_I72@PURE_QUANTA.CONN112_10137002101LF(CHIPS)':
 'L2': CDS_PINID='L2';
NET_NAME
'P5E_CPU0_P1_TX_BUF_C_DP<2>'
 '@T6G_MB_LIB.T6G(SCH_1):P5E_CPU0_P1_TX_BUF_C_DP'<2>:
 C_SIGNAL='@t6g_mb_lib.t6g(sch_1):p5e_cpu0_p1_tx_buf_c_dp(2)';
NODE_NAME     C6537 1
 '@T6G_MB_LIB.T6G(SCH_1):PAGE407_I27@PURE_QUANTA.Q_CAP_DIFFBUS(CHIPS)':
 '1': CDS_PINID='\1\';
NODE_NAME     J108 M3
 '@T6G_MB_LIB.T6G(SCH_1):PAGE320_I72@PURE_QUANTA.CONN112_10137002101LF(CHIPS)':
 'M3': CDS_PINID='M3';
NET_NAME
'P5E_CPU0_P1_TX_BUF_C_DP<3>'
 '@T6G_MB_LIB.T6G(SCH_1):P5E_CPU0_P1_TX_BUF_C_DP'<3>:
 C_SIGNAL='@t6g_mb_lib.t6g(sch_1):p5e_cpu0_p1_tx_buf_c_dp(3)';
NODE_NAME     C6539 1
 '@T6G_MB_LIB.T6G(SCH_1):PAGE407_I25@PURE_QUANTA.Q_CAP_DIFFBUS(CHIPS)':
 '1': CDS_PINID='\1\';
NODE_NAME     J108 L4
 '@T6G_MB_LIB.T6G(SCH_1):PAGE320_I72@PURE_QUANTA.CONN112_10137002101LF(CHIPS)':
 'L4': CDS_PINID='L4';
NET_NAME
'P5E_CPU0_P1_TX_BUF_C_DP<4>'
 '@T6G_MB_LIB.T6G(SCH_1):P5E_CPU0_P1_TX_BUF_C_DP'<4>:
 C_SIGNAL='@t6g_mb_lib.t6g(sch_1):p5e_cpu0_p1_tx_buf_c_dp(4)';
NODE_NAME     C6541 1
 '@T6G_MB_LIB.T6G(SCH_1):PAGE407_I22@PURE_QUANTA.Q_CAP_DIFFBUS(CHIPS)':
 '1': CDS_PINID='\1\';
NODE_NAME     J108 M5
 '@T6G_MB_LIB.T6G(SCH_1):PAGE320_I15@PURE_QUANTA.CONN112_10137002101LF(CHIPS)':
 'M5': CDS_PINID='M5';
NET_NAME
'P5E_CPU0_P1_TX_BUF_C_DP<5>'
 '@T6G_MB_LIB.T6G(SCH_1):P5E_CPU0_P1_TX_BUF_C_DP'<5>:
 C_SIGNAL='@t6g_mb_lib.t6g(sch_1):p5e_cpu0_p1_tx_buf_c_dp(5)';
NODE_NAME     C6543 1
 '@T6G_MB_LIB.T6G(SCH_1):PAGE407_I20@PURE_QUANTA.Q_CAP_DIFFBUS(CHIPS)':
 '1': CDS_PINID='\1\';
NODE_NAME     J108 L6
 '@T6G_MB_LIB.T6G(SCH_1):PAGE320_I15@PURE_QUANTA.CONN112_10137002101LF(CHIPS)':
 'L6': CDS_PINID='L6';
NET_NAME
'P5E_CPU0_P1_TX_BUF_C_DP<6>'
 '@T6G_MB_LIB.T6G(SCH_1):P5E_CPU0_P1_TX_BUF_C_DP'<6>:
 C_SIGNAL='@t6g_mb_lib.t6g(sch_1):p5e_cpu0_p1_tx_buf_c_dp(6)';
NODE_NAME     C6545 1
 '@T6G_MB_LIB.T6G(SCH_1):PAGE407_I18@PURE_QUANTA.Q_CAP_DIFFBUS(CHIPS)':
 '1': CDS_PINID='\1\';
NODE_NAME     J108 M7
 '@T6G_MB_LIB.T6G(SCH_1):PAGE320_I15@PURE_QUANTA.CONN112_10137002101LF(CHIPS)':
 'M7': CDS_PINID='M7';
NET_NAME
'P5E_CPU0_P1_TX_BUF_C_DP<7>'
 '@T6G_MB_LIB.T6G(SCH_1):P5E_CPU0_P1_TX_BUF_C_DP'<7>:
 C_SIGNAL='@t6g_mb_lib.t6g(sch_1):p5e_cpu0_p1_tx_buf_c_dp(7)';
NODE_NAME     C6547 1
 '@T6G_MB_LIB.T6G(SCH_1):PAGE407_I16@PURE_QUANTA.Q_CAP_DIFFBUS(CHIPS)':
 '1': CDS_PINID='\1\';
NODE_NAME     J108 L8
 '@T6G_MB_LIB.T6G(SCH_1):PAGE320_I15@PURE_QUANTA.CONN112_10137002101LF(CHIPS)':
 'L8': CDS_PINID='L8';
NET_NAME
'P5E_CPU0_P1_TX_BUF_C_DP<8>'
 '@T6G_MB_LIB.T6G(SCH_1):P5E_CPU0_P1_TX_BUF_C_DP'<8>:
 C_SIGNAL='@t6g_mb_lib.t6g(sch_1):p5e_cpu0_p1_tx_buf_c_dp(8)';
NODE_NAME     C6549 1
 '@T6G_MB_LIB.T6G(SCH_1):PAGE407_I105@PURE_QUANTA.Q_CAP_DIFFBUS(CHIPS)':
 '1': CDS_PINID='\1\';
NODE_NAME     J107 M1
 '@T6G_MB_LIB.T6G(SCH_1):PAGE317_I49@PURE_QUANTA.CONN112_10137002101LF(CHIPS)':
 'M1': CDS_PINID='M1';
NET_NAME
'P5E_CPU0_P1_TX_BUF_C_DP<9>'
 '@T6G_MB_LIB.T6G(SCH_1):P5E_CPU0_P1_TX_BUF_C_DP'<9>:
 C_SIGNAL='@t6g_mb_lib.t6g(sch_1):p5e_cpu0_p1_tx_buf_c_dp(9)';
NODE_NAME     C6551 1
 '@T6G_MB_LIB.T6G(SCH_1):PAGE407_I102@PURE_QUANTA.Q_CAP_DIFFBUS(CHIPS)':
 '1': CDS_PINID='\1\';
NODE_NAME     J107 L2
 '@T6G_MB_LIB.T6G(SCH_1):PAGE317_I49@PURE_QUANTA.CONN112_10137002101LF(CHIPS)':
 'L2': CDS_PINID='L2';
NET_NAME
'P5E_CPU0_P1_TX_BUF_DN<0>'
 '@T6G_MB_LIB.T6G(SCH_1):P5E_CPU0_P1_TX_BUF_DN'<0>:
 C_SIGNAL='@t6g_mb_lib.t6g(sch_1):p5e_cpu0_p1_tx_buf_dn(0)';
NODE_NAME     C6534 2
 '@T6G_MB_LIB.T6G(SCH_1):PAGE407_I47@PURE_QUANTA.Q_CAP_DIFFBUS(CHIPS)':
 '2': CDS_PINID='\2\';
NODE_NAME     U6011 EW10
 '@T6G_MB_LIB.T6G(SCH_1):PAGE407_I142@PURE_QUANTA.PT5161LRS(CHIPS)':
 'B_PETN15': CDS_PINID='B_PETN15';
NET_NAME
'P5E_CPU0_P1_TX_BUF_DN<10>'
 '@T6G_MB_LIB.T6G(SCH_1):P5E_CPU0_P1_TX_BUF_DN'<10>:
 C_SIGNAL='@t6g_mb_lib.t6g(sch_1):p5e_cpu0_p1_tx_buf_dn(10)';
NODE_NAME     U6011 BJ10
 '@T6G_MB_LIB.T6G(SCH_1):PAGE407_I43@PURE_QUANTA.PT5161LRS(CHIPS)':
 'B_PETN5': CDS_PINID='B_PETN5';
NODE_NAME     C6554 2
 '@T6G_MB_LIB.T6G(SCH_1):PAGE407_I97@PURE_QUANTA.Q_CAP_DIFFBUS(CHIPS)':
 '2': CDS_PINID='\2\';
NET_NAME
'P5E_CPU0_P1_TX_BUF_DN<11>'
 '@T6G_MB_LIB.T6G(SCH_1):P5E_CPU0_P1_TX_BUF_DN'<11>:
 C_SIGNAL='@t6g_mb_lib.t6g(sch_1):p5e_cpu0_p1_tx_buf_dn(11)';
NODE_NAME     U6011 BB10
 '@T6G_MB_LIB.T6G(SCH_1):PAGE407_I43@PURE_QUANTA.PT5161LRS(CHIPS)':
 'B_PETN4': CDS_PINID='B_PETN4';
NODE_NAME     C6556 2
 '@T6G_MB_LIB.T6G(SCH_1):PAGE407_I94@PURE_QUANTA.Q_CAP_DIFFBUS(CHIPS)':
 '2': CDS_PINID='\2\';
NET_NAME
'P5E_CPU0_P1_TX_BUF_DN<12>'
 '@T6G_MB_LIB.T6G(SCH_1):P5E_CPU0_P1_TX_BUF_DN'<12>:
 C_SIGNAL='@t6g_mb_lib.t6g(sch_1):p5e_cpu0_p1_tx_buf_dn(12)';
NODE_NAME     U6011 AR10
 '@T6G_MB_LIB.T6G(SCH_1):PAGE407_I43@PURE_QUANTA.PT5161LRS(CHIPS)':
 'B_PETN3': CDS_PINID='B_PETN3';
NODE_NAME     C6558 2
 '@T6G_MB_LIB.T6G(SCH_1):PAGE407_I92@PURE_QUANTA.Q_CAP_DIFFBUS(CHIPS)':
 '2': CDS_PINID='\2\';
NET_NAME
'P5E_CPU0_P1_TX_BUF_DN<13>'
 '@T6G_MB_LIB.T6G(SCH_1):P5E_CPU0_P1_TX_BUF_DN'<13>:
 C_SIGNAL='@t6g_mb_lib.t6g(sch_1):p5e_cpu0_p1_tx_buf_dn(13)';
NODE_NAME     U6011 AH10
 '@T6G_MB_LIB.T6G(SCH_1):PAGE407_I43@PURE_QUANTA.PT5161LRS(CHIPS)':
 'B_PETN2': CDS_PINID='B_PETN2';
NODE_NAME     C6560 2
 '@T6G_MB_LIB.T6G(SCH_1):PAGE407_I90@PURE_QUANTA.Q_CAP_DIFFBUS(CHIPS)':
 '2': CDS_PINID='\2\';
NET_NAME
'P5E_CPU0_P1_TX_BUF_DN<14>'
 '@T6G_MB_LIB.T6G(SCH_1):P5E_CPU0_P1_TX_BUF_DN'<14>:
 C_SIGNAL='@t6g_mb_lib.t6g(sch_1):p5e_cpu0_p1_tx_buf_dn(14)';
NODE_NAME     U6011 AA10
 '@T6G_MB_LIB.T6G(SCH_1):PAGE407_I43@PURE_QUANTA.PT5161LRS(CHIPS)':
 'B_PETN1': CDS_PINID='B_PETN1';
NODE_NAME     C6562 2
 '@T6G_MB_LIB.T6G(SCH_1):PAGE407_I88@PURE_QUANTA.Q_CAP_DIFFBUS(CHIPS)':
 '2': CDS_PINID='\2\';
NET_NAME
'P5E_CPU0_P1_TX_BUF_DN<15>'
 '@T6G_MB_LIB.T6G(SCH_1):P5E_CPU0_P1_TX_BUF_DN'<15>:
 C_SIGNAL='@t6g_mb_lib.t6g(sch_1):p5e_cpu0_p1_tx_buf_dn(15)';
NODE_NAME     U6011 P10
 '@T6G_MB_LIB.T6G(SCH_1):PAGE407_I43@PURE_QUANTA.PT5161LRS(CHIPS)':
 'B_PETN0': CDS_PINID='B_PETN0';
NODE_NAME     C6564 2
 '@T6G_MB_LIB.T6G(SCH_1):PAGE407_I86@PURE_QUANTA.Q_CAP_DIFFBUS(CHIPS)':
 '2': CDS_PINID='\2\';
NET_NAME
'P5E_CPU0_P1_TX_BUF_DN<1>'
 '@T6G_MB_LIB.T6G(SCH_1):P5E_CPU0_P1_TX_BUF_DN'<1>:
 C_SIGNAL='@t6g_mb_lib.t6g(sch_1):p5e_cpu0_p1_tx_buf_dn(1)';
NODE_NAME     C6536 2
 '@T6G_MB_LIB.T6G(SCH_1):PAGE407_I44@PURE_QUANTA.Q_CAP_DIFFBUS(CHIPS)':
 '2': CDS_PINID='\2\';
NODE_NAME     U6011 EM10
 '@T6G_MB_LIB.T6G(SCH_1):PAGE407_I142@PURE_QUANTA.PT5161LRS(CHIPS)':
 'B_PETN14': CDS_PINID='B_PETN14';
NET_NAME
'P5E_CPU0_P1_TX_BUF_DN<2>'
 '@T6G_MB_LIB.T6G(SCH_1):P5E_CPU0_P1_TX_BUF_DN'<2>:
 C_SIGNAL='@t6g_mb_lib.t6g(sch_1):p5e_cpu0_p1_tx_buf_dn(2)';
NODE_NAME     C6538 2
 '@T6G_MB_LIB.T6G(SCH_1):PAGE407_I26@PURE_QUANTA.Q_CAP_DIFFBUS(CHIPS)':
 '2': CDS_PINID='\2\';
NODE_NAME     U6011 EE10
 '@T6G_MB_LIB.T6G(SCH_1):PAGE407_I142@PURE_QUANTA.PT5161LRS(CHIPS)':
 'B_PETN13': CDS_PINID='B_PETN13';
NET_NAME
'P5E_CPU0_P1_TX_BUF_DN<3>'
 '@T6G_MB_LIB.T6G(SCH_1):P5E_CPU0_P1_TX_BUF_DN'<3>:
 C_SIGNAL='@t6g_mb_lib.t6g(sch_1):p5e_cpu0_p1_tx_buf_dn(3)';
NODE_NAME     C6540 2
 '@T6G_MB_LIB.T6G(SCH_1):PAGE407_I24@PURE_QUANTA.Q_CAP_DIFFBUS(CHIPS)':
 '2': CDS_PINID='\2\';
NODE_NAME     U6011 DV10
 '@T6G_MB_LIB.T6G(SCH_1):PAGE407_I142@PURE_QUANTA.PT5161LRS(CHIPS)':
 'B_PETN12': CDS_PINID='B_PETN12';
NET_NAME
'P5E_CPU0_P1_TX_BUF_DN<4>'
 '@T6G_MB_LIB.T6G(SCH_1):P5E_CPU0_P1_TX_BUF_DN'<4>:
 C_SIGNAL='@t6g_mb_lib.t6g(sch_1):p5e_cpu0_p1_tx_buf_dn(4)';
NODE_NAME     C6542 2
 '@T6G_MB_LIB.T6G(SCH_1):PAGE407_I23@PURE_QUANTA.Q_CAP_DIFFBUS(CHIPS)':
 '2': CDS_PINID='\2\';
NODE_NAME     U6011 DL10
 '@T6G_MB_LIB.T6G(SCH_1):PAGE407_I142@PURE_QUANTA.PT5161LRS(CHIPS)':
 'B_PETN11': CDS_PINID='B_PETN11';
NET_NAME
'P5E_CPU0_P1_TX_BUF_DN<5>'
 '@T6G_MB_LIB.T6G(SCH_1):P5E_CPU0_P1_TX_BUF_DN'<5>:
 C_SIGNAL='@t6g_mb_lib.t6g(sch_1):p5e_cpu0_p1_tx_buf_dn(5)';
NODE_NAME     C6544 2
 '@T6G_MB_LIB.T6G(SCH_1):PAGE407_I21@PURE_QUANTA.Q_CAP_DIFFBUS(CHIPS)':
 '2': CDS_PINID='\2\';
NODE_NAME     U6011 DD10
 '@T6G_MB_LIB.T6G(SCH_1):PAGE407_I142@PURE_QUANTA.PT5161LRS(CHIPS)':
 'B_PETN10': CDS_PINID='B_PETN10';
NET_NAME
'P5E_CPU0_P1_TX_BUF_DN<6>'
 '@T6G_MB_LIB.T6G(SCH_1):P5E_CPU0_P1_TX_BUF_DN'<6>:
 C_SIGNAL='@t6g_mb_lib.t6g(sch_1):p5e_cpu0_p1_tx_buf_dn(6)';
NODE_NAME     C6546 2
 '@T6G_MB_LIB.T6G(SCH_1):PAGE407_I19@PURE_QUANTA.Q_CAP_DIFFBUS(CHIPS)':
 '2': CDS_PINID='\2\';
NODE_NAME     U6011 CU10
 '@T6G_MB_LIB.T6G(SCH_1):PAGE407_I142@PURE_QUANTA.PT5161LRS(CHIPS)':
 'B_PETN9': CDS_PINID='B_PETN9';
NET_NAME
'P5E_CPU0_P1_TX_BUF_DN<7>'
 '@T6G_MB_LIB.T6G(SCH_1):P5E_CPU0_P1_TX_BUF_DN'<7>:
 C_SIGNAL='@t6g_mb_lib.t6g(sch_1):p5e_cpu0_p1_tx_buf_dn(7)';
NODE_NAME     C6548 2
 '@T6G_MB_LIB.T6G(SCH_1):PAGE407_I15@PURE_QUANTA.Q_CAP_DIFFBUS(CHIPS)':
 '2': CDS_PINID='\2\';
NODE_NAME     U6011 CK10
 '@T6G_MB_LIB.T6G(SCH_1):PAGE407_I142@PURE_QUANTA.PT5161LRS(CHIPS)':
 'B_PETN8': CDS_PINID='B_PETN8';
NET_NAME
'P5E_CPU0_P1_TX_BUF_DN<8>'
 '@T6G_MB_LIB.T6G(SCH_1):P5E_CPU0_P1_TX_BUF_DN'<8>:
 C_SIGNAL='@t6g_mb_lib.t6g(sch_1):p5e_cpu0_p1_tx_buf_dn(8)';
NODE_NAME     U6011 CC10
 '@T6G_MB_LIB.T6G(SCH_1):PAGE407_I43@PURE_QUANTA.PT5161LRS(CHIPS)':
 'B_PETN7': CDS_PINID='B_PETN7';
NODE_NAME     C6550 2
 '@T6G_MB_LIB.T6G(SCH_1):PAGE407_I104@PURE_QUANTA.Q_CAP_DIFFBUS(CHIPS)':
 '2': CDS_PINID='\2\';
NET_NAME
'P5E_CPU0_P1_TX_BUF_DN<9>'
 '@T6G_MB_LIB.T6G(SCH_1):P5E_CPU0_P1_TX_BUF_DN'<9>:
 C_SIGNAL='@t6g_mb_lib.t6g(sch_1):p5e_cpu0_p1_tx_buf_dn(9)';
NODE_NAME     U6011 BT10
 '@T6G_MB_LIB.T6G(SCH_1):PAGE407_I43@PURE_QUANTA.PT5161LRS(CHIPS)':
 'B_PETN6': CDS_PINID='B_PETN6';
NODE_NAME     C6552 2
 '@T6G_MB_LIB.T6G(SCH_1):PAGE407_I103@PURE_QUANTA.Q_CAP_DIFFBUS(CHIPS)':
 '2': CDS_PINID='\2\';
NET_NAME
'P5E_CPU0_P1_TX_BUF_DP<0>'
 '@T6G_MB_LIB.T6G(SCH_1):P5E_CPU0_P1_TX_BUF_DP'<0>:
 C_SIGNAL='@t6g_mb_lib.t6g(sch_1):p5e_cpu0_p1_tx_buf_dp(0)';
NODE_NAME     C6533 2
 '@T6G_MB_LIB.T6G(SCH_1):PAGE407_I46@PURE_QUANTA.Q_CAP_DIFFBUS(CHIPS)':
 '2': CDS_PINID='\2\';
NODE_NAME     U6011 EU7
 '@T6G_MB_LIB.T6G(SCH_1):PAGE407_I142@PURE_QUANTA.PT5161LRS(CHIPS)':
 'B_PETP15': CDS_PINID='B_PETP15';
NET_NAME
'P5E_CPU0_P1_TX_BUF_DP<10>'
 '@T6G_MB_LIB.T6G(SCH_1):P5E_CPU0_P1_TX_BUF_DP'<10>:
 C_SIGNAL='@t6g_mb_lib.t6g(sch_1):p5e_cpu0_p1_tx_buf_dp(10)';
NODE_NAME     U6011 BG7
 '@T6G_MB_LIB.T6G(SCH_1):PAGE407_I43@PURE_QUANTA.PT5161LRS(CHIPS)':
 'B_PETP5': CDS_PINID='B_PETP5';
NODE_NAME     C6553 2
 '@T6G_MB_LIB.T6G(SCH_1):PAGE407_I96@PURE_QUANTA.Q_CAP_DIFFBUS(CHIPS)':
 '2': CDS_PINID='\2\';
NET_NAME
'P5E_CPU0_P1_TX_BUF_DP<11>'
 '@T6G_MB_LIB.T6G(SCH_1):P5E_CPU0_P1_TX_BUF_DP'<11>:
 C_SIGNAL='@t6g_mb_lib.t6g(sch_1):p5e_cpu0_p1_tx_buf_dp(11)';
NODE_NAME     U6011 AY7
 '@T6G_MB_LIB.T6G(SCH_1):PAGE407_I43@PURE_QUANTA.PT5161LRS(CHIPS)':
 'B_PETP4': CDS_PINID='B_PETP4';
NODE_NAME     C6555 2
 '@T6G_MB_LIB.T6G(SCH_1):PAGE407_I95@PURE_QUANTA.Q_CAP_DIFFBUS(CHIPS)':
 '2': CDS_PINID='\2\';
NET_NAME
'P5E_CPU0_P1_TX_BUF_DP<12>'
 '@T6G_MB_LIB.T6G(SCH_1):P5E_CPU0_P1_TX_BUF_DP'<12>:
 C_SIGNAL='@t6g_mb_lib.t6g(sch_1):p5e_cpu0_p1_tx_buf_dp(12)';
NODE_NAME     U6011 AN7
 '@T6G_MB_LIB.T6G(SCH_1):PAGE407_I43@PURE_QUANTA.PT5161LRS(CHIPS)':
 'B_PETP3': CDS_PINID='B_PETP3';
NODE_NAME     C6557 2
 '@T6G_MB_LIB.T6G(SCH_1):PAGE407_I93@PURE_QUANTA.Q_CAP_DIFFBUS(CHIPS)':
 '2': CDS_PINID='\2\';
NET_NAME
'P5E_CPU0_P1_TX_BUF_DP<13>'
 '@T6G_MB_LIB.T6G(SCH_1):P5E_CPU0_P1_TX_BUF_DP'<13>:
 C_SIGNAL='@t6g_mb_lib.t6g(sch_1):p5e_cpu0_p1_tx_buf_dp(13)';
NODE_NAME     U6011 AF7
 '@T6G_MB_LIB.T6G(SCH_1):PAGE407_I43@PURE_QUANTA.PT5161LRS(CHIPS)':
 'B_PETP2': CDS_PINID='B_PETP2';
NODE_NAME     C6559 2
 '@T6G_MB_LIB.T6G(SCH_1):PAGE407_I91@PURE_QUANTA.Q_CAP_DIFFBUS(CHIPS)':
 '2': CDS_PINID='\2\';
NET_NAME
'P5E_CPU0_P1_TX_BUF_DP<14>'
 '@T6G_MB_LIB.T6G(SCH_1):P5E_CPU0_P1_TX_BUF_DP'<14>:
 C_SIGNAL='@t6g_mb_lib.t6g(sch_1):p5e_cpu0_p1_tx_buf_dp(14)';
NODE_NAME     U6011 W7
 '@T6G_MB_LIB.T6G(SCH_1):PAGE407_I43@PURE_QUANTA.PT5161LRS(CHIPS)':
 'B_PETP1': CDS_PINID='B_PETP1';
NODE_NAME     C6561 2
 '@T6G_MB_LIB.T6G(SCH_1):PAGE407_I89@PURE_QUANTA.Q_CAP_DIFFBUS(CHIPS)':
 '2': CDS_PINID='\2\';
NET_NAME
'P5E_CPU0_P1_TX_BUF_DP<15>'
 '@T6G_MB_LIB.T6G(SCH_1):P5E_CPU0_P1_TX_BUF_DP'<15>:
 C_SIGNAL='@t6g_mb_lib.t6g(sch_1):p5e_cpu0_p1_tx_buf_dp(15)';
NODE_NAME     U6011 M7
 '@T6G_MB_LIB.T6G(SCH_1):PAGE407_I43@PURE_QUANTA.PT5161LRS(CHIPS)':
 'B_PETP0': CDS_PINID='B_PETP0';
NODE_NAME     C6563 2
 '@T6G_MB_LIB.T6G(SCH_1):PAGE407_I87@PURE_QUANTA.Q_CAP_DIFFBUS(CHIPS)':
 '2': CDS_PINID='\2\';
NET_NAME
'P5E_CPU0_P1_TX_BUF_DP<1>'
 '@T6G_MB_LIB.T6G(SCH_1):P5E_CPU0_P1_TX_BUF_DP'<1>:
 C_SIGNAL='@t6g_mb_lib.t6g(sch_1):p5e_cpu0_p1_tx_buf_dp(1)';
NODE_NAME     C6535 2
 '@T6G_MB_LIB.T6G(SCH_1):PAGE407_I45@PURE_QUANTA.Q_CAP_DIFFBUS(CHIPS)':
 '2': CDS_PINID='\2\';
NODE_NAME     U6011 EK7
 '@T6G_MB_LIB.T6G(SCH_1):PAGE407_I142@PURE_QUANTA.PT5161LRS(CHIPS)':
 'B_PETP14': CDS_PINID='B_PETP14';
NET_NAME
'P5E_CPU0_P1_TX_BUF_DP<2>'
 '@T6G_MB_LIB.T6G(SCH_1):P5E_CPU0_P1_TX_BUF_DP'<2>:
 C_SIGNAL='@t6g_mb_lib.t6g(sch_1):p5e_cpu0_p1_tx_buf_dp(2)';
NODE_NAME     C6537 2
 '@T6G_MB_LIB.T6G(SCH_1):PAGE407_I27@PURE_QUANTA.Q_CAP_DIFFBUS(CHIPS)':
 '2': CDS_PINID='\2\';
NODE_NAME     U6011 EC7
 '@T6G_MB_LIB.T6G(SCH_1):PAGE407_I142@PURE_QUANTA.PT5161LRS(CHIPS)':
 'B_PETP13': CDS_PINID='B_PETP13';
NET_NAME
'P5E_CPU0_P1_TX_BUF_DP<3>'
 '@T6G_MB_LIB.T6G(SCH_1):P5E_CPU0_P1_TX_BUF_DP'<3>:
 C_SIGNAL='@t6g_mb_lib.t6g(sch_1):p5e_cpu0_p1_tx_buf_dp(3)';
NODE_NAME     C6539 2
 '@T6G_MB_LIB.T6G(SCH_1):PAGE407_I25@PURE_QUANTA.Q_CAP_DIFFBUS(CHIPS)':
 '2': CDS_PINID='\2\';
NODE_NAME     U6011 DT7
 '@T6G_MB_LIB.T6G(SCH_1):PAGE407_I142@PURE_QUANTA.PT5161LRS(CHIPS)':
 'B_PETP12': CDS_PINID='B_PETP12';
NET_NAME
'P5E_CPU0_P1_TX_BUF_DP<4>'
 '@T6G_MB_LIB.T6G(SCH_1):P5E_CPU0_P1_TX_BUF_DP'<4>:
 C_SIGNAL='@t6g_mb_lib.t6g(sch_1):p5e_cpu0_p1_tx_buf_dp(4)';
NODE_NAME     C6541 2
 '@T6G_MB_LIB.T6G(SCH_1):PAGE407_I22@PURE_QUANTA.Q_CAP_DIFFBUS(CHIPS)':
 '2': CDS_PINID='\2\';
NODE_NAME     U6011 DJ7
 '@T6G_MB_LIB.T6G(SCH_1):PAGE407_I142@PURE_QUANTA.PT5161LRS(CHIPS)':
 'B_PETP11': CDS_PINID='B_PETP11';
NET_NAME
'P5E_CPU0_P1_TX_BUF_DP<5>'
 '@T6G_MB_LIB.T6G(SCH_1):P5E_CPU0_P1_TX_BUF_DP'<5>:
 C_SIGNAL='@t6g_mb_lib.t6g(sch_1):p5e_cpu0_p1_tx_buf_dp(5)';
NODE_NAME     C6543 2
 '@T6G_MB_LIB.T6G(SCH_1):PAGE407_I20@PURE_QUANTA.Q_CAP_DIFFBUS(CHIPS)':
 '2': CDS_PINID='\2\';
NODE_NAME     U6011 DB7
 '@T6G_MB_LIB.T6G(SCH_1):PAGE407_I142@PURE_QUANTA.PT5161LRS(CHIPS)':
 'B_PETP10': CDS_PINID='B_PETP10';
NET_NAME
'P5E_CPU0_P1_TX_BUF_DP<6>'
 '@T6G_MB_LIB.T6G(SCH_1):P5E_CPU0_P1_TX_BUF_DP'<6>:
 C_SIGNAL='@t6g_mb_lib.t6g(sch_1):p5e_cpu0_p1_tx_buf_dp(6)';
NODE_NAME     C6545 2
 '@T6G_MB_LIB.T6G(SCH_1):PAGE407_I18@PURE_QUANTA.Q_CAP_DIFFBUS(CHIPS)':
 '2': CDS_PINID='\2\';
NODE_NAME     U6011 CR7
 '@T6G_MB_LIB.T6G(SCH_1):PAGE407_I142@PURE_QUANTA.PT5161LRS(CHIPS)':
 'B_PETP9': CDS_PINID='B_PETP9';
NET_NAME
'P5E_CPU0_P1_TX_BUF_DP<7>'
 '@T6G_MB_LIB.T6G(SCH_1):P5E_CPU0_P1_TX_BUF_DP'<7>:
 C_SIGNAL='@t6g_mb_lib.t6g(sch_1):p5e_cpu0_p1_tx_buf_dp(7)';
NODE_NAME     C6547 2
 '@T6G_MB_LIB.T6G(SCH_1):PAGE407_I16@PURE_QUANTA.Q_CAP_DIFFBUS(CHIPS)':
 '2': CDS_PINID='\2\';
NODE_NAME     U6011 CH7
 '@T6G_MB_LIB.T6G(SCH_1):PAGE407_I142@PURE_QUANTA.PT5161LRS(CHIPS)':
 'B_PETP8': CDS_PINID='B_PETP8';
NET_NAME
'P5E_CPU0_P1_TX_BUF_DP<8>'
 '@T6G_MB_LIB.T6G(SCH_1):P5E_CPU0_P1_TX_BUF_DP'<8>:
 C_SIGNAL='@t6g_mb_lib.t6g(sch_1):p5e_cpu0_p1_tx_buf_dp(8)';
NODE_NAME     U6011 CA7
 '@T6G_MB_LIB.T6G(SCH_1):PAGE407_I43@PURE_QUANTA.PT5161LRS(CHIPS)':
 'B_PETP7': CDS_PINID='B_PETP7';
NODE_NAME     C6549 2
 '@T6G_MB_LIB.T6G(SCH_1):PAGE407_I105@PURE_QUANTA.Q_CAP_DIFFBUS(CHIPS)':
 '2': CDS_PINID='\2\';
NET_NAME
'P5E_CPU0_P1_TX_BUF_DP<9>'
 '@T6G_MB_LIB.T6G(SCH_1):P5E_CPU0_P1_TX_BUF_DP'<9>:
 C_SIGNAL='@t6g_mb_lib.t6g(sch_1):p5e_cpu0_p1_tx_buf_dp(9)';
NODE_NAME     U6011 BP7
 '@T6G_MB_LIB.T6G(SCH_1):PAGE407_I43@PURE_QUANTA.PT5161LRS(CHIPS)':
 'B_PETP6': CDS_PINID='B_PETP6';
NODE_NAME     C6551 2
 '@T6G_MB_LIB.T6G(SCH_1):PAGE407_I102@PURE_QUANTA.Q_CAP_DIFFBUS(CHIPS)':
 '2': CDS_PINID='\2\';
NET_NAME
'P5E_CPU0_P1_TX_C_DN<0>'
 '@T6G_MB_LIB.T6G(SCH_1):P5E_CPU0_P1_TX_C_DN'<0>:
 C_SIGNAL='@t6g_mb_lib.t6g(sch_1):p5e_cpu0_p1_tx_c_dn(0)';
NODE_NAME     C964 1
 '@T6G_MB_LIB.T6G(SCH_1):PAGE351_I122@PURE_QUANTA.Q_CAP_DIFFBUS(CHIPS)':
 '1': CDS_PINID='\1\';
NODE_NAME     U6011 EV34
 '@T6G_MB_LIB.T6G(SCH_1):PAGE404_I38@PURE_QUANTA.PT5161LRS(CHIPS)':
 'B_PERP15': CDS_PINID='B_PERP15';
NET_NAME
'P5E_CPU0_P1_TX_C_DN<10>'
 '@T6G_MB_LIB.T6G(SCH_1):P5E_CPU0_P1_TX_C_DN'<10>:
 C_SIGNAL='@t6g_mb_lib.t6g(sch_1):p5e_cpu0_p1_tx_c_dn(10)';
NODE_NAME     C944 1
 '@T6G_MB_LIB.T6G(SCH_1):PAGE351_I156@PURE_QUANTA.Q_CAP_DIFFBUS(CHIPS)':
 '1': CDS_PINID='\1\';
NODE_NAME     U6011 BH34
 '@T6G_MB_LIB.T6G(SCH_1):PAGE404_I1@PURE_QUANTA.PT5161LRS(CHIPS)':
 'B_PERP5': CDS_PINID='B_PERP5';
NET_NAME
'P5E_CPU0_P1_TX_C_DN<11>'
 '@T6G_MB_LIB.T6G(SCH_1):P5E_CPU0_P1_TX_C_DN'<11>:
 C_SIGNAL='@t6g_mb_lib.t6g(sch_1):p5e_cpu0_p1_tx_c_dn(11)';
NODE_NAME     C942 1
 '@T6G_MB_LIB.T6G(SCH_1):PAGE351_I158@PURE_QUANTA.Q_CAP_DIFFBUS(CHIPS)':
 '1': CDS_PINID='\1\';
NODE_NAME     U6011 BA34
 '@T6G_MB_LIB.T6G(SCH_1):PAGE404_I1@PURE_QUANTA.PT5161LRS(CHIPS)':
 'B_PERP4': CDS_PINID='B_PERP4';
NET_NAME
'P5E_CPU0_P1_TX_C_DN<12>'
 '@T6G_MB_LIB.T6G(SCH_1):P5E_CPU0_P1_TX_C_DN'<12>:
 C_SIGNAL='@t6g_mb_lib.t6g(sch_1):p5e_cpu0_p1_tx_c_dn(12)';
NODE_NAME     C940 1
 '@T6G_MB_LIB.T6G(SCH_1):PAGE351_I160@PURE_QUANTA.Q_CAP_DIFFBUS(CHIPS)':
 '1': CDS_PINID='\1\';
NODE_NAME     U6011 AP34
 '@T6G_MB_LIB.T6G(SCH_1):PAGE404_I1@PURE_QUANTA.PT5161LRS(CHIPS)':
 'B_PERP3': CDS_PINID='B_PERP3';
NET_NAME
'P5E_CPU0_P1_TX_C_DN<13>'
 '@T6G_MB_LIB.T6G(SCH_1):P5E_CPU0_P1_TX_C_DN'<13>:
 C_SIGNAL='@t6g_mb_lib.t6g(sch_1):p5e_cpu0_p1_tx_c_dn(13)';
NODE_NAME     C938 1
 '@T6G_MB_LIB.T6G(SCH_1):PAGE351_I165@PURE_QUANTA.Q_CAP_DIFFBUS(CHIPS)':
 '1': CDS_PINID='\1\';
NODE_NAME     U6011 AG34
 '@T6G_MB_LIB.T6G(SCH_1):PAGE404_I1@PURE_QUANTA.PT5161LRS(CHIPS)':
 'B_PERP2': CDS_PINID='B_PERP2';
NET_NAME
'P5E_CPU0_P1_TX_C_DN<14>'
 '@T6G_MB_LIB.T6G(SCH_1):P5E_CPU0_P1_TX_C_DN'<14>:
 C_SIGNAL='@t6g_mb_lib.t6g(sch_1):p5e_cpu0_p1_tx_c_dn(14)';
NODE_NAME     C936 1
 '@T6G_MB_LIB.T6G(SCH_1):PAGE351_I167@PURE_QUANTA.Q_CAP_DIFFBUS(CHIPS)':
 '1': CDS_PINID='\1\';
NODE_NAME     U6011 AB35
 '@T6G_MB_LIB.T6G(SCH_1):PAGE404_I1@PURE_QUANTA.PT5161LRS(CHIPS)':
 'B_PERN1': CDS_PINID='B_PERN1';
NET_NAME
'P5E_CPU0_P1_TX_C_DN<15>'
 '@T6G_MB_LIB.T6G(SCH_1):P5E_CPU0_P1_TX_C_DN'<15>:
 C_SIGNAL='@t6g_mb_lib.t6g(sch_1):p5e_cpu0_p1_tx_c_dn(15)';
NODE_NAME     C934 1
 '@T6G_MB_LIB.T6G(SCH_1):PAGE351_I169@PURE_QUANTA.Q_CAP_DIFFBUS(CHIPS)':
 '1': CDS_PINID='\1\';
NODE_NAME     U6011 N34
 '@T6G_MB_LIB.T6G(SCH_1):PAGE404_I1@PURE_QUANTA.PT5161LRS(CHIPS)':
 'B_PERP0': CDS_PINID='B_PERP0';
NET_NAME
'P5E_CPU0_P1_TX_C_DN<1>'
 '@T6G_MB_LIB.T6G(SCH_1):P5E_CPU0_P1_TX_C_DN'<1>:
 C_SIGNAL='@t6g_mb_lib.t6g(sch_1):p5e_cpu0_p1_tx_c_dn(1)';
NODE_NAME     C962 1
 '@T6G_MB_LIB.T6G(SCH_1):PAGE351_I124@PURE_QUANTA.Q_CAP_DIFFBUS(CHIPS)':
 '1': CDS_PINID='\1\';
NODE_NAME     U6011 EN35
 '@T6G_MB_LIB.T6G(SCH_1):PAGE404_I38@PURE_QUANTA.PT5161LRS(CHIPS)':
 'B_PERN14': CDS_PINID='B_PERN14';
NET_NAME
'P5E_CPU0_P1_TX_C_DN<2>'
 '@T6G_MB_LIB.T6G(SCH_1):P5E_CPU0_P1_TX_C_DN'<2>:
 C_SIGNAL='@t6g_mb_lib.t6g(sch_1):p5e_cpu0_p1_tx_c_dn(2)';
NODE_NAME     C960 1
 '@T6G_MB_LIB.T6G(SCH_1):PAGE351_I126@PURE_QUANTA.Q_CAP_DIFFBUS(CHIPS)':
 '1': CDS_PINID='\1\';
NODE_NAME     U6011 ED34
 '@T6G_MB_LIB.T6G(SCH_1):PAGE404_I38@PURE_QUANTA.PT5161LRS(CHIPS)':
 'B_PERP13': CDS_PINID='B_PERP13';
NET_NAME
'P5E_CPU0_P1_TX_C_DN<3>'
 '@T6G_MB_LIB.T6G(SCH_1):P5E_CPU0_P1_TX_C_DN'<3>:
 C_SIGNAL='@t6g_mb_lib.t6g(sch_1):p5e_cpu0_p1_tx_c_dn(3)';
NODE_NAME     C958 1
 '@T6G_MB_LIB.T6G(SCH_1):PAGE351_I128@PURE_QUANTA.Q_CAP_DIFFBUS(CHIPS)':
 '1': CDS_PINID='\1\';
NODE_NAME     U6011 DU34
 '@T6G_MB_LIB.T6G(SCH_1):PAGE404_I38@PURE_QUANTA.PT5161LRS(CHIPS)':
 'B_PERP12': CDS_PINID='B_PERP12';
NET_NAME
'P5E_CPU0_P1_TX_C_DN<4>'
 '@T6G_MB_LIB.T6G(SCH_1):P5E_CPU0_P1_TX_C_DN'<4>:
 C_SIGNAL='@t6g_mb_lib.t6g(sch_1):p5e_cpu0_p1_tx_c_dn(4)';
NODE_NAME     C956 1
 '@T6G_MB_LIB.T6G(SCH_1):PAGE351_I207@PURE_QUANTA.Q_CAP_DIFFBUS(CHIPS)':
 '1': CDS_PINID='\1\';
NODE_NAME     U6011 DK34
 '@T6G_MB_LIB.T6G(SCH_1):PAGE404_I38@PURE_QUANTA.PT5161LRS(CHIPS)':
 'B_PERP11': CDS_PINID='B_PERP11';
NET_NAME
'P5E_CPU0_P1_TX_C_DN<5>'
 '@T6G_MB_LIB.T6G(SCH_1):P5E_CPU0_P1_TX_C_DN'<5>:
 C_SIGNAL='@t6g_mb_lib.t6g(sch_1):p5e_cpu0_p1_tx_c_dn(5)';
NODE_NAME     C954 1
 '@T6G_MB_LIB.T6G(SCH_1):PAGE351_I133@PURE_QUANTA.Q_CAP_DIFFBUS(CHIPS)':
 '1': CDS_PINID='\1\';
NODE_NAME     U6011 DC34
 '@T6G_MB_LIB.T6G(SCH_1):PAGE404_I38@PURE_QUANTA.PT5161LRS(CHIPS)':
 'B_PERP10': CDS_PINID='B_PERP10';
NET_NAME
'P5E_CPU0_P1_TX_C_DN<6>'
 '@T6G_MB_LIB.T6G(SCH_1):P5E_CPU0_P1_TX_C_DN'<6>:
 C_SIGNAL='@t6g_mb_lib.t6g(sch_1):p5e_cpu0_p1_tx_c_dn(6)';
NODE_NAME     C952 1
 '@T6G_MB_LIB.T6G(SCH_1):PAGE351_I135@PURE_QUANTA.Q_CAP_DIFFBUS(CHIPS)':
 '1': CDS_PINID='\1\';
NODE_NAME     U6011 CT34
 '@T6G_MB_LIB.T6G(SCH_1):PAGE404_I38@PURE_QUANTA.PT5161LRS(CHIPS)':
 'B_PERP9': CDS_PINID='B_PERP9';
NET_NAME
'P5E_CPU0_P1_TX_C_DN<7>'
 '@T6G_MB_LIB.T6G(SCH_1):P5E_CPU0_P1_TX_C_DN'<7>:
 C_SIGNAL='@t6g_mb_lib.t6g(sch_1):p5e_cpu0_p1_tx_c_dn(7)';
NODE_NAME     C950 1
 '@T6G_MB_LIB.T6G(SCH_1):PAGE351_I137@PURE_QUANTA.Q_CAP_DIFFBUS(CHIPS)':
 '1': CDS_PINID='\1\';
NODE_NAME     U6011 CJ34
 '@T6G_MB_LIB.T6G(SCH_1):PAGE404_I38@PURE_QUANTA.PT5161LRS(CHIPS)':
 'B_PERP8': CDS_PINID='B_PERP8';
NET_NAME
'P5E_CPU0_P1_TX_C_DN<8>'
 '@T6G_MB_LIB.T6G(SCH_1):P5E_CPU0_P1_TX_C_DN'<8>:
 C_SIGNAL='@t6g_mb_lib.t6g(sch_1):p5e_cpu0_p1_tx_c_dn(8)';
NODE_NAME     C948 1
 '@T6G_MB_LIB.T6G(SCH_1):PAGE351_I152@PURE_QUANTA.Q_CAP_DIFFBUS(CHIPS)':
 '1': CDS_PINID='\1\';
NODE_NAME     U6011 CB34
 '@T6G_MB_LIB.T6G(SCH_1):PAGE404_I1@PURE_QUANTA.PT5161LRS(CHIPS)':
 'B_PERP7': CDS_PINID='B_PERP7';
NET_NAME
'P5E_CPU0_P1_TX_C_DN<9>'
 '@T6G_MB_LIB.T6G(SCH_1):P5E_CPU0_P1_TX_C_DN'<9>:
 C_SIGNAL='@t6g_mb_lib.t6g(sch_1):p5e_cpu0_p1_tx_c_dn(9)';
NODE_NAME     C946 1
 '@T6G_MB_LIB.T6G(SCH_1):PAGE351_I154@PURE_QUANTA.Q_CAP_DIFFBUS(CHIPS)':
 '1': CDS_PINID='\1\';
NODE_NAME     U6011 BR34
 '@T6G_MB_LIB.T6G(SCH_1):PAGE404_I1@PURE_QUANTA.PT5161LRS(CHIPS)':
 'B_PERP6': CDS_PINID='B_PERP6';
NET_NAME
'P5E_CPU0_P1_TX_C_DP<0>'
 '@T6G_MB_LIB.T6G(SCH_1):P5E_CPU0_P1_TX_C_DP'<0>:
 C_SIGNAL='@t6g_mb_lib.t6g(sch_1):p5e_cpu0_p1_tx_c_dp(0)';
NODE_NAME     C965 1
 '@T6G_MB_LIB.T6G(SCH_1):PAGE351_I121@PURE_QUANTA.Q_CAP_DIFFBUS(CHIPS)':
 '1': CDS_PINID='\1\';
NODE_NAME     U6011 EY35
 '@T6G_MB_LIB.T6G(SCH_1):PAGE404_I38@PURE_QUANTA.PT5161LRS(CHIPS)':
 'B_PERN15': CDS_PINID='B_PERN15';
NET_NAME
'P5E_CPU0_P1_TX_C_DP<10>'
 '@T6G_MB_LIB.T6G(SCH_1):P5E_CPU0_P1_TX_C_DP'<10>:
 C_SIGNAL='@t6g_mb_lib.t6g(sch_1):p5e_cpu0_p1_tx_c_dp(10)';
NODE_NAME     C945 1
 '@T6G_MB_LIB.T6G(SCH_1):PAGE351_I155@PURE_QUANTA.Q_CAP_DIFFBUS(CHIPS)':
 '1': CDS_PINID='\1\';
NODE_NAME     U6011 BK35
 '@T6G_MB_LIB.T6G(SCH_1):PAGE404_I1@PURE_QUANTA.PT5161LRS(CHIPS)':
 'B_PERN5': CDS_PINID='B_PERN5';
NET_NAME
'P5E_CPU0_P1_TX_C_DP<11>'
 '@T6G_MB_LIB.T6G(SCH_1):P5E_CPU0_P1_TX_C_DP'<11>:
 C_SIGNAL='@t6g_mb_lib.t6g(sch_1):p5e_cpu0_p1_tx_c_dp(11)';
NODE_NAME     C943 1
 '@T6G_MB_LIB.T6G(SCH_1):PAGE351_I157@PURE_QUANTA.Q_CAP_DIFFBUS(CHIPS)':
 '1': CDS_PINID='\1\';
NODE_NAME     U6011 BC35
 '@T6G_MB_LIB.T6G(SCH_1):PAGE404_I1@PURE_QUANTA.PT5161LRS(CHIPS)':
 'B_PERN4': CDS_PINID='B_PERN4';
NET_NAME
'P5E_CPU0_P1_TX_C_DP<12>'
 '@T6G_MB_LIB.T6G(SCH_1):P5E_CPU0_P1_TX_C_DP'<12>:
 C_SIGNAL='@t6g_mb_lib.t6g(sch_1):p5e_cpu0_p1_tx_c_dp(12)';
NODE_NAME     C941 1
 '@T6G_MB_LIB.T6G(SCH_1):PAGE351_I159@PURE_QUANTA.Q_CAP_DIFFBUS(CHIPS)':
 '1': CDS_PINID='\1\';
NODE_NAME     U6011 AT35
 '@T6G_MB_LIB.T6G(SCH_1):PAGE404_I1@PURE_QUANTA.PT5161LRS(CHIPS)':
 'B_PERN3': CDS_PINID='B_PERN3';
NET_NAME
'P5E_CPU0_P1_TX_C_DP<13>'
 '@T6G_MB_LIB.T6G(SCH_1):P5E_CPU0_P1_TX_C_DP'<13>:
 C_SIGNAL='@t6g_mb_lib.t6g(sch_1):p5e_cpu0_p1_tx_c_dp(13)';
NODE_NAME     C939 1
 '@T6G_MB_LIB.T6G(SCH_1):PAGE351_I164@PURE_QUANTA.Q_CAP_DIFFBUS(CHIPS)':
 '1': CDS_PINID='\1\';
NODE_NAME     U6011 AJ35
 '@T6G_MB_LIB.T6G(SCH_1):PAGE404_I1@PURE_QUANTA.PT5161LRS(CHIPS)':
 'B_PERN2': CDS_PINID='B_PERN2';
NET_NAME
'P5E_CPU0_P1_TX_C_DP<14>'
 '@T6G_MB_LIB.T6G(SCH_1):P5E_CPU0_P1_TX_C_DP'<14>:
 C_SIGNAL='@t6g_mb_lib.t6g(sch_1):p5e_cpu0_p1_tx_c_dp(14)';
NODE_NAME     C937 1
 '@T6G_MB_LIB.T6G(SCH_1):PAGE351_I166@PURE_QUANTA.Q_CAP_DIFFBUS(CHIPS)':
 '1': CDS_PINID='\1\';
NODE_NAME     U6011 Y34
 '@T6G_MB_LIB.T6G(SCH_1):PAGE404_I1@PURE_QUANTA.PT5161LRS(CHIPS)':
 'B_PERP1': CDS_PINID='B_PERP1';
NET_NAME
'P5E_CPU0_P1_TX_C_DP<15>'
 '@T6G_MB_LIB.T6G(SCH_1):P5E_CPU0_P1_TX_C_DP'<15>:
 C_SIGNAL='@t6g_mb_lib.t6g(sch_1):p5e_cpu0_p1_tx_c_dp(15)';
NODE_NAME     C935 1
 '@T6G_MB_LIB.T6G(SCH_1):PAGE351_I168@PURE_QUANTA.Q_CAP_DIFFBUS(CHIPS)':
 '1': CDS_PINID='\1\';
NODE_NAME     U6011 R35
 '@T6G_MB_LIB.T6G(SCH_1):PAGE404_I1@PURE_QUANTA.PT5161LRS(CHIPS)':
 'B_PERN0': CDS_PINID='B_PERN0';
NET_NAME
'P5E_CPU0_P1_TX_C_DP<1>'
 '@T6G_MB_LIB.T6G(SCH_1):P5E_CPU0_P1_TX_C_DP'<1>:
 C_SIGNAL='@t6g_mb_lib.t6g(sch_1):p5e_cpu0_p1_tx_c_dp(1)';
NODE_NAME     C963 1
 '@T6G_MB_LIB.T6G(SCH_1):PAGE351_I123@PURE_QUANTA.Q_CAP_DIFFBUS(CHIPS)':
 '1': CDS_PINID='\1\';
NODE_NAME     U6011 EL34
 '@T6G_MB_LIB.T6G(SCH_1):PAGE404_I38@PURE_QUANTA.PT5161LRS(CHIPS)':
 'B_PERP14': CDS_PINID='B_PERP14';
NET_NAME
'P5E_CPU0_P1_TX_C_DP<2>'
 '@T6G_MB_LIB.T6G(SCH_1):P5E_CPU0_P1_TX_C_DP'<2>:
 C_SIGNAL='@t6g_mb_lib.t6g(sch_1):p5e_cpu0_p1_tx_c_dp(2)';
NODE_NAME     C961 1
 '@T6G_MB_LIB.T6G(SCH_1):PAGE351_I125@PURE_QUANTA.Q_CAP_DIFFBUS(CHIPS)':
 '1': CDS_PINID='\1\';
NODE_NAME     U6011 EF35
 '@T6G_MB_LIB.T6G(SCH_1):PAGE404_I38@PURE_QUANTA.PT5161LRS(CHIPS)':
 'B_PERN13': CDS_PINID='B_PERN13';
NET_NAME
'P5E_CPU0_P1_TX_C_DP<3>'
 '@T6G_MB_LIB.T6G(SCH_1):P5E_CPU0_P1_TX_C_DP'<3>:
 C_SIGNAL='@t6g_mb_lib.t6g(sch_1):p5e_cpu0_p1_tx_c_dp(3)';
NODE_NAME     C959 1
 '@T6G_MB_LIB.T6G(SCH_1):PAGE351_I127@PURE_QUANTA.Q_CAP_DIFFBUS(CHIPS)':
 '1': CDS_PINID='\1\';
NODE_NAME     U6011 DW35
 '@T6G_MB_LIB.T6G(SCH_1):PAGE404_I38@PURE_QUANTA.PT5161LRS(CHIPS)':
 'B_PERN12': CDS_PINID='B_PERN12';
NET_NAME
'P5E_CPU0_P1_TX_C_DP<4>'
 '@T6G_MB_LIB.T6G(SCH_1):P5E_CPU0_P1_TX_C_DP'<4>:
 C_SIGNAL='@t6g_mb_lib.t6g(sch_1):p5e_cpu0_p1_tx_c_dp(4)';
NODE_NAME     C957 1
 '@T6G_MB_LIB.T6G(SCH_1):PAGE351_I206@PURE_QUANTA.Q_CAP_DIFFBUS(CHIPS)':
 '1': CDS_PINID='\1\';
NODE_NAME     U6011 DM35
 '@T6G_MB_LIB.T6G(SCH_1):PAGE404_I38@PURE_QUANTA.PT5161LRS(CHIPS)':
 'B_PERN11': CDS_PINID='B_PERN11';
NET_NAME
'P5E_CPU0_P1_TX_C_DP<5>'
 '@T6G_MB_LIB.T6G(SCH_1):P5E_CPU0_P1_TX_C_DP'<5>:
 C_SIGNAL='@t6g_mb_lib.t6g(sch_1):p5e_cpu0_p1_tx_c_dp(5)';
NODE_NAME     C955 1
 '@T6G_MB_LIB.T6G(SCH_1):PAGE351_I208@PURE_QUANTA.Q_CAP_DIFFBUS(CHIPS)':
 '1': CDS_PINID='\1\';
NODE_NAME     U6011 DE35
 '@T6G_MB_LIB.T6G(SCH_1):PAGE404_I38@PURE_QUANTA.PT5161LRS(CHIPS)':
 'B_PERN10': CDS_PINID='B_PERN10';
NET_NAME
'P5E_CPU0_P1_TX_C_DP<6>'
 '@T6G_MB_LIB.T6G(SCH_1):P5E_CPU0_P1_TX_C_DP'<6>:
 C_SIGNAL='@t6g_mb_lib.t6g(sch_1):p5e_cpu0_p1_tx_c_dp(6)';
NODE_NAME     C953 1
 '@T6G_MB_LIB.T6G(SCH_1):PAGE351_I134@PURE_QUANTA.Q_CAP_DIFFBUS(CHIPS)':
 '1': CDS_PINID='\1\';
NODE_NAME     U6011 CV35
 '@T6G_MB_LIB.T6G(SCH_1):PAGE404_I38@PURE_QUANTA.PT5161LRS(CHIPS)':
 'B_PERN9': CDS_PINID='B_PERN9';
NET_NAME
'P5E_CPU0_P1_TX_C_DP<7>'
 '@T6G_MB_LIB.T6G(SCH_1):P5E_CPU0_P1_TX_C_DP'<7>:
 C_SIGNAL='@t6g_mb_lib.t6g(sch_1):p5e_cpu0_p1_tx_c_dp(7)';
NODE_NAME     C951 1
 '@T6G_MB_LIB.T6G(SCH_1):PAGE351_I136@PURE_QUANTA.Q_CAP_DIFFBUS(CHIPS)':
 '1': CDS_PINID='\1\';
NODE_NAME     U6011 CL35
 '@T6G_MB_LIB.T6G(SCH_1):PAGE404_I38@PURE_QUANTA.PT5161LRS(CHIPS)':
 'B_PERN8': CDS_PINID='B_PERN8';
NET_NAME
'P5E_CPU0_P1_TX_C_DP<8>'
 '@T6G_MB_LIB.T6G(SCH_1):P5E_CPU0_P1_TX_C_DP'<8>:
 C_SIGNAL='@t6g_mb_lib.t6g(sch_1):p5e_cpu0_p1_tx_c_dp(8)';
NODE_NAME     C949 1
 '@T6G_MB_LIB.T6G(SCH_1):PAGE351_I151@PURE_QUANTA.Q_CAP_DIFFBUS(CHIPS)':
 '1': CDS_PINID='\1\';
NODE_NAME     U6011 CD35
 '@T6G_MB_LIB.T6G(SCH_1):PAGE404_I1@PURE_QUANTA.PT5161LRS(CHIPS)':
 'B_PERN7': CDS_PINID='B_PERN7';
NET_NAME
'P5E_CPU0_P1_TX_C_DP<9>'
 '@T6G_MB_LIB.T6G(SCH_1):P5E_CPU0_P1_TX_C_DP'<9>:
 C_SIGNAL='@t6g_mb_lib.t6g(sch_1):p5e_cpu0_p1_tx_c_dp(9)';
NODE_NAME     C947 1
 '@T6G_MB_LIB.T6G(SCH_1):PAGE351_I153@PURE_QUANTA.Q_CAP_DIFFBUS(CHIPS)':
 '1': CDS_PINID='\1\';
NODE_NAME     U6011 BU35
 '@T6G_MB_LIB.T6G(SCH_1):PAGE404_I1@PURE_QUANTA.PT5161LRS(CHIPS)':
 'B_PERN6': CDS_PINID='B_PERN6';
NET_NAME
'P5E_CPU0_P1_TX_DN<0>'
 '@T6G_MB_LIB.T6G(SCH_1):P5E_CPU0_P1_TX_DN'<0>:
 C_SIGNAL='@t6g_mb_lib.t6g(sch_1):p5e_cpu0_p1_tx_dn(0)';
NODE_NAME     U25 CU52
 '@T6G_MB_LIB.T6G(SCH_1):PAGE24_I149@PURE_QUANTA.GENOA_SP5(CHIPS)':
 'P1_TXN0': CDS_PINID='P1_TXN0';
NODE_NAME     C964 2
 '@T6G_MB_LIB.T6G(SCH_1):PAGE351_I122@PURE_QUANTA.Q_CAP_DIFFBUS(CHIPS)':
 '2': CDS_PINID='\2\';
NET_NAME
'P5E_CPU0_P1_TX_DN<10>'
 '@T6G_MB_LIB.T6G(SCH_1):P5E_CPU0_P1_TX_DN'<10>:
 C_SIGNAL='@t6g_mb_lib.t6g(sch_1):p5e_cpu0_p1_tx_dn(10)';
NODE_NAME     U25 DA43
 '@T6G_MB_LIB.T6G(SCH_1):PAGE24_I149@PURE_QUANTA.GENOA_SP5(CHIPS)':
 'P1_TXN10': CDS_PINID='P1_TXN10';
NODE_NAME     C944 2
 '@T6G_MB_LIB.T6G(SCH_1):PAGE351_I156@PURE_QUANTA.Q_CAP_DIFFBUS(CHIPS)':
 '2': CDS_PINID='\2\';
NET_NAME
'P5E_CPU0_P1_TX_DN<11>'
 '@T6G_MB_LIB.T6G(SCH_1):P5E_CPU0_P1_TX_DN'<11>:
 C_SIGNAL='@t6g_mb_lib.t6g(sch_1):p5e_cpu0_p1_tx_dn(11)';
NODE_NAME     U25 DC43
 '@T6G_MB_LIB.T6G(SCH_1):PAGE24_I149@PURE_QUANTA.GENOA_SP5(CHIPS)':
 'P1_TXN11': CDS_PINID='P1_TXN11';
NODE_NAME     C942 2
 '@T6G_MB_LIB.T6G(SCH_1):PAGE351_I158@PURE_QUANTA.Q_CAP_DIFFBUS(CHIPS)':
 '2': CDS_PINID='\2\';
NET_NAME
'P5E_CPU0_P1_TX_DN<12>'
 '@T6G_MB_LIB.T6G(SCH_1):P5E_CPU0_P1_TX_DN'<12>:
 C_SIGNAL='@t6g_mb_lib.t6g(sch_1):p5e_cpu0_p1_tx_dn(12)';
NODE_NAME     U25 CW43
 '@T6G_MB_LIB.T6G(SCH_1):PAGE24_I149@PURE_QUANTA.GENOA_SP5(CHIPS)':
 'P1_TXN12': CDS_PINID='P1_TXN12';
NODE_NAME     C940 2
 '@T6G_MB_LIB.T6G(SCH_1):PAGE351_I160@PURE_QUANTA.Q_CAP_DIFFBUS(CHIPS)':
 '2': CDS_PINID='\2\';
NET_NAME
'P5E_CPU0_P1_TX_DN<13>'
 '@T6G_MB_LIB.T6G(SCH_1):P5E_CPU0_P1_TX_DN'<13>:
 C_SIGNAL='@t6g_mb_lib.t6g(sch_1):p5e_cpu0_p1_tx_dn(13)';
NODE_NAME     U25 DB40
 '@T6G_MB_LIB.T6G(SCH_1):PAGE24_I149@PURE_QUANTA.GENOA_SP5(CHIPS)':
 'P1_TXN13': CDS_PINID='P1_TXN13';
NODE_NAME     C938 2
 '@T6G_MB_LIB.T6G(SCH_1):PAGE351_I165@PURE_QUANTA.Q_CAP_DIFFBUS(CHIPS)':
 '2': CDS_PINID='\2\';
NET_NAME
'P5E_CPU0_P1_TX_DN<14>'
 '@T6G_MB_LIB.T6G(SCH_1):P5E_CPU0_P1_TX_DN'<14>:
 C_SIGNAL='@t6g_mb_lib.t6g(sch_1):p5e_cpu0_p1_tx_dn(14)';
NODE_NAME     U25 CY40
 '@T6G_MB_LIB.T6G(SCH_1):PAGE24_I149@PURE_QUANTA.GENOA_SP5(CHIPS)':
 'P1_TXN14': CDS_PINID='P1_TXN14';
NODE_NAME     C936 2
 '@T6G_MB_LIB.T6G(SCH_1):PAGE351_I167@PURE_QUANTA.Q_CAP_DIFFBUS(CHIPS)':
 '2': CDS_PINID='\2\';
NET_NAME
'P5E_CPU0_P1_TX_DN<15>'
 '@T6G_MB_LIB.T6G(SCH_1):P5E_CPU0_P1_TX_DN'<15>:
 C_SIGNAL='@t6g_mb_lib.t6g(sch_1):p5e_cpu0_p1_tx_dn(15)';
NODE_NAME     U25 CV40
 '@T6G_MB_LIB.T6G(SCH_1):PAGE24_I149@PURE_QUANTA.GENOA_SP5(CHIPS)':
 'P1_TXN15': CDS_PINID='P1_TXN15';
NODE_NAME     C934 2
 '@T6G_MB_LIB.T6G(SCH_1):PAGE351_I169@PURE_QUANTA.Q_CAP_DIFFBUS(CHIPS)':
 '2': CDS_PINID='\2\';
NET_NAME
'P5E_CPU0_P1_TX_DN<1>'
 '@T6G_MB_LIB.T6G(SCH_1):P5E_CPU0_P1_TX_DN'<1>:
 C_SIGNAL='@t6g_mb_lib.t6g(sch_1):p5e_cpu0_p1_tx_dn(1)';
NODE_NAME     U25 DA52
 '@T6G_MB_LIB.T6G(SCH_1):PAGE24_I149@PURE_QUANTA.GENOA_SP5(CHIPS)':
 'P1_TXN1': CDS_PINID='P1_TXN1';
NODE_NAME     C962 2
 '@T6G_MB_LIB.T6G(SCH_1):PAGE351_I124@PURE_QUANTA.Q_CAP_DIFFBUS(CHIPS)':
 '2': CDS_PINID='\2\';
NET_NAME
'P5E_CPU0_P1_TX_DN<2>'
 '@T6G_MB_LIB.T6G(SCH_1):P5E_CPU0_P1_TX_DN'<2>:
 C_SIGNAL='@t6g_mb_lib.t6g(sch_1):p5e_cpu0_p1_tx_dn(2)';
NODE_NAME     U25 DC52
 '@T6G_MB_LIB.T6G(SCH_1):PAGE24_I149@PURE_QUANTA.GENOA_SP5(CHIPS)':
 'P1_TXN2': CDS_PINID='P1_TXN2';
NODE_NAME     C960 2
 '@T6G_MB_LIB.T6G(SCH_1):PAGE351_I126@PURE_QUANTA.Q_CAP_DIFFBUS(CHIPS)':
 '2': CDS_PINID='\2\';
NET_NAME
'P5E_CPU0_P1_TX_DN<3>'
 '@T6G_MB_LIB.T6G(SCH_1):P5E_CPU0_P1_TX_DN'<3>:
 C_SIGNAL='@t6g_mb_lib.t6g(sch_1):p5e_cpu0_p1_tx_dn(3)';
NODE_NAME     U25 CW52
 '@T6G_MB_LIB.T6G(SCH_1):PAGE24_I149@PURE_QUANTA.GENOA_SP5(CHIPS)':
 'P1_TXN3': CDS_PINID='P1_TXN3';
NODE_NAME     C958 2
 '@T6G_MB_LIB.T6G(SCH_1):PAGE351_I128@PURE_QUANTA.Q_CAP_DIFFBUS(CHIPS)':
 '2': CDS_PINID='\2\';
NET_NAME
'P5E_CPU0_P1_TX_DN<4>'
 '@T6G_MB_LIB.T6G(SCH_1):P5E_CPU0_P1_TX_DN'<4>:
 C_SIGNAL='@t6g_mb_lib.t6g(sch_1):p5e_cpu0_p1_tx_dn(4)';
NODE_NAME     U25 DA49
 '@T6G_MB_LIB.T6G(SCH_1):PAGE24_I149@PURE_QUANTA.GENOA_SP5(CHIPS)':
 'P1_TXN4': CDS_PINID='P1_TXN4';
NODE_NAME     C956 2
 '@T6G_MB_LIB.T6G(SCH_1):PAGE351_I207@PURE_QUANTA.Q_CAP_DIFFBUS(CHIPS)':
 '2': CDS_PINID='\2\';
NET_NAME
'P5E_CPU0_P1_TX_DN<5>'
 '@T6G_MB_LIB.T6G(SCH_1):P5E_CPU0_P1_TX_DN'<5>:
 C_SIGNAL='@t6g_mb_lib.t6g(sch_1):p5e_cpu0_p1_tx_dn(5)';
NODE_NAME     U25 DC49
 '@T6G_MB_LIB.T6G(SCH_1):PAGE24_I149@PURE_QUANTA.GENOA_SP5(CHIPS)':
 'P1_TXN5': CDS_PINID='P1_TXN5';
NODE_NAME     C954 2
 '@T6G_MB_LIB.T6G(SCH_1):PAGE351_I133@PURE_QUANTA.Q_CAP_DIFFBUS(CHIPS)':
 '2': CDS_PINID='\2\';
NET_NAME
'P5E_CPU0_P1_TX_DN<6>'
 '@T6G_MB_LIB.T6G(SCH_1):P5E_CPU0_P1_TX_DN'<6>:
 C_SIGNAL='@t6g_mb_lib.t6g(sch_1):p5e_cpu0_p1_tx_dn(6)';
NODE_NAME     U25 CW49
 '@T6G_MB_LIB.T6G(SCH_1):PAGE24_I149@PURE_QUANTA.GENOA_SP5(CHIPS)':
 'P1_TXN6': CDS_PINID='P1_TXN6';
NODE_NAME     C952 2
 '@T6G_MB_LIB.T6G(SCH_1):PAGE351_I135@PURE_QUANTA.Q_CAP_DIFFBUS(CHIPS)':
 '2': CDS_PINID='\2\';
NET_NAME
'P5E_CPU0_P1_TX_DN<7>'
 '@T6G_MB_LIB.T6G(SCH_1):P5E_CPU0_P1_TX_DN'<7>:
 C_SIGNAL='@t6g_mb_lib.t6g(sch_1):p5e_cpu0_p1_tx_dn(7)';
NODE_NAME     U25 DA46
 '@T6G_MB_LIB.T6G(SCH_1):PAGE24_I149@PURE_QUANTA.GENOA_SP5(CHIPS)':
 'P1_TXN7': CDS_PINID='P1_TXN7';
NODE_NAME     C950 2
 '@T6G_MB_LIB.T6G(SCH_1):PAGE351_I137@PURE_QUANTA.Q_CAP_DIFFBUS(CHIPS)':
 '2': CDS_PINID='\2\';
NET_NAME
'P5E_CPU0_P1_TX_DN<8>'
 '@T6G_MB_LIB.T6G(SCH_1):P5E_CPU0_P1_TX_DN'<8>:
 C_SIGNAL='@t6g_mb_lib.t6g(sch_1):p5e_cpu0_p1_tx_dn(8)';
NODE_NAME     U25 DC46
 '@T6G_MB_LIB.T6G(SCH_1):PAGE24_I149@PURE_QUANTA.GENOA_SP5(CHIPS)':
 'P1_TXN8': CDS_PINID='P1_TXN8';
NODE_NAME     C948 2
 '@T6G_MB_LIB.T6G(SCH_1):PAGE351_I152@PURE_QUANTA.Q_CAP_DIFFBUS(CHIPS)':
 '2': CDS_PINID='\2\';
NET_NAME
'P5E_CPU0_P1_TX_DN<9>'
 '@T6G_MB_LIB.T6G(SCH_1):P5E_CPU0_P1_TX_DN'<9>:
 C_SIGNAL='@t6g_mb_lib.t6g(sch_1):p5e_cpu0_p1_tx_dn(9)';
NODE_NAME     U25 CW46
 '@T6G_MB_LIB.T6G(SCH_1):PAGE24_I149@PURE_QUANTA.GENOA_SP5(CHIPS)':
 'P1_TXN9': CDS_PINID='P1_TXN9';
NODE_NAME     C946 2
 '@T6G_MB_LIB.T6G(SCH_1):PAGE351_I154@PURE_QUANTA.Q_CAP_DIFFBUS(CHIPS)':
 '2': CDS_PINID='\2\';
NET_NAME
'P5E_CPU0_P1_TX_DP<0>'
 '@T6G_MB_LIB.T6G(SCH_1):P5E_CPU0_P1_TX_DP'<0>:
 C_SIGNAL='@t6g_mb_lib.t6g(sch_1):p5e_cpu0_p1_tx_dp(0)';
NODE_NAME     U25 CU53
 '@T6G_MB_LIB.T6G(SCH_1):PAGE24_I149@PURE_QUANTA.GENOA_SP5(CHIPS)':
 'P1_TXP0': CDS_PINID='P1_TXP0';
NODE_NAME     C965 2
 '@T6G_MB_LIB.T6G(SCH_1):PAGE351_I121@PURE_QUANTA.Q_CAP_DIFFBUS(CHIPS)':
 '2': CDS_PINID='\2\';
NET_NAME
'P5E_CPU0_P1_TX_DP<10>'
 '@T6G_MB_LIB.T6G(SCH_1):P5E_CPU0_P1_TX_DP'<10>:
 C_SIGNAL='@t6g_mb_lib.t6g(sch_1):p5e_cpu0_p1_tx_dp(10)';
NODE_NAME     U25 DA44
 '@T6G_MB_LIB.T6G(SCH_1):PAGE24_I149@PURE_QUANTA.GENOA_SP5(CHIPS)':
 'P1_TXP10': CDS_PINID='P1_TXP10';
NODE_NAME     C945 2
 '@T6G_MB_LIB.T6G(SCH_1):PAGE351_I155@PURE_QUANTA.Q_CAP_DIFFBUS(CHIPS)':
 '2': CDS_PINID='\2\';
NET_NAME
'P5E_CPU0_P1_TX_DP<11>'
 '@T6G_MB_LIB.T6G(SCH_1):P5E_CPU0_P1_TX_DP'<11>:
 C_SIGNAL='@t6g_mb_lib.t6g(sch_1):p5e_cpu0_p1_tx_dp(11)';
NODE_NAME     U25 DC44
 '@T6G_MB_LIB.T6G(SCH_1):PAGE24_I149@PURE_QUANTA.GENOA_SP5(CHIPS)':
 'P1_TXP11': CDS_PINID='P1_TXP11';
NODE_NAME     C943 2
 '@T6G_MB_LIB.T6G(SCH_1):PAGE351_I157@PURE_QUANTA.Q_CAP_DIFFBUS(CHIPS)':
 '2': CDS_PINID='\2\';
NET_NAME
'P5E_CPU0_P1_TX_DP<12>'
 '@T6G_MB_LIB.T6G(SCH_1):P5E_CPU0_P1_TX_DP'<12>:
 C_SIGNAL='@t6g_mb_lib.t6g(sch_1):p5e_cpu0_p1_tx_dp(12)';
NODE_NAME     U25 CW44
 '@T6G_MB_LIB.T6G(SCH_1):PAGE24_I149@PURE_QUANTA.GENOA_SP5(CHIPS)':
 'P1_TXP12': CDS_PINID='P1_TXP12';
NODE_NAME     C941 2
 '@T6G_MB_LIB.T6G(SCH_1):PAGE351_I159@PURE_QUANTA.Q_CAP_DIFFBUS(CHIPS)':
 '2': CDS_PINID='\2\';
NET_NAME
'P5E_CPU0_P1_TX_DP<13>'
 '@T6G_MB_LIB.T6G(SCH_1):P5E_CPU0_P1_TX_DP'<13>:
 C_SIGNAL='@t6g_mb_lib.t6g(sch_1):p5e_cpu0_p1_tx_dp(13)';
NODE_NAME     U25 DB41
 '@T6G_MB_LIB.T6G(SCH_1):PAGE24_I149@PURE_QUANTA.GENOA_SP5(CHIPS)':
 'P1_TXP13': CDS_PINID='P1_TXP13';
NODE_NAME     C939 2
 '@T6G_MB_LIB.T6G(SCH_1):PAGE351_I164@PURE_QUANTA.Q_CAP_DIFFBUS(CHIPS)':
 '2': CDS_PINID='\2\';
NET_NAME
'P5E_CPU0_P1_TX_DP<14>'
 '@T6G_MB_LIB.T6G(SCH_1):P5E_CPU0_P1_TX_DP'<14>:
 C_SIGNAL='@t6g_mb_lib.t6g(sch_1):p5e_cpu0_p1_tx_dp(14)';
NODE_NAME     U25 CY41
 '@T6G_MB_LIB.T6G(SCH_1):PAGE24_I149@PURE_QUANTA.GENOA_SP5(CHIPS)':
 'P1_TXP14': CDS_PINID='P1_TXP14';
NODE_NAME     C937 2
 '@T6G_MB_LIB.T6G(SCH_1):PAGE351_I166@PURE_QUANTA.Q_CAP_DIFFBUS(CHIPS)':
 '2': CDS_PINID='\2\';
NET_NAME
'P5E_CPU0_P1_TX_DP<15>'
 '@T6G_MB_LIB.T6G(SCH_1):P5E_CPU0_P1_TX_DP'<15>:
 C_SIGNAL='@t6g_mb_lib.t6g(sch_1):p5e_cpu0_p1_tx_dp(15)';
NODE_NAME     U25 CV41
 '@T6G_MB_LIB.T6G(SCH_1):PAGE24_I149@PURE_QUANTA.GENOA_SP5(CHIPS)':
 'P1_TXP15': CDS_PINID='P1_TXP15';
NODE_NAME     C935 2
 '@T6G_MB_LIB.T6G(SCH_1):PAGE351_I168@PURE_QUANTA.Q_CAP_DIFFBUS(CHIPS)':
 '2': CDS_PINID='\2\';
NET_NAME
'P5E_CPU0_P1_TX_DP<1>'
 '@T6G_MB_LIB.T6G(SCH_1):P5E_CPU0_P1_TX_DP'<1>:
 C_SIGNAL='@t6g_mb_lib.t6g(sch_1):p5e_cpu0_p1_tx_dp(1)';
NODE_NAME     U25 DA53
 '@T6G_MB_LIB.T6G(SCH_1):PAGE24_I149@PURE_QUANTA.GENOA_SP5(CHIPS)':
 'P1_TXP1': CDS_PINID='P1_TXP1';
NODE_NAME     C963 2
 '@T6G_MB_LIB.T6G(SCH_1):PAGE351_I123@PURE_QUANTA.Q_CAP_DIFFBUS(CHIPS)':
 '2': CDS_PINID='\2\';
NET_NAME
'P5E_CPU0_P1_TX_DP<2>'
 '@T6G_MB_LIB.T6G(SCH_1):P5E_CPU0_P1_TX_DP'<2>:
 C_SIGNAL='@t6g_mb_lib.t6g(sch_1):p5e_cpu0_p1_tx_dp(2)';
NODE_NAME     U25 DC53
 '@T6G_MB_LIB.T6G(SCH_1):PAGE24_I149@PURE_QUANTA.GENOA_SP5(CHIPS)':
 'P1_TXP2': CDS_PINID='P1_TXP2';
NODE_NAME     C961 2
 '@T6G_MB_LIB.T6G(SCH_1):PAGE351_I125@PURE_QUANTA.Q_CAP_DIFFBUS(CHIPS)':
 '2': CDS_PINID='\2\';
NET_NAME
'P5E_CPU0_P1_TX_DP<3>'
 '@T6G_MB_LIB.T6G(SCH_1):P5E_CPU0_P1_TX_DP'<3>:
 C_SIGNAL='@t6g_mb_lib.t6g(sch_1):p5e_cpu0_p1_tx_dp(3)';
NODE_NAME     U25 CW53
 '@T6G_MB_LIB.T6G(SCH_1):PAGE24_I149@PURE_QUANTA.GENOA_SP5(CHIPS)':
 'P1_TXP3': CDS_PINID='P1_TXP3';
NODE_NAME     C959 2
 '@T6G_MB_LIB.T6G(SCH_1):PAGE351_I127@PURE_QUANTA.Q_CAP_DIFFBUS(CHIPS)':
 '2': CDS_PINID='\2\';
NET_NAME
'P5E_CPU0_P1_TX_DP<4>'
 '@T6G_MB_LIB.T6G(SCH_1):P5E_CPU0_P1_TX_DP'<4>:
 C_SIGNAL='@t6g_mb_lib.t6g(sch_1):p5e_cpu0_p1_tx_dp(4)';
NODE_NAME     U25 DA50
 '@T6G_MB_LIB.T6G(SCH_1):PAGE24_I149@PURE_QUANTA.GENOA_SP5(CHIPS)':
 'P1_TXP4': CDS_PINID='P1_TXP4';
NODE_NAME     C957 2
 '@T6G_MB_LIB.T6G(SCH_1):PAGE351_I206@PURE_QUANTA.Q_CAP_DIFFBUS(CHIPS)':
 '2': CDS_PINID='\2\';
NET_NAME
'P5E_CPU0_P1_TX_DP<5>'
 '@T6G_MB_LIB.T6G(SCH_1):P5E_CPU0_P1_TX_DP'<5>:
 C_SIGNAL='@t6g_mb_lib.t6g(sch_1):p5e_cpu0_p1_tx_dp(5)';
NODE_NAME     U25 DC50
 '@T6G_MB_LIB.T6G(SCH_1):PAGE24_I149@PURE_QUANTA.GENOA_SP5(CHIPS)':
 'P1_TXP5': CDS_PINID='P1_TXP5';
NODE_NAME     C955 2
 '@T6G_MB_LIB.T6G(SCH_1):PAGE351_I208@PURE_QUANTA.Q_CAP_DIFFBUS(CHIPS)':
 '2': CDS_PINID='\2\';
NET_NAME
'P5E_CPU0_P1_TX_DP<6>'
 '@T6G_MB_LIB.T6G(SCH_1):P5E_CPU0_P1_TX_DP'<6>:
 C_SIGNAL='@t6g_mb_lib.t6g(sch_1):p5e_cpu0_p1_tx_dp(6)';
NODE_NAME     U25 CW50
 '@T6G_MB_LIB.T6G(SCH_1):PAGE24_I149@PURE_QUANTA.GENOA_SP5(CHIPS)':
 'P1_TXP6': CDS_PINID='P1_TXP6';
NODE_NAME     C953 2
 '@T6G_MB_LIB.T6G(SCH_1):PAGE351_I134@PURE_QUANTA.Q_CAP_DIFFBUS(CHIPS)':
 '2': CDS_PINID='\2\';
NET_NAME
'P5E_CPU0_P1_TX_DP<7>'
 '@T6G_MB_LIB.T6G(SCH_1):P5E_CPU0_P1_TX_DP'<7>:
 C_SIGNAL='@t6g_mb_lib.t6g(sch_1):p5e_cpu0_p1_tx_dp(7)';
NODE_NAME     U25 DA47
 '@T6G_MB_LIB.T6G(SCH_1):PAGE24_I149@PURE_QUANTA.GENOA_SP5(CHIPS)':
 'P1_TXP7': CDS_PINID='P1_TXP7';
NODE_NAME     C951 2
 '@T6G_MB_LIB.T6G(SCH_1):PAGE351_I136@PURE_QUANTA.Q_CAP_DIFFBUS(CHIPS)':
 '2': CDS_PINID='\2\';
NET_NAME
'P5E_CPU0_P1_TX_DP<8>'
 '@T6G_MB_LIB.T6G(SCH_1):P5E_CPU0_P1_TX_DP'<8>:
 C_SIGNAL='@t6g_mb_lib.t6g(sch_1):p5e_cpu0_p1_tx_dp(8)';
NODE_NAME     U25 DC47
 '@T6G_MB_LIB.T6G(SCH_1):PAGE24_I149@PURE_QUANTA.GENOA_SP5(CHIPS)':
 'P1_TXP8': CDS_PINID='P1_TXP8';
NODE_NAME     C949 2
 '@T6G_MB_LIB.T6G(SCH_1):PAGE351_I151@PURE_QUANTA.Q_CAP_DIFFBUS(CHIPS)':
 '2': CDS_PINID='\2\';
NET_NAME
'P5E_CPU0_P1_TX_DP<9>'
 '@T6G_MB_LIB.T6G(SCH_1):P5E_CPU0_P1_TX_DP'<9>:
 C_SIGNAL='@t6g_mb_lib.t6g(sch_1):p5e_cpu0_p1_tx_dp(9)';
NODE_NAME     U25 CW47
 '@T6G_MB_LIB.T6G(SCH_1):PAGE24_I149@PURE_QUANTA.GENOA_SP5(CHIPS)':
 'P1_TXP9': CDS_PINID='P1_TXP9';
NODE_NAME     C947 2
 '@T6G_MB_LIB.T6G(SCH_1):PAGE351_I153@PURE_QUANTA.Q_CAP_DIFFBUS(CHIPS)':
 '2': CDS_PINID='\2\';
NET_NAME
'P5E_CPU0_P2_RX_BUF_DN<0>'
 '@T6G_MB_LIB.T6G(SCH_1):P5E_CPU0_P2_RX_BUF_DN'<0>:
 C_SIGNAL='@t6g_mb_lib.t6g(sch_1):p5e_cpu0_p2_rx_buf_dn(0)';
NODE_NAME     U6012 EV2
 '@T6G_MB_LIB.T6G(SCH_1):PAGE417_I38@PURE_QUANTA.PT5161LRS(CHIPS)':
 'A_PERN15': CDS_PINID='A_PERN15';
NODE_NAME     J106 C1
 '@T6G_MB_LIB.T6G(SCH_1):PAGE327_I74@PURE_QUANTA.CONN112_10137002101LF(CHIPS)':
 'C1': CDS_PINID='C1';
NET_NAME
'P5E_CPU0_P2_RX_BUF_DN<10>'
 '@T6G_MB_LIB.T6G(SCH_1):P5E_CPU0_P2_RX_BUF_DN'<10>:
 C_SIGNAL='@t6g_mb_lib.t6g(sch_1):p5e_cpu0_p2_rx_buf_dn(10)';
NODE_NAME     U6012 BH2
 '@T6G_MB_LIB.T6G(SCH_1):PAGE417_I1@PURE_QUANTA.PT5161LRS(CHIPS)':
 'A_PERN5': CDS_PINID='A_PERN5';
NODE_NAME     J105 C3
 '@T6G_MB_LIB.T6G(SCH_1):PAGE326_I75@PURE_QUANTA.CONN112_10137002101LF(CHIPS)':
 'C3': CDS_PINID='C3';
NET_NAME
'P5E_CPU0_P2_RX_BUF_DN<11>'
 '@T6G_MB_LIB.T6G(SCH_1):P5E_CPU0_P2_RX_BUF_DN'<11>:
 C_SIGNAL='@t6g_mb_lib.t6g(sch_1):p5e_cpu0_p2_rx_buf_dn(11)';
NODE_NAME     U6012 BA2
 '@T6G_MB_LIB.T6G(SCH_1):PAGE417_I1@PURE_QUANTA.PT5161LRS(CHIPS)':
 'A_PERN4': CDS_PINID='A_PERN4';
NODE_NAME     J105 B4
 '@T6G_MB_LIB.T6G(SCH_1):PAGE326_I75@PURE_QUANTA.CONN112_10137002101LF(CHIPS)':
 'B4': CDS_PINID='B4';
NET_NAME
'P5E_CPU0_P2_RX_BUF_DN<12>'
 '@T6G_MB_LIB.T6G(SCH_1):P5E_CPU0_P2_RX_BUF_DN'<12>:
 C_SIGNAL='@t6g_mb_lib.t6g(sch_1):p5e_cpu0_p2_rx_buf_dn(12)';
NODE_NAME     U6012 AP2
 '@T6G_MB_LIB.T6G(SCH_1):PAGE417_I1@PURE_QUANTA.PT5161LRS(CHIPS)':
 'A_PERN3': CDS_PINID='A_PERN3';
NODE_NAME     J105 C5
 '@T6G_MB_LIB.T6G(SCH_1):PAGE326_I76@PURE_QUANTA.CONN112_10137002101LF(CHIPS)':
 'C5': CDS_PINID='C5';
NET_NAME
'P5E_CPU0_P2_RX_BUF_DN<13>'
 '@T6G_MB_LIB.T6G(SCH_1):P5E_CPU0_P2_RX_BUF_DN'<13>:
 C_SIGNAL='@t6g_mb_lib.t6g(sch_1):p5e_cpu0_p2_rx_buf_dn(13)';
NODE_NAME     U6012 AG2
 '@T6G_MB_LIB.T6G(SCH_1):PAGE417_I1@PURE_QUANTA.PT5161LRS(CHIPS)':
 'A_PERN2': CDS_PINID='A_PERN2';
NODE_NAME     J105 B6
 '@T6G_MB_LIB.T6G(SCH_1):PAGE326_I76@PURE_QUANTA.CONN112_10137002101LF(CHIPS)':
 'B6': CDS_PINID='B6';
NET_NAME
'P5E_CPU0_P2_RX_BUF_DN<14>'
 '@T6G_MB_LIB.T6G(SCH_1):P5E_CPU0_P2_RX_BUF_DN'<14>:
 C_SIGNAL='@t6g_mb_lib.t6g(sch_1):p5e_cpu0_p2_rx_buf_dn(14)';
NODE_NAME     U6012 Y2
 '@T6G_MB_LIB.T6G(SCH_1):PAGE417_I1@PURE_QUANTA.PT5161LRS(CHIPS)':
 'A_PERN1': CDS_PINID='A_PERN1';
NODE_NAME     J105 C7
 '@T6G_MB_LIB.T6G(SCH_1):PAGE326_I76@PURE_QUANTA.CONN112_10137002101LF(CHIPS)':
 'C7': CDS_PINID='C7';
NET_NAME
'P5E_CPU0_P2_RX_BUF_DN<15>'
 '@T6G_MB_LIB.T6G(SCH_1):P5E_CPU0_P2_RX_BUF_DN'<15>:
 C_SIGNAL='@t6g_mb_lib.t6g(sch_1):p5e_cpu0_p2_rx_buf_dn(15)';
NODE_NAME     U6012 N2
 '@T6G_MB_LIB.T6G(SCH_1):PAGE417_I1@PURE_QUANTA.PT5161LRS(CHIPS)':
 'A_PERN0': CDS_PINID='A_PERN0';
NODE_NAME     J105 B8
 '@T6G_MB_LIB.T6G(SCH_1):PAGE326_I76@PURE_QUANTA.CONN112_10137002101LF(CHIPS)':
 'B8': CDS_PINID='B8';
NET_NAME
'P5E_CPU0_P2_RX_BUF_DN<1>'
 '@T6G_MB_LIB.T6G(SCH_1):P5E_CPU0_P2_RX_BUF_DN'<1>:
 C_SIGNAL='@t6g_mb_lib.t6g(sch_1):p5e_cpu0_p2_rx_buf_dn(1)';
NODE_NAME     U6012 EL2
 '@T6G_MB_LIB.T6G(SCH_1):PAGE417_I38@PURE_QUANTA.PT5161LRS(CHIPS)':
 'A_PERN14': CDS_PINID='A_PERN14';
NODE_NAME     J106 B2
 '@T6G_MB_LIB.T6G(SCH_1):PAGE327_I74@PURE_QUANTA.CONN112_10137002101LF(CHIPS)':
 'B2': CDS_PINID='B2';
NET_NAME
'P5E_CPU0_P2_RX_BUF_DN<2>'
 '@T6G_MB_LIB.T6G(SCH_1):P5E_CPU0_P2_RX_BUF_DN'<2>:
 C_SIGNAL='@t6g_mb_lib.t6g(sch_1):p5e_cpu0_p2_rx_buf_dn(2)';
NODE_NAME     U6012 ED2
 '@T6G_MB_LIB.T6G(SCH_1):PAGE417_I38@PURE_QUANTA.PT5161LRS(CHIPS)':
 'A_PERN13': CDS_PINID='A_PERN13';
NODE_NAME     J106 C3
 '@T6G_MB_LIB.T6G(SCH_1):PAGE327_I74@PURE_QUANTA.CONN112_10137002101LF(CHIPS)':
 'C3': CDS_PINID='C3';
NET_NAME
'P5E_CPU0_P2_RX_BUF_DN<3>'
 '@T6G_MB_LIB.T6G(SCH_1):P5E_CPU0_P2_RX_BUF_DN'<3>:
 C_SIGNAL='@t6g_mb_lib.t6g(sch_1):p5e_cpu0_p2_rx_buf_dn(3)';
NODE_NAME     U6012 DU2
 '@T6G_MB_LIB.T6G(SCH_1):PAGE417_I38@PURE_QUANTA.PT5161LRS(CHIPS)':
 'A_PERN12': CDS_PINID='A_PERN12';
NODE_NAME     J106 B4
 '@T6G_MB_LIB.T6G(SCH_1):PAGE327_I74@PURE_QUANTA.CONN112_10137002101LF(CHIPS)':
 'B4': CDS_PINID='B4';
NET_NAME
'P5E_CPU0_P2_RX_BUF_DN<4>'
 '@T6G_MB_LIB.T6G(SCH_1):P5E_CPU0_P2_RX_BUF_DN'<4>:
 C_SIGNAL='@t6g_mb_lib.t6g(sch_1):p5e_cpu0_p2_rx_buf_dn(4)';
NODE_NAME     U6012 DK2
 '@T6G_MB_LIB.T6G(SCH_1):PAGE417_I38@PURE_QUANTA.PT5161LRS(CHIPS)':
 'A_PERN11': CDS_PINID='A_PERN11';
NODE_NAME     J106 C5
 '@T6G_MB_LIB.T6G(SCH_1):PAGE327_I19@PURE_QUANTA.CONN112_10137002101LF(CHIPS)':
 'C5': CDS_PINID='C5';
NET_NAME
'P5E_CPU0_P2_RX_BUF_DN<5>'
 '@T6G_MB_LIB.T6G(SCH_1):P5E_CPU0_P2_RX_BUF_DN'<5>:
 C_SIGNAL='@t6g_mb_lib.t6g(sch_1):p5e_cpu0_p2_rx_buf_dn(5)';
NODE_NAME     U6012 DC2
 '@T6G_MB_LIB.T6G(SCH_1):PAGE417_I38@PURE_QUANTA.PT5161LRS(CHIPS)':
 'A_PERN10': CDS_PINID='A_PERN10';
NODE_NAME     J106 B6
 '@T6G_MB_LIB.T6G(SCH_1):PAGE327_I19@PURE_QUANTA.CONN112_10137002101LF(CHIPS)':
 'B6': CDS_PINID='B6';
NET_NAME
'P5E_CPU0_P2_RX_BUF_DN<6>'
 '@T6G_MB_LIB.T6G(SCH_1):P5E_CPU0_P2_RX_BUF_DN'<6>:
 C_SIGNAL='@t6g_mb_lib.t6g(sch_1):p5e_cpu0_p2_rx_buf_dn(6)';
NODE_NAME     U6012 CT2
 '@T6G_MB_LIB.T6G(SCH_1):PAGE417_I38@PURE_QUANTA.PT5161LRS(CHIPS)':
 'A_PERN9': CDS_PINID='A_PERN9';
NODE_NAME     J106 C7
 '@T6G_MB_LIB.T6G(SCH_1):PAGE327_I19@PURE_QUANTA.CONN112_10137002101LF(CHIPS)':
 'C7': CDS_PINID='C7';
NET_NAME
'P5E_CPU0_P2_RX_BUF_DN<7>'
 '@T6G_MB_LIB.T6G(SCH_1):P5E_CPU0_P2_RX_BUF_DN'<7>:
 C_SIGNAL='@t6g_mb_lib.t6g(sch_1):p5e_cpu0_p2_rx_buf_dn(7)';
NODE_NAME     U6012 CJ2
 '@T6G_MB_LIB.T6G(SCH_1):PAGE417_I38@PURE_QUANTA.PT5161LRS(CHIPS)':
 'A_PERN8': CDS_PINID='A_PERN8';
NODE_NAME     J106 B8
 '@T6G_MB_LIB.T6G(SCH_1):PAGE327_I19@PURE_QUANTA.CONN112_10137002101LF(CHIPS)':
 'B8': CDS_PINID='B8';
NET_NAME
'P5E_CPU0_P2_RX_BUF_DN<8>'
 '@T6G_MB_LIB.T6G(SCH_1):P5E_CPU0_P2_RX_BUF_DN'<8>:
 C_SIGNAL='@t6g_mb_lib.t6g(sch_1):p5e_cpu0_p2_rx_buf_dn(8)';
NODE_NAME     U6012 CB2
 '@T6G_MB_LIB.T6G(SCH_1):PAGE417_I1@PURE_QUANTA.PT5161LRS(CHIPS)':
 'A_PERN7': CDS_PINID='A_PERN7';
NODE_NAME     J105 C1
 '@T6G_MB_LIB.T6G(SCH_1):PAGE326_I75@PURE_QUANTA.CONN112_10137002101LF(CHIPS)':
 'C1': CDS_PINID='C1';
NET_NAME
'P5E_CPU0_P2_RX_BUF_DN<9>'
 '@T6G_MB_LIB.T6G(SCH_1):P5E_CPU0_P2_RX_BUF_DN'<9>:
 C_SIGNAL='@t6g_mb_lib.t6g(sch_1):p5e_cpu0_p2_rx_buf_dn(9)';
NODE_NAME     U6012 BR2
 '@T6G_MB_LIB.T6G(SCH_1):PAGE417_I1@PURE_QUANTA.PT5161LRS(CHIPS)':
 'A_PERN6': CDS_PINID='A_PERN6';
NODE_NAME     J105 B2
 '@T6G_MB_LIB.T6G(SCH_1):PAGE326_I75@PURE_QUANTA.CONN112_10137002101LF(CHIPS)':
 'B2': CDS_PINID='B2';
NET_NAME
'P5E_CPU0_P2_RX_BUF_DP<0>'
 '@T6G_MB_LIB.T6G(SCH_1):P5E_CPU0_P2_RX_BUF_DP'<0>:
 C_SIGNAL='@t6g_mb_lib.t6g(sch_1):p5e_cpu0_p2_rx_buf_dp(0)';
NODE_NAME     U6012 EY1
 '@T6G_MB_LIB.T6G(SCH_1):PAGE417_I38@PURE_QUANTA.PT5161LRS(CHIPS)':
 'A_PERP15': CDS_PINID='A_PERP15';
NODE_NAME     J106 D1
 '@T6G_MB_LIB.T6G(SCH_1):PAGE327_I74@PURE_QUANTA.CONN112_10137002101LF(CHIPS)':
 'D1': CDS_PINID='D1';
NET_NAME
'P5E_CPU0_P2_RX_BUF_DP<10>'
 '@T6G_MB_LIB.T6G(SCH_1):P5E_CPU0_P2_RX_BUF_DP'<10>:
 C_SIGNAL='@t6g_mb_lib.t6g(sch_1):p5e_cpu0_p2_rx_buf_dp(10)';
NODE_NAME     U6012 BK1
 '@T6G_MB_LIB.T6G(SCH_1):PAGE417_I1@PURE_QUANTA.PT5161LRS(CHIPS)':
 'A_PERP5': CDS_PINID='A_PERP5';
NODE_NAME     J105 D3
 '@T6G_MB_LIB.T6G(SCH_1):PAGE326_I75@PURE_QUANTA.CONN112_10137002101LF(CHIPS)':
 'D3': CDS_PINID='D3';
NET_NAME
'P5E_CPU0_P2_RX_BUF_DP<11>'
 '@T6G_MB_LIB.T6G(SCH_1):P5E_CPU0_P2_RX_BUF_DP'<11>:
 C_SIGNAL='@t6g_mb_lib.t6g(sch_1):p5e_cpu0_p2_rx_buf_dp(11)';
NODE_NAME     U6012 BC1
 '@T6G_MB_LIB.T6G(SCH_1):PAGE417_I1@PURE_QUANTA.PT5161LRS(CHIPS)':
 'A_PERP4': CDS_PINID='A_PERP4';
NODE_NAME     J105 C4
 '@T6G_MB_LIB.T6G(SCH_1):PAGE326_I75@PURE_QUANTA.CONN112_10137002101LF(CHIPS)':
 'C4': CDS_PINID='C4';
NET_NAME
'P5E_CPU0_P2_RX_BUF_DP<12>'
 '@T6G_MB_LIB.T6G(SCH_1):P5E_CPU0_P2_RX_BUF_DP'<12>:
 C_SIGNAL='@t6g_mb_lib.t6g(sch_1):p5e_cpu0_p2_rx_buf_dp(12)';
NODE_NAME     U6012 AT1
 '@T6G_MB_LIB.T6G(SCH_1):PAGE417_I1@PURE_QUANTA.PT5161LRS(CHIPS)':
 'A_PERP3': CDS_PINID='A_PERP3';
NODE_NAME     J105 D5
 '@T6G_MB_LIB.T6G(SCH_1):PAGE326_I76@PURE_QUANTA.CONN112_10137002101LF(CHIPS)':
 'D5': CDS_PINID='D5';
NET_NAME
'P5E_CPU0_P2_RX_BUF_DP<13>'
 '@T6G_MB_LIB.T6G(SCH_1):P5E_CPU0_P2_RX_BUF_DP'<13>:
 C_SIGNAL='@t6g_mb_lib.t6g(sch_1):p5e_cpu0_p2_rx_buf_dp(13)';
NODE_NAME     U6012 AJ1
 '@T6G_MB_LIB.T6G(SCH_1):PAGE417_I1@PURE_QUANTA.PT5161LRS(CHIPS)':
 'A_PERP2': CDS_PINID='A_PERP2';
NODE_NAME     J105 C6
 '@T6G_MB_LIB.T6G(SCH_1):PAGE326_I76@PURE_QUANTA.CONN112_10137002101LF(CHIPS)':
 'C6': CDS_PINID='C6';
NET_NAME
'P5E_CPU0_P2_RX_BUF_DP<14>'
 '@T6G_MB_LIB.T6G(SCH_1):P5E_CPU0_P2_RX_BUF_DP'<14>:
 C_SIGNAL='@t6g_mb_lib.t6g(sch_1):p5e_cpu0_p2_rx_buf_dp(14)';
NODE_NAME     U6012 AB1
 '@T6G_MB_LIB.T6G(SCH_1):PAGE417_I1@PURE_QUANTA.PT5161LRS(CHIPS)':
 'A_PERP1': CDS_PINID='A_PERP1';
NODE_NAME     J105 D7
 '@T6G_MB_LIB.T6G(SCH_1):PAGE326_I76@PURE_QUANTA.CONN112_10137002101LF(CHIPS)':
 'D7': CDS_PINID='D7';
NET_NAME
'P5E_CPU0_P2_RX_BUF_DP<15>'
 '@T6G_MB_LIB.T6G(SCH_1):P5E_CPU0_P2_RX_BUF_DP'<15>:
 C_SIGNAL='@t6g_mb_lib.t6g(sch_1):p5e_cpu0_p2_rx_buf_dp(15)';
NODE_NAME     U6012 R1
 '@T6G_MB_LIB.T6G(SCH_1):PAGE417_I1@PURE_QUANTA.PT5161LRS(CHIPS)':
 'A_PERP0': CDS_PINID='A_PERP0';
NODE_NAME     J105 C8
 '@T6G_MB_LIB.T6G(SCH_1):PAGE326_I76@PURE_QUANTA.CONN112_10137002101LF(CHIPS)':
 'C8': CDS_PINID='C8';
NET_NAME
'P5E_CPU0_P2_RX_BUF_DP<1>'
 '@T6G_MB_LIB.T6G(SCH_1):P5E_CPU0_P2_RX_BUF_DP'<1>:
 C_SIGNAL='@t6g_mb_lib.t6g(sch_1):p5e_cpu0_p2_rx_buf_dp(1)';
NODE_NAME     U6012 EN1
 '@T6G_MB_LIB.T6G(SCH_1):PAGE417_I38@PURE_QUANTA.PT5161LRS(CHIPS)':
 'A_PERP14': CDS_PINID='A_PERP14';
NODE_NAME     J106 C2
 '@T6G_MB_LIB.T6G(SCH_1):PAGE327_I74@PURE_QUANTA.CONN112_10137002101LF(CHIPS)':
 'C2': CDS_PINID='C2';
NET_NAME
'P5E_CPU0_P2_RX_BUF_DP<2>'
 '@T6G_MB_LIB.T6G(SCH_1):P5E_CPU0_P2_RX_BUF_DP'<2>:
 C_SIGNAL='@t6g_mb_lib.t6g(sch_1):p5e_cpu0_p2_rx_buf_dp(2)';
NODE_NAME     U6012 EF1
 '@T6G_MB_LIB.T6G(SCH_1):PAGE417_I38@PURE_QUANTA.PT5161LRS(CHIPS)':
 'A_PERP13': CDS_PINID='A_PERP13';
NODE_NAME     J106 D3
 '@T6G_MB_LIB.T6G(SCH_1):PAGE327_I74@PURE_QUANTA.CONN112_10137002101LF(CHIPS)':
 'D3': CDS_PINID='D3';
NET_NAME
'P5E_CPU0_P2_RX_BUF_DP<3>'
 '@T6G_MB_LIB.T6G(SCH_1):P5E_CPU0_P2_RX_BUF_DP'<3>:
 C_SIGNAL='@t6g_mb_lib.t6g(sch_1):p5e_cpu0_p2_rx_buf_dp(3)';
NODE_NAME     U6012 DW1
 '@T6G_MB_LIB.T6G(SCH_1):PAGE417_I38@PURE_QUANTA.PT5161LRS(CHIPS)':
 'A_PERP12': CDS_PINID='A_PERP12';
NODE_NAME     J106 C4
 '@T6G_MB_LIB.T6G(SCH_1):PAGE327_I74@PURE_QUANTA.CONN112_10137002101LF(CHIPS)':
 'C4': CDS_PINID='C4';
NET_NAME
'P5E_CPU0_P2_RX_BUF_DP<4>'
 '@T6G_MB_LIB.T6G(SCH_1):P5E_CPU0_P2_RX_BUF_DP'<4>:
 C_SIGNAL='@t6g_mb_lib.t6g(sch_1):p5e_cpu0_p2_rx_buf_dp(4)';
NODE_NAME     U6012 DM1
 '@T6G_MB_LIB.T6G(SCH_1):PAGE417_I38@PURE_QUANTA.PT5161LRS(CHIPS)':
 'A_PERP11': CDS_PINID='A_PERP11';
NODE_NAME     J106 D5
 '@T6G_MB_LIB.T6G(SCH_1):PAGE327_I19@PURE_QUANTA.CONN112_10137002101LF(CHIPS)':
 'D5': CDS_PINID='D5';
NET_NAME
'P5E_CPU0_P2_RX_BUF_DP<5>'
 '@T6G_MB_LIB.T6G(SCH_1):P5E_CPU0_P2_RX_BUF_DP'<5>:
 C_SIGNAL='@t6g_mb_lib.t6g(sch_1):p5e_cpu0_p2_rx_buf_dp(5)';
NODE_NAME     U6012 DE1
 '@T6G_MB_LIB.T6G(SCH_1):PAGE417_I38@PURE_QUANTA.PT5161LRS(CHIPS)':
 'A_PERP10': CDS_PINID='A_PERP10';
NODE_NAME     J106 C6
 '@T6G_MB_LIB.T6G(SCH_1):PAGE327_I19@PURE_QUANTA.CONN112_10137002101LF(CHIPS)':
 'C6': CDS_PINID='C6';
NET_NAME
'P5E_CPU0_P2_RX_BUF_DP<6>'
 '@T6G_MB_LIB.T6G(SCH_1):P5E_CPU0_P2_RX_BUF_DP'<6>:
 C_SIGNAL='@t6g_mb_lib.t6g(sch_1):p5e_cpu0_p2_rx_buf_dp(6)';
NODE_NAME     U6012 CV1
 '@T6G_MB_LIB.T6G(SCH_1):PAGE417_I38@PURE_QUANTA.PT5161LRS(CHIPS)':
 'A_PERP9': CDS_PINID='A_PERP9';
NODE_NAME     J106 D7
 '@T6G_MB_LIB.T6G(SCH_1):PAGE327_I19@PURE_QUANTA.CONN112_10137002101LF(CHIPS)':
 'D7': CDS_PINID='D7';
NET_NAME
'P5E_CPU0_P2_RX_BUF_DP<7>'
 '@T6G_MB_LIB.T6G(SCH_1):P5E_CPU0_P2_RX_BUF_DP'<7>:
 C_SIGNAL='@t6g_mb_lib.t6g(sch_1):p5e_cpu0_p2_rx_buf_dp(7)';
NODE_NAME     U6012 CL1
 '@T6G_MB_LIB.T6G(SCH_1):PAGE417_I38@PURE_QUANTA.PT5161LRS(CHIPS)':
 'A_PERP8': CDS_PINID='A_PERP8';
NODE_NAME     J106 C8
 '@T6G_MB_LIB.T6G(SCH_1):PAGE327_I19@PURE_QUANTA.CONN112_10137002101LF(CHIPS)':
 'C8': CDS_PINID='C8';
NET_NAME
'P5E_CPU0_P2_RX_BUF_DP<8>'
 '@T6G_MB_LIB.T6G(SCH_1):P5E_CPU0_P2_RX_BUF_DP'<8>:
 C_SIGNAL='@t6g_mb_lib.t6g(sch_1):p5e_cpu0_p2_rx_buf_dp(8)';
NODE_NAME     U6012 CD1
 '@T6G_MB_LIB.T6G(SCH_1):PAGE417_I1@PURE_QUANTA.PT5161LRS(CHIPS)':
 'A_PERP7': CDS_PINID='A_PERP7';
NODE_NAME     J105 D1
 '@T6G_MB_LIB.T6G(SCH_1):PAGE326_I75@PURE_QUANTA.CONN112_10137002101LF(CHIPS)':
 'D1': CDS_PINID='D1';
NET_NAME
'P5E_CPU0_P2_RX_BUF_DP<9>'
 '@T6G_MB_LIB.T6G(SCH_1):P5E_CPU0_P2_RX_BUF_DP'<9>:
 C_SIGNAL='@t6g_mb_lib.t6g(sch_1):p5e_cpu0_p2_rx_buf_dp(9)';
NODE_NAME     U6012 BU1
 '@T6G_MB_LIB.T6G(SCH_1):PAGE417_I1@PURE_QUANTA.PT5161LRS(CHIPS)':
 'A_PERP6': CDS_PINID='A_PERP6';
NODE_NAME     J105 C2
 '@T6G_MB_LIB.T6G(SCH_1):PAGE326_I75@PURE_QUANTA.CONN112_10137002101LF(CHIPS)':
 'C2': CDS_PINID='C2';
NET_NAME
'P5E_CPU0_P2_RX_DN<0>'
 '@T6G_MB_LIB.T6G(SCH_1):P5E_CPU0_P2_RX_DN'<0>:
 C_SIGNAL='@t6g_mb_lib.t6g(sch_1):p5e_cpu0_p2_rx_dn(0)';
NODE_NAME     U25 CM36
 '@T6G_MB_LIB.T6G(SCH_1):PAGE25_I147@PURE_QUANTA.GENOA_SP5(CHIPS)':
 'P2_RXN0': CDS_PINID='P2_RXN0';
NODE_NAME     U6012 EW29
 '@T6G_MB_LIB.T6G(SCH_1):PAGE416_I38@PURE_QUANTA.PT5161LRS(CHIPS)':
 'A_PETN15': CDS_PINID='A_PETN15';
NET_NAME
'P5E_CPU0_P2_RX_DN<10>'
 '@T6G_MB_LIB.T6G(SCH_1):P5E_CPU0_P2_RX_DN'<10>:
 C_SIGNAL='@t6g_mb_lib.t6g(sch_1):p5e_cpu0_p2_rx_dn(10)';
NODE_NAME     U25 CU27
 '@T6G_MB_LIB.T6G(SCH_1):PAGE25_I147@PURE_QUANTA.GENOA_SP5(CHIPS)':
 'P2_RXN10': CDS_PINID='P2_RXN10';
NODE_NAME     U6012 BJ29
 '@T6G_MB_LIB.T6G(SCH_1):PAGE416_I1@PURE_QUANTA.PT5161LRS(CHIPS)':
 'A_PETN5': CDS_PINID='A_PETN5';
NET_NAME
'P5E_CPU0_P2_RX_DN<11>'
 '@T6G_MB_LIB.T6G(SCH_1):P5E_CPU0_P2_RX_DN'<11>:
 C_SIGNAL='@t6g_mb_lib.t6g(sch_1):p5e_cpu0_p2_rx_dn(11)';
NODE_NAME     U25 CR27
 '@T6G_MB_LIB.T6G(SCH_1):PAGE25_I147@PURE_QUANTA.GENOA_SP5(CHIPS)':
 'P2_RXN11': CDS_PINID='P2_RXN11';
NODE_NAME     U6012 BB29
 '@T6G_MB_LIB.T6G(SCH_1):PAGE416_I1@PURE_QUANTA.PT5161LRS(CHIPS)':
 'A_PETN4': CDS_PINID='A_PETN4';
NET_NAME
'P5E_CPU0_P2_RX_DN<12>'
 '@T6G_MB_LIB.T6G(SCH_1):P5E_CPU0_P2_RX_DN'<12>:
 C_SIGNAL='@t6g_mb_lib.t6g(sch_1):p5e_cpu0_p2_rx_dn(12)';
NODE_NAME     U25 CN27
 '@T6G_MB_LIB.T6G(SCH_1):PAGE25_I147@PURE_QUANTA.GENOA_SP5(CHIPS)':
 'P2_RXN12': CDS_PINID='P2_RXN12';
NODE_NAME     U6012 AR29
 '@T6G_MB_LIB.T6G(SCH_1):PAGE416_I1@PURE_QUANTA.PT5161LRS(CHIPS)':
 'A_PETN3': CDS_PINID='A_PETN3';
NET_NAME
'P5E_CPU0_P2_RX_DN<13>'
 '@T6G_MB_LIB.T6G(SCH_1):P5E_CPU0_P2_RX_DN'<13>:
 C_SIGNAL='@t6g_mb_lib.t6g(sch_1):p5e_cpu0_p2_rx_dn(13)';
NODE_NAME     U25 CL24
 '@T6G_MB_LIB.T6G(SCH_1):PAGE25_I147@PURE_QUANTA.GENOA_SP5(CHIPS)':
 'P2_RXN13': CDS_PINID='P2_RXN13';
NODE_NAME     U6012 AH29
 '@T6G_MB_LIB.T6G(SCH_1):PAGE416_I1@PURE_QUANTA.PT5161LRS(CHIPS)':
 'A_PETN2': CDS_PINID='A_PETN2';
NET_NAME
'P5E_CPU0_P2_RX_DN<14>'
 '@T6G_MB_LIB.T6G(SCH_1):P5E_CPU0_P2_RX_DN'<14>:
 C_SIGNAL='@t6g_mb_lib.t6g(sch_1):p5e_cpu0_p2_rx_dn(14)';
NODE_NAME     U25 CR24
 '@T6G_MB_LIB.T6G(SCH_1):PAGE25_I147@PURE_QUANTA.GENOA_SP5(CHIPS)':
 'P2_RXN14': CDS_PINID='P2_RXN14';
NODE_NAME     U6012 AA29
 '@T6G_MB_LIB.T6G(SCH_1):PAGE416_I1@PURE_QUANTA.PT5161LRS(CHIPS)':
 'A_PETN1': CDS_PINID='A_PETN1';
NET_NAME
'P5E_CPU0_P2_RX_DN<15>'
 '@T6G_MB_LIB.T6G(SCH_1):P5E_CPU0_P2_RX_DN'<15>:
 C_SIGNAL='@t6g_mb_lib.t6g(sch_1):p5e_cpu0_p2_rx_dn(15)';
NODE_NAME     U25 CN24
 '@T6G_MB_LIB.T6G(SCH_1):PAGE25_I147@PURE_QUANTA.GENOA_SP5(CHIPS)':
 'P2_RXN15': CDS_PINID='P2_RXN15';
NODE_NAME     U6012 P29
 '@T6G_MB_LIB.T6G(SCH_1):PAGE416_I1@PURE_QUANTA.PT5161LRS(CHIPS)':
 'A_PETN0': CDS_PINID='A_PETN0';
NET_NAME
'P5E_CPU0_P2_RX_DN<1>'
 '@T6G_MB_LIB.T6G(SCH_1):P5E_CPU0_P2_RX_DN'<1>:
 C_SIGNAL='@t6g_mb_lib.t6g(sch_1):p5e_cpu0_p2_rx_dn(1)';
NODE_NAME     U25 CP36
 '@T6G_MB_LIB.T6G(SCH_1):PAGE25_I147@PURE_QUANTA.GENOA_SP5(CHIPS)':
 'P2_RXN1': CDS_PINID='P2_RXN1';
NODE_NAME     U6012 EM29
 '@T6G_MB_LIB.T6G(SCH_1):PAGE416_I38@PURE_QUANTA.PT5161LRS(CHIPS)':
 'A_PETN14': CDS_PINID='A_PETN14';
NET_NAME
'P5E_CPU0_P2_RX_DN<2>'
 '@T6G_MB_LIB.T6G(SCH_1):P5E_CPU0_P2_RX_DN'<2>:
 C_SIGNAL='@t6g_mb_lib.t6g(sch_1):p5e_cpu0_p2_rx_dn(2)';
NODE_NAME     U25 CT36
 '@T6G_MB_LIB.T6G(SCH_1):PAGE25_I147@PURE_QUANTA.GENOA_SP5(CHIPS)':
 'P2_RXN2': CDS_PINID='P2_RXN2';
NODE_NAME     U6012 EE29
 '@T6G_MB_LIB.T6G(SCH_1):PAGE416_I38@PURE_QUANTA.PT5161LRS(CHIPS)':
 'A_PETN13': CDS_PINID='A_PETN13';
NET_NAME
'P5E_CPU0_P2_RX_DN<3>'
 '@T6G_MB_LIB.T6G(SCH_1):P5E_CPU0_P2_RX_DN'<3>:
 C_SIGNAL='@t6g_mb_lib.t6g(sch_1):p5e_cpu0_p2_rx_dn(3)';
NODE_NAME     U25 CN33
 '@T6G_MB_LIB.T6G(SCH_1):PAGE25_I147@PURE_QUANTA.GENOA_SP5(CHIPS)':
 'P2_RXN3': CDS_PINID='P2_RXN3';
NODE_NAME     U6012 DV29
 '@T6G_MB_LIB.T6G(SCH_1):PAGE416_I38@PURE_QUANTA.PT5161LRS(CHIPS)':
 'A_PETN12': CDS_PINID='A_PETN12';
NET_NAME
'P5E_CPU0_P2_RX_DN<4>'
 '@T6G_MB_LIB.T6G(SCH_1):P5E_CPU0_P2_RX_DN'<4>:
 C_SIGNAL='@t6g_mb_lib.t6g(sch_1):p5e_cpu0_p2_rx_dn(4)';
NODE_NAME     U25 CU33
 '@T6G_MB_LIB.T6G(SCH_1):PAGE25_I147@PURE_QUANTA.GENOA_SP5(CHIPS)':
 'P2_RXN4': CDS_PINID='P2_RXN4';
NODE_NAME     U6012 DL29
 '@T6G_MB_LIB.T6G(SCH_1):PAGE416_I38@PURE_QUANTA.PT5161LRS(CHIPS)':
 'A_PETN11': CDS_PINID='A_PETN11';
NET_NAME
'P5E_CPU0_P2_RX_DN<5>'
 '@T6G_MB_LIB.T6G(SCH_1):P5E_CPU0_P2_RX_DN'<5>:
 C_SIGNAL='@t6g_mb_lib.t6g(sch_1):p5e_cpu0_p2_rx_dn(5)';
NODE_NAME     U25 CR33
 '@T6G_MB_LIB.T6G(SCH_1):PAGE25_I147@PURE_QUANTA.GENOA_SP5(CHIPS)':
 'P2_RXN5': CDS_PINID='P2_RXN5';
NODE_NAME     U6012 DD29
 '@T6G_MB_LIB.T6G(SCH_1):PAGE416_I38@PURE_QUANTA.PT5161LRS(CHIPS)':
 'A_PETN10': CDS_PINID='A_PETN10';
NET_NAME
'P5E_CPU0_P2_RX_DN<6>'
 '@T6G_MB_LIB.T6G(SCH_1):P5E_CPU0_P2_RX_DN'<6>:
 C_SIGNAL='@t6g_mb_lib.t6g(sch_1):p5e_cpu0_p2_rx_dn(6)';
NODE_NAME     U25 CN30
 '@T6G_MB_LIB.T6G(SCH_1):PAGE25_I147@PURE_QUANTA.GENOA_SP5(CHIPS)':
 'P2_RXN6': CDS_PINID='P2_RXN6';
NODE_NAME     U6012 CU29
 '@T6G_MB_LIB.T6G(SCH_1):PAGE416_I38@PURE_QUANTA.PT5161LRS(CHIPS)':
 'A_PETN9': CDS_PINID='A_PETN9';
NET_NAME
'P5E_CPU0_P2_RX_DN<7>'
 '@T6G_MB_LIB.T6G(SCH_1):P5E_CPU0_P2_RX_DN'<7>:
 C_SIGNAL='@t6g_mb_lib.t6g(sch_1):p5e_cpu0_p2_rx_dn(7)';
NODE_NAME     U25 CU30
 '@T6G_MB_LIB.T6G(SCH_1):PAGE25_I147@PURE_QUANTA.GENOA_SP5(CHIPS)':
 'P2_RXN7': CDS_PINID='P2_RXN7';
NODE_NAME     U6012 CK29
 '@T6G_MB_LIB.T6G(SCH_1):PAGE416_I38@PURE_QUANTA.PT5161LRS(CHIPS)':
 'A_PETN8': CDS_PINID='A_PETN8';
NET_NAME
'P5E_CPU0_P2_RX_DN<8>'
 '@T6G_MB_LIB.T6G(SCH_1):P5E_CPU0_P2_RX_DN'<8>:
 C_SIGNAL='@t6g_mb_lib.t6g(sch_1):p5e_cpu0_p2_rx_dn(8)';
NODE_NAME     U25 CR30
 '@T6G_MB_LIB.T6G(SCH_1):PAGE25_I147@PURE_QUANTA.GENOA_SP5(CHIPS)':
 'P2_RXN8': CDS_PINID='P2_RXN8';
NODE_NAME     U6012 CC29
 '@T6G_MB_LIB.T6G(SCH_1):PAGE416_I1@PURE_QUANTA.PT5161LRS(CHIPS)':
 'A_PETN7': CDS_PINID='A_PETN7';
NET_NAME
'P5E_CPU0_P2_RX_DN<9>'
 '@T6G_MB_LIB.T6G(SCH_1):P5E_CPU0_P2_RX_DN'<9>:
 C_SIGNAL='@t6g_mb_lib.t6g(sch_1):p5e_cpu0_p2_rx_dn(9)';
NODE_NAME     U25 CL27
 '@T6G_MB_LIB.T6G(SCH_1):PAGE25_I147@PURE_QUANTA.GENOA_SP5(CHIPS)':
 'P2_RXN9': CDS_PINID='P2_RXN9';
NODE_NAME     U6012 BT29
 '@T6G_MB_LIB.T6G(SCH_1):PAGE416_I1@PURE_QUANTA.PT5161LRS(CHIPS)':
 'A_PETN6': CDS_PINID='A_PETN6';
NET_NAME
'P5E_CPU0_P2_RX_DP<0>'
 '@T6G_MB_LIB.T6G(SCH_1):P5E_CPU0_P2_RX_DP'<0>:
 C_SIGNAL='@t6g_mb_lib.t6g(sch_1):p5e_cpu0_p2_rx_dp(0)';
NODE_NAME     U25 CM35
 '@T6G_MB_LIB.T6G(SCH_1):PAGE25_I147@PURE_QUANTA.GENOA_SP5(CHIPS)':
 'P2_RXP0': CDS_PINID='P2_RXP0';
NODE_NAME     U6012 EU26
 '@T6G_MB_LIB.T6G(SCH_1):PAGE416_I38@PURE_QUANTA.PT5161LRS(CHIPS)':
 'A_PETP15': CDS_PINID='A_PETP15';
NET_NAME
'P5E_CPU0_P2_RX_DP<10>'
 '@T6G_MB_LIB.T6G(SCH_1):P5E_CPU0_P2_RX_DP'<10>:
 C_SIGNAL='@t6g_mb_lib.t6g(sch_1):p5e_cpu0_p2_rx_dp(10)';
NODE_NAME     U25 CU26
 '@T6G_MB_LIB.T6G(SCH_1):PAGE25_I147@PURE_QUANTA.GENOA_SP5(CHIPS)':
 'P2_RXP10': CDS_PINID='P2_RXP10';
NODE_NAME     U6012 BG26
 '@T6G_MB_LIB.T6G(SCH_1):PAGE416_I1@PURE_QUANTA.PT5161LRS(CHIPS)':
 'A_PETP5': CDS_PINID='A_PETP5';
NET_NAME
'P5E_CPU0_P2_RX_DP<11>'
 '@T6G_MB_LIB.T6G(SCH_1):P5E_CPU0_P2_RX_DP'<11>:
 C_SIGNAL='@t6g_mb_lib.t6g(sch_1):p5e_cpu0_p2_rx_dp(11)';
NODE_NAME     U25 CR26
 '@T6G_MB_LIB.T6G(SCH_1):PAGE25_I147@PURE_QUANTA.GENOA_SP5(CHIPS)':
 'P2_RXP11': CDS_PINID='P2_RXP11';
NODE_NAME     U6012 AY26
 '@T6G_MB_LIB.T6G(SCH_1):PAGE416_I1@PURE_QUANTA.PT5161LRS(CHIPS)':
 'A_PETP4': CDS_PINID='A_PETP4';
NET_NAME
'P5E_CPU0_P2_RX_DP<12>'
 '@T6G_MB_LIB.T6G(SCH_1):P5E_CPU0_P2_RX_DP'<12>:
 C_SIGNAL='@t6g_mb_lib.t6g(sch_1):p5e_cpu0_p2_rx_dp(12)';
NODE_NAME     U25 CN26
 '@T6G_MB_LIB.T6G(SCH_1):PAGE25_I147@PURE_QUANTA.GENOA_SP5(CHIPS)':
 'P2_RXP12': CDS_PINID='P2_RXP12';
NODE_NAME     U6012 AN26
 '@T6G_MB_LIB.T6G(SCH_1):PAGE416_I1@PURE_QUANTA.PT5161LRS(CHIPS)':
 'A_PETP3': CDS_PINID='A_PETP3';
NET_NAME
'P5E_CPU0_P2_RX_DP<13>'
 '@T6G_MB_LIB.T6G(SCH_1):P5E_CPU0_P2_RX_DP'<13>:
 C_SIGNAL='@t6g_mb_lib.t6g(sch_1):p5e_cpu0_p2_rx_dp(13)';
NODE_NAME     U25 CL23
 '@T6G_MB_LIB.T6G(SCH_1):PAGE25_I147@PURE_QUANTA.GENOA_SP5(CHIPS)':
 'P2_RXP13': CDS_PINID='P2_RXP13';
NODE_NAME     U6012 AF26
 '@T6G_MB_LIB.T6G(SCH_1):PAGE416_I1@PURE_QUANTA.PT5161LRS(CHIPS)':
 'A_PETP2': CDS_PINID='A_PETP2';
NET_NAME
'P5E_CPU0_P2_RX_DP<14>'
 '@T6G_MB_LIB.T6G(SCH_1):P5E_CPU0_P2_RX_DP'<14>:
 C_SIGNAL='@t6g_mb_lib.t6g(sch_1):p5e_cpu0_p2_rx_dp(14)';
NODE_NAME     U25 CR23
 '@T6G_MB_LIB.T6G(SCH_1):PAGE25_I147@PURE_QUANTA.GENOA_SP5(CHIPS)':
 'P2_RXP14': CDS_PINID='P2_RXP14';
NODE_NAME     U6012 W26
 '@T6G_MB_LIB.T6G(SCH_1):PAGE416_I1@PURE_QUANTA.PT5161LRS(CHIPS)':
 'A_PETP1': CDS_PINID='A_PETP1';
NET_NAME
'P5E_CPU0_P2_RX_DP<15>'
 '@T6G_MB_LIB.T6G(SCH_1):P5E_CPU0_P2_RX_DP'<15>:
 C_SIGNAL='@t6g_mb_lib.t6g(sch_1):p5e_cpu0_p2_rx_dp(15)';
NODE_NAME     U25 CN23
 '@T6G_MB_LIB.T6G(SCH_1):PAGE25_I147@PURE_QUANTA.GENOA_SP5(CHIPS)':
 'P2_RXP15': CDS_PINID='P2_RXP15';
NODE_NAME     U6012 M26
 '@T6G_MB_LIB.T6G(SCH_1):PAGE416_I1@PURE_QUANTA.PT5161LRS(CHIPS)':
 'A_PETP0': CDS_PINID='A_PETP0';
NET_NAME
'P5E_CPU0_P2_RX_DP<1>'
 '@T6G_MB_LIB.T6G(SCH_1):P5E_CPU0_P2_RX_DP'<1>:
 C_SIGNAL='@t6g_mb_lib.t6g(sch_1):p5e_cpu0_p2_rx_dp(1)';
NODE_NAME     U25 CP35
 '@T6G_MB_LIB.T6G(SCH_1):PAGE25_I147@PURE_QUANTA.GENOA_SP5(CHIPS)':
 'P2_RXP1': CDS_PINID='P2_RXP1';
NODE_NAME     U6012 EK26
 '@T6G_MB_LIB.T6G(SCH_1):PAGE416_I38@PURE_QUANTA.PT5161LRS(CHIPS)':
 'A_PETP14': CDS_PINID='A_PETP14';
NET_NAME
'P5E_CPU0_P2_RX_DP<2>'
 '@T6G_MB_LIB.T6G(SCH_1):P5E_CPU0_P2_RX_DP'<2>:
 C_SIGNAL='@t6g_mb_lib.t6g(sch_1):p5e_cpu0_p2_rx_dp(2)';
NODE_NAME     U25 CT35
 '@T6G_MB_LIB.T6G(SCH_1):PAGE25_I147@PURE_QUANTA.GENOA_SP5(CHIPS)':
 'P2_RXP2': CDS_PINID='P2_RXP2';
NODE_NAME     U6012 EC26
 '@T6G_MB_LIB.T6G(SCH_1):PAGE416_I38@PURE_QUANTA.PT5161LRS(CHIPS)':
 'A_PETP13': CDS_PINID='A_PETP13';
NET_NAME
'P5E_CPU0_P2_RX_DP<3>'
 '@T6G_MB_LIB.T6G(SCH_1):P5E_CPU0_P2_RX_DP'<3>:
 C_SIGNAL='@t6g_mb_lib.t6g(sch_1):p5e_cpu0_p2_rx_dp(3)';
NODE_NAME     U25 CN32
 '@T6G_MB_LIB.T6G(SCH_1):PAGE25_I147@PURE_QUANTA.GENOA_SP5(CHIPS)':
 'P2_RXP3': CDS_PINID='P2_RXP3';
NODE_NAME     U6012 DT26
 '@T6G_MB_LIB.T6G(SCH_1):PAGE416_I38@PURE_QUANTA.PT5161LRS(CHIPS)':
 'A_PETP12': CDS_PINID='A_PETP12';
NET_NAME
'P5E_CPU0_P2_RX_DP<4>'
 '@T6G_MB_LIB.T6G(SCH_1):P5E_CPU0_P2_RX_DP'<4>:
 C_SIGNAL='@t6g_mb_lib.t6g(sch_1):p5e_cpu0_p2_rx_dp(4)';
NODE_NAME     U25 CU32
 '@T6G_MB_LIB.T6G(SCH_1):PAGE25_I147@PURE_QUANTA.GENOA_SP5(CHIPS)':
 'P2_RXP4': CDS_PINID='P2_RXP4';
NODE_NAME     U6012 DJ26
 '@T6G_MB_LIB.T6G(SCH_1):PAGE416_I38@PURE_QUANTA.PT5161LRS(CHIPS)':
 'A_PETP11': CDS_PINID='A_PETP11';
NET_NAME
'P5E_CPU0_P2_RX_DP<5>'
 '@T6G_MB_LIB.T6G(SCH_1):P5E_CPU0_P2_RX_DP'<5>:
 C_SIGNAL='@t6g_mb_lib.t6g(sch_1):p5e_cpu0_p2_rx_dp(5)';
NODE_NAME     U25 CR32
 '@T6G_MB_LIB.T6G(SCH_1):PAGE25_I147@PURE_QUANTA.GENOA_SP5(CHIPS)':
 'P2_RXP5': CDS_PINID='P2_RXP5';
NODE_NAME     U6012 DB26
 '@T6G_MB_LIB.T6G(SCH_1):PAGE416_I38@PURE_QUANTA.PT5161LRS(CHIPS)':
 'A_PETP10': CDS_PINID='A_PETP10';
NET_NAME
'P5E_CPU0_P2_RX_DP<6>'
 '@T6G_MB_LIB.T6G(SCH_1):P5E_CPU0_P2_RX_DP'<6>:
 C_SIGNAL='@t6g_mb_lib.t6g(sch_1):p5e_cpu0_p2_rx_dp(6)';
NODE_NAME     U25 CN29
 '@T6G_MB_LIB.T6G(SCH_1):PAGE25_I147@PURE_QUANTA.GENOA_SP5(CHIPS)':
 'P2_RXP6': CDS_PINID='P2_RXP6';
NODE_NAME     U6012 CR26
 '@T6G_MB_LIB.T6G(SCH_1):PAGE416_I38@PURE_QUANTA.PT5161LRS(CHIPS)':
 'A_PETP9': CDS_PINID='A_PETP9';
NET_NAME
'P5E_CPU0_P2_RX_DP<7>'
 '@T6G_MB_LIB.T6G(SCH_1):P5E_CPU0_P2_RX_DP'<7>:
 C_SIGNAL='@t6g_mb_lib.t6g(sch_1):p5e_cpu0_p2_rx_dp(7)';
NODE_NAME     U25 CU29
 '@T6G_MB_LIB.T6G(SCH_1):PAGE25_I147@PURE_QUANTA.GENOA_SP5(CHIPS)':
 'P2_RXP7': CDS_PINID='P2_RXP7';
NODE_NAME     U6012 CH26
 '@T6G_MB_LIB.T6G(SCH_1):PAGE416_I38@PURE_QUANTA.PT5161LRS(CHIPS)':
 'A_PETP8': CDS_PINID='A_PETP8';
NET_NAME
'P5E_CPU0_P2_RX_DP<8>'
 '@T6G_MB_LIB.T6G(SCH_1):P5E_CPU0_P2_RX_DP'<8>:
 C_SIGNAL='@t6g_mb_lib.t6g(sch_1):p5e_cpu0_p2_rx_dp(8)';
NODE_NAME     U25 CR29
 '@T6G_MB_LIB.T6G(SCH_1):PAGE25_I147@PURE_QUANTA.GENOA_SP5(CHIPS)':
 'P2_RXP8': CDS_PINID='P2_RXP8';
NODE_NAME     U6012 CA26
 '@T6G_MB_LIB.T6G(SCH_1):PAGE416_I1@PURE_QUANTA.PT5161LRS(CHIPS)':
 'A_PETP7': CDS_PINID='A_PETP7';
NET_NAME
'P5E_CPU0_P2_RX_DP<9>'
 '@T6G_MB_LIB.T6G(SCH_1):P5E_CPU0_P2_RX_DP'<9>:
 C_SIGNAL='@t6g_mb_lib.t6g(sch_1):p5e_cpu0_p2_rx_dp(9)';
NODE_NAME     U25 CL26
 '@T6G_MB_LIB.T6G(SCH_1):PAGE25_I147@PURE_QUANTA.GENOA_SP5(CHIPS)':
 'P2_RXP9': CDS_PINID='P2_RXP9';
NODE_NAME     U6012 BP26
 '@T6G_MB_LIB.T6G(SCH_1):PAGE416_I1@PURE_QUANTA.PT5161LRS(CHIPS)':
 'A_PETP6': CDS_PINID='A_PETP6';
NET_NAME
'P5E_CPU0_P2_TX_BUF_C_DN<0>'
 '@T6G_MB_LIB.T6G(SCH_1):P5E_CPU0_P2_TX_BUF_C_DN'<0>:
 C_SIGNAL='@t6g_mb_lib.t6g(sch_1):p5e_cpu0_p2_tx_buf_c_dn(0)';
NODE_NAME     C6566 1
 '@T6G_MB_LIB.T6G(SCH_1):PAGE418_I48@PURE_QUANTA.Q_CAP_DIFFBUS(CHIPS)':
 '1': CDS_PINID='\1\';
NODE_NAME     J106 I1
 '@T6G_MB_LIB.T6G(SCH_1):PAGE327_I74@PURE_QUANTA.CONN112_10137002101LF(CHIPS)':
 'I1': CDS_PINID='I1';
NET_NAME
'P5E_CPU0_P2_TX_BUF_C_DN<10>'
 '@T6G_MB_LIB.T6G(SCH_1):P5E_CPU0_P2_TX_BUF_C_DN'<10>:
 C_SIGNAL='@t6g_mb_lib.t6g(sch_1):p5e_cpu0_p2_tx_buf_c_dn(10)';
NODE_NAME     C6586 1
 '@T6G_MB_LIB.T6G(SCH_1):PAGE418_I98@PURE_QUANTA.Q_CAP_DIFFBUS(CHIPS)':
 '1': CDS_PINID='\1\';
NODE_NAME     J105 I3
 '@T6G_MB_LIB.T6G(SCH_1):PAGE326_I75@PURE_QUANTA.CONN112_10137002101LF(CHIPS)':
 'I3': CDS_PINID='I3';
NET_NAME
'P5E_CPU0_P2_TX_BUF_C_DN<11>'
 '@T6G_MB_LIB.T6G(SCH_1):P5E_CPU0_P2_TX_BUF_C_DN'<11>:
 C_SIGNAL='@t6g_mb_lib.t6g(sch_1):p5e_cpu0_p2_tx_buf_c_dn(11)';
NODE_NAME     C6588 1
 '@T6G_MB_LIB.T6G(SCH_1):PAGE418_I96@PURE_QUANTA.Q_CAP_DIFFBUS(CHIPS)':
 '1': CDS_PINID='\1\';
NODE_NAME     J105 H4
 '@T6G_MB_LIB.T6G(SCH_1):PAGE326_I75@PURE_QUANTA.CONN112_10137002101LF(CHIPS)':
 'H4': CDS_PINID='H4';
NET_NAME
'P5E_CPU0_P2_TX_BUF_C_DN<12>'
 '@T6G_MB_LIB.T6G(SCH_1):P5E_CPU0_P2_TX_BUF_C_DN'<12>:
 C_SIGNAL='@t6g_mb_lib.t6g(sch_1):p5e_cpu0_p2_tx_buf_c_dn(12)';
NODE_NAME     C6590 1
 '@T6G_MB_LIB.T6G(SCH_1):PAGE418_I94@PURE_QUANTA.Q_CAP_DIFFBUS(CHIPS)':
 '1': CDS_PINID='\1\';
NODE_NAME     J105 I5
 '@T6G_MB_LIB.T6G(SCH_1):PAGE326_I76@PURE_QUANTA.CONN112_10137002101LF(CHIPS)':
 'I5': CDS_PINID='I5';
NET_NAME
'P5E_CPU0_P2_TX_BUF_C_DN<13>'
 '@T6G_MB_LIB.T6G(SCH_1):P5E_CPU0_P2_TX_BUF_C_DN'<13>:
 C_SIGNAL='@t6g_mb_lib.t6g(sch_1):p5e_cpu0_p2_tx_buf_c_dn(13)';
NODE_NAME     C6592 1
 '@T6G_MB_LIB.T6G(SCH_1):PAGE418_I92@PURE_QUANTA.Q_CAP_DIFFBUS(CHIPS)':
 '1': CDS_PINID='\1\';
NODE_NAME     J105 H6
 '@T6G_MB_LIB.T6G(SCH_1):PAGE326_I76@PURE_QUANTA.CONN112_10137002101LF(CHIPS)':
 'H6': CDS_PINID='H6';
NET_NAME
'P5E_CPU0_P2_TX_BUF_C_DN<14>'
 '@T6G_MB_LIB.T6G(SCH_1):P5E_CPU0_P2_TX_BUF_C_DN'<14>:
 C_SIGNAL='@t6g_mb_lib.t6g(sch_1):p5e_cpu0_p2_tx_buf_c_dn(14)';
NODE_NAME     C6594 1
 '@T6G_MB_LIB.T6G(SCH_1):PAGE418_I90@PURE_QUANTA.Q_CAP_DIFFBUS(CHIPS)':
 '1': CDS_PINID='\1\';
NODE_NAME     J105 I7
 '@T6G_MB_LIB.T6G(SCH_1):PAGE326_I76@PURE_QUANTA.CONN112_10137002101LF(CHIPS)':
 'I7': CDS_PINID='I7';
NET_NAME
'P5E_CPU0_P2_TX_BUF_C_DN<15>'
 '@T6G_MB_LIB.T6G(SCH_1):P5E_CPU0_P2_TX_BUF_C_DN'<15>:
 C_SIGNAL='@t6g_mb_lib.t6g(sch_1):p5e_cpu0_p2_tx_buf_c_dn(15)';
NODE_NAME     C6596 1
 '@T6G_MB_LIB.T6G(SCH_1):PAGE418_I88@PURE_QUANTA.Q_CAP_DIFFBUS(CHIPS)':
 '1': CDS_PINID='\1\';
NODE_NAME     J105 H8
 '@T6G_MB_LIB.T6G(SCH_1):PAGE326_I76@PURE_QUANTA.CONN112_10137002101LF(CHIPS)':
 'H8': CDS_PINID='H8';
NET_NAME
'P5E_CPU0_P2_TX_BUF_C_DN<1>'
 '@T6G_MB_LIB.T6G(SCH_1):P5E_CPU0_P2_TX_BUF_C_DN'<1>:
 C_SIGNAL='@t6g_mb_lib.t6g(sch_1):p5e_cpu0_p2_tx_buf_c_dn(1)';
NODE_NAME     C6568 1
 '@T6G_MB_LIB.T6G(SCH_1):PAGE418_I33@PURE_QUANTA.Q_CAP_DIFFBUS(CHIPS)':
 '1': CDS_PINID='\1\';
NODE_NAME     J106 H2
 '@T6G_MB_LIB.T6G(SCH_1):PAGE327_I74@PURE_QUANTA.CONN112_10137002101LF(CHIPS)':
 'H2': CDS_PINID='H2';
NET_NAME
'P5E_CPU0_P2_TX_BUF_C_DN<2>'
 '@T6G_MB_LIB.T6G(SCH_1):P5E_CPU0_P2_TX_BUF_C_DN'<2>:
 C_SIGNAL='@t6g_mb_lib.t6g(sch_1):p5e_cpu0_p2_tx_buf_c_dn(2)';
NODE_NAME     C6570 1
 '@T6G_MB_LIB.T6G(SCH_1):PAGE418_I31@PURE_QUANTA.Q_CAP_DIFFBUS(CHIPS)':
 '1': CDS_PINID='\1\';
NODE_NAME     J106 I3
 '@T6G_MB_LIB.T6G(SCH_1):PAGE327_I74@PURE_QUANTA.CONN112_10137002101LF(CHIPS)':
 'I3': CDS_PINID='I3';
NET_NAME
'P5E_CPU0_P2_TX_BUF_C_DN<3>'
 '@T6G_MB_LIB.T6G(SCH_1):P5E_CPU0_P2_TX_BUF_C_DN'<3>:
 C_SIGNAL='@t6g_mb_lib.t6g(sch_1):p5e_cpu0_p2_tx_buf_c_dn(3)';
NODE_NAME     C6572 1
 '@T6G_MB_LIB.T6G(SCH_1):PAGE418_I29@PURE_QUANTA.Q_CAP_DIFFBUS(CHIPS)':
 '1': CDS_PINID='\1\';
NODE_NAME     J106 H4
 '@T6G_MB_LIB.T6G(SCH_1):PAGE327_I74@PURE_QUANTA.CONN112_10137002101LF(CHIPS)':
 'H4': CDS_PINID='H4';
NET_NAME
'P5E_CPU0_P2_TX_BUF_C_DN<4>'
 '@T6G_MB_LIB.T6G(SCH_1):P5E_CPU0_P2_TX_BUF_C_DN'<4>:
 C_SIGNAL='@t6g_mb_lib.t6g(sch_1):p5e_cpu0_p2_tx_buf_c_dn(4)';
NODE_NAME     C6574 1
 '@T6G_MB_LIB.T6G(SCH_1):PAGE418_I28@PURE_QUANTA.Q_CAP_DIFFBUS(CHIPS)':
 '1': CDS_PINID='\1\';
NODE_NAME     J106 I5
 '@T6G_MB_LIB.T6G(SCH_1):PAGE327_I19@PURE_QUANTA.CONN112_10137002101LF(CHIPS)':
 'I5': CDS_PINID='I5';
NET_NAME
'P5E_CPU0_P2_TX_BUF_C_DN<5>'
 '@T6G_MB_LIB.T6G(SCH_1):P5E_CPU0_P2_TX_BUF_C_DN'<5>:
 C_SIGNAL='@t6g_mb_lib.t6g(sch_1):p5e_cpu0_p2_tx_buf_c_dn(5)';
NODE_NAME     C6576 1
 '@T6G_MB_LIB.T6G(SCH_1):PAGE418_I26@PURE_QUANTA.Q_CAP_DIFFBUS(CHIPS)':
 '1': CDS_PINID='\1\';
NODE_NAME     J106 H6
 '@T6G_MB_LIB.T6G(SCH_1):PAGE327_I19@PURE_QUANTA.CONN112_10137002101LF(CHIPS)':
 'H6': CDS_PINID='H6';
NET_NAME
'P5E_CPU0_P2_TX_BUF_C_DN<6>'
 '@T6G_MB_LIB.T6G(SCH_1):P5E_CPU0_P2_TX_BUF_C_DN'<6>:
 C_SIGNAL='@t6g_mb_lib.t6g(sch_1):p5e_cpu0_p2_tx_buf_c_dn(6)';
NODE_NAME     C6578 1
 '@T6G_MB_LIB.T6G(SCH_1):PAGE418_I20@PURE_QUANTA.Q_CAP_DIFFBUS(CHIPS)':
 '1': CDS_PINID='\1\';
NODE_NAME     J106 I7
 '@T6G_MB_LIB.T6G(SCH_1):PAGE327_I19@PURE_QUANTA.CONN112_10137002101LF(CHIPS)':
 'I7': CDS_PINID='I7';
NET_NAME
'P5E_CPU0_P2_TX_BUF_C_DN<7>'
 '@T6G_MB_LIB.T6G(SCH_1):P5E_CPU0_P2_TX_BUF_C_DN'<7>:
 C_SIGNAL='@t6g_mb_lib.t6g(sch_1):p5e_cpu0_p2_tx_buf_c_dn(7)';
NODE_NAME     C6580 1
 '@T6G_MB_LIB.T6G(SCH_1):PAGE418_I17@PURE_QUANTA.Q_CAP_DIFFBUS(CHIPS)':
 '1': CDS_PINID='\1\';
NODE_NAME     J106 H8
 '@T6G_MB_LIB.T6G(SCH_1):PAGE327_I19@PURE_QUANTA.CONN112_10137002101LF(CHIPS)':
 'H8': CDS_PINID='H8';
NET_NAME
'P5E_CPU0_P2_TX_BUF_C_DN<8>'
 '@T6G_MB_LIB.T6G(SCH_1):P5E_CPU0_P2_TX_BUF_C_DN'<8>:
 C_SIGNAL='@t6g_mb_lib.t6g(sch_1):p5e_cpu0_p2_tx_buf_c_dn(8)';
NODE_NAME     C6582 1
 '@T6G_MB_LIB.T6G(SCH_1):PAGE418_I105@PURE_QUANTA.Q_CAP_DIFFBUS(CHIPS)':
 '1': CDS_PINID='\1\';
NODE_NAME     J105 I1
 '@T6G_MB_LIB.T6G(SCH_1):PAGE326_I75@PURE_QUANTA.CONN112_10137002101LF(CHIPS)':
 'I1': CDS_PINID='I1';
NET_NAME
'P5E_CPU0_P2_TX_BUF_C_DN<9>'
 '@T6G_MB_LIB.T6G(SCH_1):P5E_CPU0_P2_TX_BUF_C_DN'<9>:
 C_SIGNAL='@t6g_mb_lib.t6g(sch_1):p5e_cpu0_p2_tx_buf_c_dn(9)';
NODE_NAME     C6584 1
 '@T6G_MB_LIB.T6G(SCH_1):PAGE418_I100@PURE_QUANTA.Q_CAP_DIFFBUS(CHIPS)':
 '1': CDS_PINID='\1\';
NODE_NAME     J105 H2
 '@T6G_MB_LIB.T6G(SCH_1):PAGE326_I75@PURE_QUANTA.CONN112_10137002101LF(CHIPS)':
 'H2': CDS_PINID='H2';
NET_NAME
'P5E_CPU0_P2_TX_BUF_C_DP<0>'
 '@T6G_MB_LIB.T6G(SCH_1):P5E_CPU0_P2_TX_BUF_C_DP'<0>:
 C_SIGNAL='@t6g_mb_lib.t6g(sch_1):p5e_cpu0_p2_tx_buf_c_dp(0)';
NODE_NAME     C6565 1
 '@T6G_MB_LIB.T6G(SCH_1):PAGE418_I49@PURE_QUANTA.Q_CAP_DIFFBUS(CHIPS)':
 '1': CDS_PINID='\1\';
NODE_NAME     J106 J1
 '@T6G_MB_LIB.T6G(SCH_1):PAGE327_I74@PURE_QUANTA.CONN112_10137002101LF(CHIPS)':
 'J1': CDS_PINID='J1';
NET_NAME
'P5E_CPU0_P2_TX_BUF_C_DP<10>'
 '@T6G_MB_LIB.T6G(SCH_1):P5E_CPU0_P2_TX_BUF_C_DP'<10>:
 C_SIGNAL='@t6g_mb_lib.t6g(sch_1):p5e_cpu0_p2_tx_buf_c_dp(10)';
NODE_NAME     C6585 1
 '@T6G_MB_LIB.T6G(SCH_1):PAGE418_I99@PURE_QUANTA.Q_CAP_DIFFBUS(CHIPS)':
 '1': CDS_PINID='\1\';
NODE_NAME     J105 J3
 '@T6G_MB_LIB.T6G(SCH_1):PAGE326_I75@PURE_QUANTA.CONN112_10137002101LF(CHIPS)':
 'J3': CDS_PINID='J3';
NET_NAME
'P5E_CPU0_P2_TX_BUF_C_DP<11>'
 '@T6G_MB_LIB.T6G(SCH_1):P5E_CPU0_P2_TX_BUF_C_DP'<11>:
 C_SIGNAL='@t6g_mb_lib.t6g(sch_1):p5e_cpu0_p2_tx_buf_c_dp(11)';
NODE_NAME     C6587 1
 '@T6G_MB_LIB.T6G(SCH_1):PAGE418_I97@PURE_QUANTA.Q_CAP_DIFFBUS(CHIPS)':
 '1': CDS_PINID='\1\';
NODE_NAME     J105 I4
 '@T6G_MB_LIB.T6G(SCH_1):PAGE326_I75@PURE_QUANTA.CONN112_10137002101LF(CHIPS)':
 'I4': CDS_PINID='I4';
NET_NAME
'P5E_CPU0_P2_TX_BUF_C_DP<12>'
 '@T6G_MB_LIB.T6G(SCH_1):P5E_CPU0_P2_TX_BUF_C_DP'<12>:
 C_SIGNAL='@t6g_mb_lib.t6g(sch_1):p5e_cpu0_p2_tx_buf_c_dp(12)';
NODE_NAME     C6589 1
 '@T6G_MB_LIB.T6G(SCH_1):PAGE418_I95@PURE_QUANTA.Q_CAP_DIFFBUS(CHIPS)':
 '1': CDS_PINID='\1\';
NODE_NAME     J105 J5
 '@T6G_MB_LIB.T6G(SCH_1):PAGE326_I76@PURE_QUANTA.CONN112_10137002101LF(CHIPS)':
 'J5': CDS_PINID='J5';
NET_NAME
'P5E_CPU0_P2_TX_BUF_C_DP<13>'
 '@T6G_MB_LIB.T6G(SCH_1):P5E_CPU0_P2_TX_BUF_C_DP'<13>:
 C_SIGNAL='@t6g_mb_lib.t6g(sch_1):p5e_cpu0_p2_tx_buf_c_dp(13)';
NODE_NAME     C6591 1
 '@T6G_MB_LIB.T6G(SCH_1):PAGE418_I93@PURE_QUANTA.Q_CAP_DIFFBUS(CHIPS)':
 '1': CDS_PINID='\1\';
NODE_NAME     J105 I6
 '@T6G_MB_LIB.T6G(SCH_1):PAGE326_I76@PURE_QUANTA.CONN112_10137002101LF(CHIPS)':
 'I6': CDS_PINID='I6';
NET_NAME
'P5E_CPU0_P2_TX_BUF_C_DP<14>'
 '@T6G_MB_LIB.T6G(SCH_1):P5E_CPU0_P2_TX_BUF_C_DP'<14>:
 C_SIGNAL='@t6g_mb_lib.t6g(sch_1):p5e_cpu0_p2_tx_buf_c_dp(14)';
NODE_NAME     C6593 1
 '@T6G_MB_LIB.T6G(SCH_1):PAGE418_I91@PURE_QUANTA.Q_CAP_DIFFBUS(CHIPS)':
 '1': CDS_PINID='\1\';
NODE_NAME     J105 J7
 '@T6G_MB_LIB.T6G(SCH_1):PAGE326_I76@PURE_QUANTA.CONN112_10137002101LF(CHIPS)':
 'J7': CDS_PINID='J7';
NET_NAME
'P5E_CPU0_P2_TX_BUF_C_DP<15>'
 '@T6G_MB_LIB.T6G(SCH_1):P5E_CPU0_P2_TX_BUF_C_DP'<15>:
 C_SIGNAL='@t6g_mb_lib.t6g(sch_1):p5e_cpu0_p2_tx_buf_c_dp(15)';
NODE_NAME     C6595 1
 '@T6G_MB_LIB.T6G(SCH_1):PAGE418_I89@PURE_QUANTA.Q_CAP_DIFFBUS(CHIPS)':
 '1': CDS_PINID='\1\';
NODE_NAME     J105 I8
 '@T6G_MB_LIB.T6G(SCH_1):PAGE326_I76@PURE_QUANTA.CONN112_10137002101LF(CHIPS)':
 'I8': CDS_PINID='I8';
NET_NAME
'P5E_CPU0_P2_TX_BUF_C_DP<1>'
 '@T6G_MB_LIB.T6G(SCH_1):P5E_CPU0_P2_TX_BUF_C_DP'<1>:
 C_SIGNAL='@t6g_mb_lib.t6g(sch_1):p5e_cpu0_p2_tx_buf_c_dp(1)';
NODE_NAME     C6567 1
 '@T6G_MB_LIB.T6G(SCH_1):PAGE418_I32@PURE_QUANTA.Q_CAP_DIFFBUS(CHIPS)':
 '1': CDS_PINID='\1\';
NODE_NAME     J106 I2
 '@T6G_MB_LIB.T6G(SCH_1):PAGE327_I74@PURE_QUANTA.CONN112_10137002101LF(CHIPS)':
 'I2': CDS_PINID='I2';
NET_NAME
'P5E_CPU0_P2_TX_BUF_C_DP<2>'
 '@T6G_MB_LIB.T6G(SCH_1):P5E_CPU0_P2_TX_BUF_C_DP'<2>:
 C_SIGNAL='@t6g_mb_lib.t6g(sch_1):p5e_cpu0_p2_tx_buf_c_dp(2)';
NODE_NAME     C6569 1
 '@T6G_MB_LIB.T6G(SCH_1):PAGE418_I34@PURE_QUANTA.Q_CAP_DIFFBUS(CHIPS)':
 '1': CDS_PINID='\1\';
NODE_NAME     J106 J3
 '@T6G_MB_LIB.T6G(SCH_1):PAGE327_I74@PURE_QUANTA.CONN112_10137002101LF(CHIPS)':
 'J3': CDS_PINID='J3';
NET_NAME
'P5E_CPU0_P2_TX_BUF_C_DP<3>'
 '@T6G_MB_LIB.T6G(SCH_1):P5E_CPU0_P2_TX_BUF_C_DP'<3>:
 C_SIGNAL='@t6g_mb_lib.t6g(sch_1):p5e_cpu0_p2_tx_buf_c_dp(3)';
NODE_NAME     C6571 1
 '@T6G_MB_LIB.T6G(SCH_1):PAGE418_I30@PURE_QUANTA.Q_CAP_DIFFBUS(CHIPS)':
 '1': CDS_PINID='\1\';
NODE_NAME     J106 I4
 '@T6G_MB_LIB.T6G(SCH_1):PAGE327_I74@PURE_QUANTA.CONN112_10137002101LF(CHIPS)':
 'I4': CDS_PINID='I4';
NET_NAME
'P5E_CPU0_P2_TX_BUF_C_DP<4>'
 '@T6G_MB_LIB.T6G(SCH_1):P5E_CPU0_P2_TX_BUF_C_DP'<4>:
 C_SIGNAL='@t6g_mb_lib.t6g(sch_1):p5e_cpu0_p2_tx_buf_c_dp(4)';
NODE_NAME     C6573 1
 '@T6G_MB_LIB.T6G(SCH_1):PAGE418_I27@PURE_QUANTA.Q_CAP_DIFFBUS(CHIPS)':
 '1': CDS_PINID='\1\';
NODE_NAME     J106 J5
 '@T6G_MB_LIB.T6G(SCH_1):PAGE327_I19@PURE_QUANTA.CONN112_10137002101LF(CHIPS)':
 'J5': CDS_PINID='J5';
NET_NAME
'P5E_CPU0_P2_TX_BUF_C_DP<5>'
 '@T6G_MB_LIB.T6G(SCH_1):P5E_CPU0_P2_TX_BUF_C_DP'<5>:
 C_SIGNAL='@t6g_mb_lib.t6g(sch_1):p5e_cpu0_p2_tx_buf_c_dp(5)';
NODE_NAME     C6575 1
 '@T6G_MB_LIB.T6G(SCH_1):PAGE418_I25@PURE_QUANTA.Q_CAP_DIFFBUS(CHIPS)':
 '1': CDS_PINID='\1\';
NODE_NAME     J106 I6
 '@T6G_MB_LIB.T6G(SCH_1):PAGE327_I19@PURE_QUANTA.CONN112_10137002101LF(CHIPS)':
 'I6': CDS_PINID='I6';
NET_NAME
'P5E_CPU0_P2_TX_BUF_C_DP<6>'
 '@T6G_MB_LIB.T6G(SCH_1):P5E_CPU0_P2_TX_BUF_C_DP'<6>:
 C_SIGNAL='@t6g_mb_lib.t6g(sch_1):p5e_cpu0_p2_tx_buf_c_dp(6)';
NODE_NAME     C6577 1
 '@T6G_MB_LIB.T6G(SCH_1):PAGE418_I19@PURE_QUANTA.Q_CAP_DIFFBUS(CHIPS)':
 '1': CDS_PINID='\1\';
NODE_NAME     J106 J7
 '@T6G_MB_LIB.T6G(SCH_1):PAGE327_I19@PURE_QUANTA.CONN112_10137002101LF(CHIPS)':
 'J7': CDS_PINID='J7';
NET_NAME
'P5E_CPU0_P2_TX_BUF_C_DP<7>'
 '@T6G_MB_LIB.T6G(SCH_1):P5E_CPU0_P2_TX_BUF_C_DP'<7>:
 C_SIGNAL='@t6g_mb_lib.t6g(sch_1):p5e_cpu0_p2_tx_buf_c_dp(7)';
NODE_NAME     C6579 1
 '@T6G_MB_LIB.T6G(SCH_1):PAGE418_I18@PURE_QUANTA.Q_CAP_DIFFBUS(CHIPS)':
 '1': CDS_PINID='\1\';
NODE_NAME     J106 I8
 '@T6G_MB_LIB.T6G(SCH_1):PAGE327_I19@PURE_QUANTA.CONN112_10137002101LF(CHIPS)':
 'I8': CDS_PINID='I8';
NET_NAME
'P5E_CPU0_P2_TX_BUF_C_DP<8>'
 '@T6G_MB_LIB.T6G(SCH_1):P5E_CPU0_P2_TX_BUF_C_DP'<8>:
 C_SIGNAL='@t6g_mb_lib.t6g(sch_1):p5e_cpu0_p2_tx_buf_c_dp(8)';
NODE_NAME     C6581 1
 '@T6G_MB_LIB.T6G(SCH_1):PAGE418_I104@PURE_QUANTA.Q_CAP_DIFFBUS(CHIPS)':
 '1': CDS_PINID='\1\';
NODE_NAME     J105 J1
 '@T6G_MB_LIB.T6G(SCH_1):PAGE326_I75@PURE_QUANTA.CONN112_10137002101LF(CHIPS)':
 'J1': CDS_PINID='J1';
NET_NAME
'P5E_CPU0_P2_TX_BUF_C_DP<9>'
 '@T6G_MB_LIB.T6G(SCH_1):P5E_CPU0_P2_TX_BUF_C_DP'<9>:
 C_SIGNAL='@t6g_mb_lib.t6g(sch_1):p5e_cpu0_p2_tx_buf_c_dp(9)';
NODE_NAME     C6583 1
 '@T6G_MB_LIB.T6G(SCH_1):PAGE418_I101@PURE_QUANTA.Q_CAP_DIFFBUS(CHIPS)':
 '1': CDS_PINID='\1\';
NODE_NAME     J105 I2
 '@T6G_MB_LIB.T6G(SCH_1):PAGE326_I75@PURE_QUANTA.CONN112_10137002101LF(CHIPS)':
 'I2': CDS_PINID='I2';
NET_NAME
'P5E_CPU0_P2_TX_BUF_DN<0>'
 '@T6G_MB_LIB.T6G(SCH_1):P5E_CPU0_P2_TX_BUF_DN'<0>:
 C_SIGNAL='@t6g_mb_lib.t6g(sch_1):p5e_cpu0_p2_tx_buf_dn(0)';
NODE_NAME     C6566 2
 '@T6G_MB_LIB.T6G(SCH_1):PAGE418_I48@PURE_QUANTA.Q_CAP_DIFFBUS(CHIPS)':
 '2': CDS_PINID='\2\';
NODE_NAME     U6012 EW10
 '@T6G_MB_LIB.T6G(SCH_1):PAGE418_I142@PURE_QUANTA.PT5161LRS(CHIPS)':
 'B_PETN15': CDS_PINID='B_PETN15';
NET_NAME
'P5E_CPU0_P2_TX_BUF_DN<10>'
 '@T6G_MB_LIB.T6G(SCH_1):P5E_CPU0_P2_TX_BUF_DN'<10>:
 C_SIGNAL='@t6g_mb_lib.t6g(sch_1):p5e_cpu0_p2_tx_buf_dn(10)';
NODE_NAME     U6012 BJ10
 '@T6G_MB_LIB.T6G(SCH_1):PAGE418_I47@PURE_QUANTA.PT5161LRS(CHIPS)':
 'B_PETN5': CDS_PINID='B_PETN5';
NODE_NAME     C6586 2
 '@T6G_MB_LIB.T6G(SCH_1):PAGE418_I98@PURE_QUANTA.Q_CAP_DIFFBUS(CHIPS)':
 '2': CDS_PINID='\2\';
NET_NAME
'P5E_CPU0_P2_TX_BUF_DN<11>'
 '@T6G_MB_LIB.T6G(SCH_1):P5E_CPU0_P2_TX_BUF_DN'<11>:
 C_SIGNAL='@t6g_mb_lib.t6g(sch_1):p5e_cpu0_p2_tx_buf_dn(11)';
NODE_NAME     U6012 BB10
 '@T6G_MB_LIB.T6G(SCH_1):PAGE418_I47@PURE_QUANTA.PT5161LRS(CHIPS)':
 'B_PETN4': CDS_PINID='B_PETN4';
NODE_NAME     C6588 2
 '@T6G_MB_LIB.T6G(SCH_1):PAGE418_I96@PURE_QUANTA.Q_CAP_DIFFBUS(CHIPS)':
 '2': CDS_PINID='\2\';
NET_NAME
'P5E_CPU0_P2_TX_BUF_DN<12>'
 '@T6G_MB_LIB.T6G(SCH_1):P5E_CPU0_P2_TX_BUF_DN'<12>:
 C_SIGNAL='@t6g_mb_lib.t6g(sch_1):p5e_cpu0_p2_tx_buf_dn(12)';
NODE_NAME     U6012 AR10
 '@T6G_MB_LIB.T6G(SCH_1):PAGE418_I47@PURE_QUANTA.PT5161LRS(CHIPS)':
 'B_PETN3': CDS_PINID='B_PETN3';
NODE_NAME     C6590 2
 '@T6G_MB_LIB.T6G(SCH_1):PAGE418_I94@PURE_QUANTA.Q_CAP_DIFFBUS(CHIPS)':
 '2': CDS_PINID='\2\';
NET_NAME
'P5E_CPU0_P2_TX_BUF_DN<13>'
 '@T6G_MB_LIB.T6G(SCH_1):P5E_CPU0_P2_TX_BUF_DN'<13>:
 C_SIGNAL='@t6g_mb_lib.t6g(sch_1):p5e_cpu0_p2_tx_buf_dn(13)';
NODE_NAME     U6012 AH10
 '@T6G_MB_LIB.T6G(SCH_1):PAGE418_I47@PURE_QUANTA.PT5161LRS(CHIPS)':
 'B_PETN2': CDS_PINID='B_PETN2';
NODE_NAME     C6592 2
 '@T6G_MB_LIB.T6G(SCH_1):PAGE418_I92@PURE_QUANTA.Q_CAP_DIFFBUS(CHIPS)':
 '2': CDS_PINID='\2\';
NET_NAME
'P5E_CPU0_P2_TX_BUF_DN<14>'
 '@T6G_MB_LIB.T6G(SCH_1):P5E_CPU0_P2_TX_BUF_DN'<14>:
 C_SIGNAL='@t6g_mb_lib.t6g(sch_1):p5e_cpu0_p2_tx_buf_dn(14)';
NODE_NAME     U6012 AA10
 '@T6G_MB_LIB.T6G(SCH_1):PAGE418_I47@PURE_QUANTA.PT5161LRS(CHIPS)':
 'B_PETN1': CDS_PINID='B_PETN1';
NODE_NAME     C6594 2
 '@T6G_MB_LIB.T6G(SCH_1):PAGE418_I90@PURE_QUANTA.Q_CAP_DIFFBUS(CHIPS)':
 '2': CDS_PINID='\2\';
NET_NAME
'P5E_CPU0_P2_TX_BUF_DN<15>'
 '@T6G_MB_LIB.T6G(SCH_1):P5E_CPU0_P2_TX_BUF_DN'<15>:
 C_SIGNAL='@t6g_mb_lib.t6g(sch_1):p5e_cpu0_p2_tx_buf_dn(15)';
NODE_NAME     U6012 P10
 '@T6G_MB_LIB.T6G(SCH_1):PAGE418_I47@PURE_QUANTA.PT5161LRS(CHIPS)':
 'B_PETN0': CDS_PINID='B_PETN0';
NODE_NAME     C6596 2
 '@T6G_MB_LIB.T6G(SCH_1):PAGE418_I88@PURE_QUANTA.Q_CAP_DIFFBUS(CHIPS)':
 '2': CDS_PINID='\2\';
NET_NAME
'P5E_CPU0_P2_TX_BUF_DN<1>'
 '@T6G_MB_LIB.T6G(SCH_1):P5E_CPU0_P2_TX_BUF_DN'<1>:
 C_SIGNAL='@t6g_mb_lib.t6g(sch_1):p5e_cpu0_p2_tx_buf_dn(1)';
NODE_NAME     C6568 2
 '@T6G_MB_LIB.T6G(SCH_1):PAGE418_I33@PURE_QUANTA.Q_CAP_DIFFBUS(CHIPS)':
 '2': CDS_PINID='\2\';
NODE_NAME     U6012 EM10
 '@T6G_MB_LIB.T6G(SCH_1):PAGE418_I142@PURE_QUANTA.PT5161LRS(CHIPS)':
 'B_PETN14': CDS_PINID='B_PETN14';
NET_NAME
'P5E_CPU0_P2_TX_BUF_DN<2>'
 '@T6G_MB_LIB.T6G(SCH_1):P5E_CPU0_P2_TX_BUF_DN'<2>:
 C_SIGNAL='@t6g_mb_lib.t6g(sch_1):p5e_cpu0_p2_tx_buf_dn(2)';
NODE_NAME     C6570 2
 '@T6G_MB_LIB.T6G(SCH_1):PAGE418_I31@PURE_QUANTA.Q_CAP_DIFFBUS(CHIPS)':
 '2': CDS_PINID='\2\';
NODE_NAME     U6012 EE10
 '@T6G_MB_LIB.T6G(SCH_1):PAGE418_I142@PURE_QUANTA.PT5161LRS(CHIPS)':
 'B_PETN13': CDS_PINID='B_PETN13';
NET_NAME
'P5E_CPU0_P2_TX_BUF_DN<3>'
 '@T6G_MB_LIB.T6G(SCH_1):P5E_CPU0_P2_TX_BUF_DN'<3>:
 C_SIGNAL='@t6g_mb_lib.t6g(sch_1):p5e_cpu0_p2_tx_buf_dn(3)';
NODE_NAME     C6572 2
 '@T6G_MB_LIB.T6G(SCH_1):PAGE418_I29@PURE_QUANTA.Q_CAP_DIFFBUS(CHIPS)':
 '2': CDS_PINID='\2\';
NODE_NAME     U6012 DV10
 '@T6G_MB_LIB.T6G(SCH_1):PAGE418_I142@PURE_QUANTA.PT5161LRS(CHIPS)':
 'B_PETN12': CDS_PINID='B_PETN12';
NET_NAME
'P5E_CPU0_P2_TX_BUF_DN<4>'
 '@T6G_MB_LIB.T6G(SCH_1):P5E_CPU0_P2_TX_BUF_DN'<4>:
 C_SIGNAL='@t6g_mb_lib.t6g(sch_1):p5e_cpu0_p2_tx_buf_dn(4)';
NODE_NAME     C6574 2
 '@T6G_MB_LIB.T6G(SCH_1):PAGE418_I28@PURE_QUANTA.Q_CAP_DIFFBUS(CHIPS)':
 '2': CDS_PINID='\2\';
NODE_NAME     U6012 DL10
 '@T6G_MB_LIB.T6G(SCH_1):PAGE418_I142@PURE_QUANTA.PT5161LRS(CHIPS)':
 'B_PETN11': CDS_PINID='B_PETN11';
NET_NAME
'P5E_CPU0_P2_TX_BUF_DN<5>'
 '@T6G_MB_LIB.T6G(SCH_1):P5E_CPU0_P2_TX_BUF_DN'<5>:
 C_SIGNAL='@t6g_mb_lib.t6g(sch_1):p5e_cpu0_p2_tx_buf_dn(5)';
NODE_NAME     C6576 2
 '@T6G_MB_LIB.T6G(SCH_1):PAGE418_I26@PURE_QUANTA.Q_CAP_DIFFBUS(CHIPS)':
 '2': CDS_PINID='\2\';
NODE_NAME     U6012 DD10
 '@T6G_MB_LIB.T6G(SCH_1):PAGE418_I142@PURE_QUANTA.PT5161LRS(CHIPS)':
 'B_PETN10': CDS_PINID='B_PETN10';
NET_NAME
'P5E_CPU0_P2_TX_BUF_DN<6>'
 '@T6G_MB_LIB.T6G(SCH_1):P5E_CPU0_P2_TX_BUF_DN'<6>:
 C_SIGNAL='@t6g_mb_lib.t6g(sch_1):p5e_cpu0_p2_tx_buf_dn(6)';
NODE_NAME     C6578 2
 '@T6G_MB_LIB.T6G(SCH_1):PAGE418_I20@PURE_QUANTA.Q_CAP_DIFFBUS(CHIPS)':
 '2': CDS_PINID='\2\';
NODE_NAME     U6012 CU10
 '@T6G_MB_LIB.T6G(SCH_1):PAGE418_I142@PURE_QUANTA.PT5161LRS(CHIPS)':
 'B_PETN9': CDS_PINID='B_PETN9';
NET_NAME
'P5E_CPU0_P2_TX_BUF_DN<7>'
 '@T6G_MB_LIB.T6G(SCH_1):P5E_CPU0_P2_TX_BUF_DN'<7>:
 C_SIGNAL='@t6g_mb_lib.t6g(sch_1):p5e_cpu0_p2_tx_buf_dn(7)';
NODE_NAME     C6580 2
 '@T6G_MB_LIB.T6G(SCH_1):PAGE418_I17@PURE_QUANTA.Q_CAP_DIFFBUS(CHIPS)':
 '2': CDS_PINID='\2\';
NODE_NAME     U6012 CK10
 '@T6G_MB_LIB.T6G(SCH_1):PAGE418_I142@PURE_QUANTA.PT5161LRS(CHIPS)':
 'B_PETN8': CDS_PINID='B_PETN8';
NET_NAME
'P5E_CPU0_P2_TX_BUF_DN<8>'
 '@T6G_MB_LIB.T6G(SCH_1):P5E_CPU0_P2_TX_BUF_DN'<8>:
 C_SIGNAL='@t6g_mb_lib.t6g(sch_1):p5e_cpu0_p2_tx_buf_dn(8)';
NODE_NAME     U6012 CC10
 '@T6G_MB_LIB.T6G(SCH_1):PAGE418_I47@PURE_QUANTA.PT5161LRS(CHIPS)':
 'B_PETN7': CDS_PINID='B_PETN7';
NODE_NAME     C6582 2
 '@T6G_MB_LIB.T6G(SCH_1):PAGE418_I105@PURE_QUANTA.Q_CAP_DIFFBUS(CHIPS)':
 '2': CDS_PINID='\2\';
NET_NAME
'P5E_CPU0_P2_TX_BUF_DN<9>'
 '@T6G_MB_LIB.T6G(SCH_1):P5E_CPU0_P2_TX_BUF_DN'<9>:
 C_SIGNAL='@t6g_mb_lib.t6g(sch_1):p5e_cpu0_p2_tx_buf_dn(9)';
NODE_NAME     U6012 BT10
 '@T6G_MB_LIB.T6G(SCH_1):PAGE418_I47@PURE_QUANTA.PT5161LRS(CHIPS)':
 'B_PETN6': CDS_PINID='B_PETN6';
NODE_NAME     C6584 2
 '@T6G_MB_LIB.T6G(SCH_1):PAGE418_I100@PURE_QUANTA.Q_CAP_DIFFBUS(CHIPS)':
 '2': CDS_PINID='\2\';
NET_NAME
'P5E_CPU0_P2_TX_BUF_DP<0>'
 '@T6G_MB_LIB.T6G(SCH_1):P5E_CPU0_P2_TX_BUF_DP'<0>:
 C_SIGNAL='@t6g_mb_lib.t6g(sch_1):p5e_cpu0_p2_tx_buf_dp(0)';
NODE_NAME     C6565 2
 '@T6G_MB_LIB.T6G(SCH_1):PAGE418_I49@PURE_QUANTA.Q_CAP_DIFFBUS(CHIPS)':
 '2': CDS_PINID='\2\';
NODE_NAME     U6012 EU7
 '@T6G_MB_LIB.T6G(SCH_1):PAGE418_I142@PURE_QUANTA.PT5161LRS(CHIPS)':
 'B_PETP15': CDS_PINID='B_PETP15';
NET_NAME
'P5E_CPU0_P2_TX_BUF_DP<10>'
 '@T6G_MB_LIB.T6G(SCH_1):P5E_CPU0_P2_TX_BUF_DP'<10>:
 C_SIGNAL='@t6g_mb_lib.t6g(sch_1):p5e_cpu0_p2_tx_buf_dp(10)';
NODE_NAME     U6012 BG7
 '@T6G_MB_LIB.T6G(SCH_1):PAGE418_I47@PURE_QUANTA.PT5161LRS(CHIPS)':
 'B_PETP5': CDS_PINID='B_PETP5';
NODE_NAME     C6585 2
 '@T6G_MB_LIB.T6G(SCH_1):PAGE418_I99@PURE_QUANTA.Q_CAP_DIFFBUS(CHIPS)':
 '2': CDS_PINID='\2\';
NET_NAME
'P5E_CPU0_P2_TX_BUF_DP<11>'
 '@T6G_MB_LIB.T6G(SCH_1):P5E_CPU0_P2_TX_BUF_DP'<11>:
 C_SIGNAL='@t6g_mb_lib.t6g(sch_1):p5e_cpu0_p2_tx_buf_dp(11)';
NODE_NAME     U6012 AY7
 '@T6G_MB_LIB.T6G(SCH_1):PAGE418_I47@PURE_QUANTA.PT5161LRS(CHIPS)':
 'B_PETP4': CDS_PINID='B_PETP4';
NODE_NAME     C6587 2
 '@T6G_MB_LIB.T6G(SCH_1):PAGE418_I97@PURE_QUANTA.Q_CAP_DIFFBUS(CHIPS)':
 '2': CDS_PINID='\2\';
NET_NAME
'P5E_CPU0_P2_TX_BUF_DP<12>'
 '@T6G_MB_LIB.T6G(SCH_1):P5E_CPU0_P2_TX_BUF_DP'<12>:
 C_SIGNAL='@t6g_mb_lib.t6g(sch_1):p5e_cpu0_p2_tx_buf_dp(12)';
NODE_NAME     U6012 AN7
 '@T6G_MB_LIB.T6G(SCH_1):PAGE418_I47@PURE_QUANTA.PT5161LRS(CHIPS)':
 'B_PETP3': CDS_PINID='B_PETP3';
NODE_NAME     C6589 2
 '@T6G_MB_LIB.T6G(SCH_1):PAGE418_I95@PURE_QUANTA.Q_CAP_DIFFBUS(CHIPS)':
 '2': CDS_PINID='\2\';
NET_NAME
'P5E_CPU0_P2_TX_BUF_DP<13>'
 '@T6G_MB_LIB.T6G(SCH_1):P5E_CPU0_P2_TX_BUF_DP'<13>:
 C_SIGNAL='@t6g_mb_lib.t6g(sch_1):p5e_cpu0_p2_tx_buf_dp(13)';
NODE_NAME     U6012 AF7
 '@T6G_MB_LIB.T6G(SCH_1):PAGE418_I47@PURE_QUANTA.PT5161LRS(CHIPS)':
 'B_PETP2': CDS_PINID='B_PETP2';
NODE_NAME     C6591 2
 '@T6G_MB_LIB.T6G(SCH_1):PAGE418_I93@PURE_QUANTA.Q_CAP_DIFFBUS(CHIPS)':
 '2': CDS_PINID='\2\';
NET_NAME
'P5E_CPU0_P2_TX_BUF_DP<14>'
 '@T6G_MB_LIB.T6G(SCH_1):P5E_CPU0_P2_TX_BUF_DP'<14>:
 C_SIGNAL='@t6g_mb_lib.t6g(sch_1):p5e_cpu0_p2_tx_buf_dp(14)';
NODE_NAME     U6012 W7
 '@T6G_MB_LIB.T6G(SCH_1):PAGE418_I47@PURE_QUANTA.PT5161LRS(CHIPS)':
 'B_PETP1': CDS_PINID='B_PETP1';
NODE_NAME     C6593 2
 '@T6G_MB_LIB.T6G(SCH_1):PAGE418_I91@PURE_QUANTA.Q_CAP_DIFFBUS(CHIPS)':
 '2': CDS_PINID='\2\';
NET_NAME
'P5E_CPU0_P2_TX_BUF_DP<15>'
 '@T6G_MB_LIB.T6G(SCH_1):P5E_CPU0_P2_TX_BUF_DP'<15>:
 C_SIGNAL='@t6g_mb_lib.t6g(sch_1):p5e_cpu0_p2_tx_buf_dp(15)';
NODE_NAME     U6012 M7
 '@T6G_MB_LIB.T6G(SCH_1):PAGE418_I47@PURE_QUANTA.PT5161LRS(CHIPS)':
 'B_PETP0': CDS_PINID='B_PETP0';
NODE_NAME     C6595 2
 '@T6G_MB_LIB.T6G(SCH_1):PAGE418_I89@PURE_QUANTA.Q_CAP_DIFFBUS(CHIPS)':
 '2': CDS_PINID='\2\';
NET_NAME
'P5E_CPU0_P2_TX_BUF_DP<1>'
 '@T6G_MB_LIB.T6G(SCH_1):P5E_CPU0_P2_TX_BUF_DP'<1>:
 C_SIGNAL='@t6g_mb_lib.t6g(sch_1):p5e_cpu0_p2_tx_buf_dp(1)';
NODE_NAME     C6567 2
 '@T6G_MB_LIB.T6G(SCH_1):PAGE418_I32@PURE_QUANTA.Q_CAP_DIFFBUS(CHIPS)':
 '2': CDS_PINID='\2\';
NODE_NAME     U6012 EK7
 '@T6G_MB_LIB.T6G(SCH_1):PAGE418_I142@PURE_QUANTA.PT5161LRS(CHIPS)':
 'B_PETP14': CDS_PINID='B_PETP14';
NET_NAME
'P5E_CPU0_P2_TX_BUF_DP<2>'
 '@T6G_MB_LIB.T6G(SCH_1):P5E_CPU0_P2_TX_BUF_DP'<2>:
 C_SIGNAL='@t6g_mb_lib.t6g(sch_1):p5e_cpu0_p2_tx_buf_dp(2)';
NODE_NAME     C6569 2
 '@T6G_MB_LIB.T6G(SCH_1):PAGE418_I34@PURE_QUANTA.Q_CAP_DIFFBUS(CHIPS)':
 '2': CDS_PINID='\2\';
NODE_NAME     U6012 EC7
 '@T6G_MB_LIB.T6G(SCH_1):PAGE418_I142@PURE_QUANTA.PT5161LRS(CHIPS)':
 'B_PETP13': CDS_PINID='B_PETP13';
NET_NAME
'P5E_CPU0_P2_TX_BUF_DP<3>'
 '@T6G_MB_LIB.T6G(SCH_1):P5E_CPU0_P2_TX_BUF_DP'<3>:
 C_SIGNAL='@t6g_mb_lib.t6g(sch_1):p5e_cpu0_p2_tx_buf_dp(3)';
NODE_NAME     C6571 2
 '@T6G_MB_LIB.T6G(SCH_1):PAGE418_I30@PURE_QUANTA.Q_CAP_DIFFBUS(CHIPS)':
 '2': CDS_PINID='\2\';
NODE_NAME     U6012 DT7
 '@T6G_MB_LIB.T6G(SCH_1):PAGE418_I142@PURE_QUANTA.PT5161LRS(CHIPS)':
 'B_PETP12': CDS_PINID='B_PETP12';
NET_NAME
'P5E_CPU0_P2_TX_BUF_DP<4>'
 '@T6G_MB_LIB.T6G(SCH_1):P5E_CPU0_P2_TX_BUF_DP'<4>:
 C_SIGNAL='@t6g_mb_lib.t6g(sch_1):p5e_cpu0_p2_tx_buf_dp(4)';
NODE_NAME     C6573 2
 '@T6G_MB_LIB.T6G(SCH_1):PAGE418_I27@PURE_QUANTA.Q_CAP_DIFFBUS(CHIPS)':
 '2': CDS_PINID='\2\';
NODE_NAME     U6012 DJ7
 '@T6G_MB_LIB.T6G(SCH_1):PAGE418_I142@PURE_QUANTA.PT5161LRS(CHIPS)':
 'B_PETP11': CDS_PINID='B_PETP11';
NET_NAME
'P5E_CPU0_P2_TX_BUF_DP<5>'
 '@T6G_MB_LIB.T6G(SCH_1):P5E_CPU0_P2_TX_BUF_DP'<5>:
 C_SIGNAL='@t6g_mb_lib.t6g(sch_1):p5e_cpu0_p2_tx_buf_dp(5)';
NODE_NAME     C6575 2
 '@T6G_MB_LIB.T6G(SCH_1):PAGE418_I25@PURE_QUANTA.Q_CAP_DIFFBUS(CHIPS)':
 '2': CDS_PINID='\2\';
NODE_NAME     U6012 DB7
 '@T6G_MB_LIB.T6G(SCH_1):PAGE418_I142@PURE_QUANTA.PT5161LRS(CHIPS)':
 'B_PETP10': CDS_PINID='B_PETP10';
NET_NAME
'P5E_CPU0_P2_TX_BUF_DP<6>'
 '@T6G_MB_LIB.T6G(SCH_1):P5E_CPU0_P2_TX_BUF_DP'<6>:
 C_SIGNAL='@t6g_mb_lib.t6g(sch_1):p5e_cpu0_p2_tx_buf_dp(6)';
NODE_NAME     C6577 2
 '@T6G_MB_LIB.T6G(SCH_1):PAGE418_I19@PURE_QUANTA.Q_CAP_DIFFBUS(CHIPS)':
 '2': CDS_PINID='\2\';
NODE_NAME     U6012 CR7
 '@T6G_MB_LIB.T6G(SCH_1):PAGE418_I142@PURE_QUANTA.PT5161LRS(CHIPS)':
 'B_PETP9': CDS_PINID='B_PETP9';
NET_NAME
'P5E_CPU0_P2_TX_BUF_DP<7>'
 '@T6G_MB_LIB.T6G(SCH_1):P5E_CPU0_P2_TX_BUF_DP'<7>:
 C_SIGNAL='@t6g_mb_lib.t6g(sch_1):p5e_cpu0_p2_tx_buf_dp(7)';
NODE_NAME     C6579 2
 '@T6G_MB_LIB.T6G(SCH_1):PAGE418_I18@PURE_QUANTA.Q_CAP_DIFFBUS(CHIPS)':
 '2': CDS_PINID='\2\';
NODE_NAME     U6012 CH7
 '@T6G_MB_LIB.T6G(SCH_1):PAGE418_I142@PURE_QUANTA.PT5161LRS(CHIPS)':
 'B_PETP8': CDS_PINID='B_PETP8';
NET_NAME
'P5E_CPU0_P2_TX_BUF_DP<8>'
 '@T6G_MB_LIB.T6G(SCH_1):P5E_CPU0_P2_TX_BUF_DP'<8>:
 C_SIGNAL='@t6g_mb_lib.t6g(sch_1):p5e_cpu0_p2_tx_buf_dp(8)';
NODE_NAME     U6012 CA7
 '@T6G_MB_LIB.T6G(SCH_1):PAGE418_I47@PURE_QUANTA.PT5161LRS(CHIPS)':
 'B_PETP7': CDS_PINID='B_PETP7';
NODE_NAME     C6581 2
 '@T6G_MB_LIB.T6G(SCH_1):PAGE418_I104@PURE_QUANTA.Q_CAP_DIFFBUS(CHIPS)':
 '2': CDS_PINID='\2\';
NET_NAME
'P5E_CPU0_P2_TX_BUF_DP<9>'
 '@T6G_MB_LIB.T6G(SCH_1):P5E_CPU0_P2_TX_BUF_DP'<9>:
 C_SIGNAL='@t6g_mb_lib.t6g(sch_1):p5e_cpu0_p2_tx_buf_dp(9)';
NODE_NAME     U6012 BP7
 '@T6G_MB_LIB.T6G(SCH_1):PAGE418_I47@PURE_QUANTA.PT5161LRS(CHIPS)':
 'B_PETP6': CDS_PINID='B_PETP6';
NODE_NAME     C6583 2
 '@T6G_MB_LIB.T6G(SCH_1):PAGE418_I101@PURE_QUANTA.Q_CAP_DIFFBUS(CHIPS)':
 '2': CDS_PINID='\2\';
NET_NAME
'P5E_CPU0_P2_TX_C_DN<0>'
 '@T6G_MB_LIB.T6G(SCH_1):P5E_CPU0_P2_TX_C_DN'<0>:
 C_SIGNAL='@t6g_mb_lib.t6g(sch_1):p5e_cpu0_p2_tx_c_dn(0)';
NODE_NAME     C868 1
 '@T6G_MB_LIB.T6G(SCH_1):PAGE352_I22@PURE_QUANTA.Q_CAP_DIFFBUS(CHIPS)':
 '1': CDS_PINID='\1\';
NODE_NAME     U6012 EV34
 '@T6G_MB_LIB.T6G(SCH_1):PAGE415_I37@PURE_QUANTA.PT5161LRS(CHIPS)':
 'B_PERP15': CDS_PINID='B_PERP15';
NET_NAME
'P5E_CPU0_P2_TX_C_DN<10>'
 '@T6G_MB_LIB.T6G(SCH_1):P5E_CPU0_P2_TX_C_DN'<10>:
 C_SIGNAL='@t6g_mb_lib.t6g(sch_1):p5e_cpu0_p2_tx_c_dn(10)';
NODE_NAME     C848 1
 '@T6G_MB_LIB.T6G(SCH_1):PAGE352_I66@PURE_QUANTA.Q_CAP_DIFFBUS(CHIPS)':
 '1': CDS_PINID='\1\';
NODE_NAME     U6012 BH34
 '@T6G_MB_LIB.T6G(SCH_1):PAGE415_I38@PURE_QUANTA.PT5161LRS(CHIPS)':
 'B_PERP5': CDS_PINID='B_PERP5';
NET_NAME
'P5E_CPU0_P2_TX_C_DN<11>'
 '@T6G_MB_LIB.T6G(SCH_1):P5E_CPU0_P2_TX_C_DN'<11>:
 C_SIGNAL='@t6g_mb_lib.t6g(sch_1):p5e_cpu0_p2_tx_c_dn(11)';
NODE_NAME     C846 1
 '@T6G_MB_LIB.T6G(SCH_1):PAGE352_I68@PURE_QUANTA.Q_CAP_DIFFBUS(CHIPS)':
 '1': CDS_PINID='\1\';
NODE_NAME     U6012 BA34
 '@T6G_MB_LIB.T6G(SCH_1):PAGE415_I38@PURE_QUANTA.PT5161LRS(CHIPS)':
 'B_PERP4': CDS_PINID='B_PERP4';
NET_NAME
'P5E_CPU0_P2_TX_C_DN<12>'
 '@T6G_MB_LIB.T6G(SCH_1):P5E_CPU0_P2_TX_C_DN'<12>:
 C_SIGNAL='@t6g_mb_lib.t6g(sch_1):p5e_cpu0_p2_tx_c_dn(12)';
NODE_NAME     C844 1
 '@T6G_MB_LIB.T6G(SCH_1):PAGE352_I70@PURE_QUANTA.Q_CAP_DIFFBUS(CHIPS)':
 '1': CDS_PINID='\1\';
NODE_NAME     U6012 AP34
 '@T6G_MB_LIB.T6G(SCH_1):PAGE415_I38@PURE_QUANTA.PT5161LRS(CHIPS)':
 'B_PERP3': CDS_PINID='B_PERP3';
NET_NAME
'P5E_CPU0_P2_TX_C_DN<13>'
 '@T6G_MB_LIB.T6G(SCH_1):P5E_CPU0_P2_TX_C_DN'<13>:
 C_SIGNAL='@t6g_mb_lib.t6g(sch_1):p5e_cpu0_p2_tx_c_dn(13)';
NODE_NAME     C842 1
 '@T6G_MB_LIB.T6G(SCH_1):PAGE352_I76@PURE_QUANTA.Q_CAP_DIFFBUS(CHIPS)':
 '1': CDS_PINID='\1\';
NODE_NAME     U6012 AG34
 '@T6G_MB_LIB.T6G(SCH_1):PAGE415_I38@PURE_QUANTA.PT5161LRS(CHIPS)':
 'B_PERP2': CDS_PINID='B_PERP2';
NET_NAME
'P5E_CPU0_P2_TX_C_DN<14>'
 '@T6G_MB_LIB.T6G(SCH_1):P5E_CPU0_P2_TX_C_DN'<14>:
 C_SIGNAL='@t6g_mb_lib.t6g(sch_1):p5e_cpu0_p2_tx_c_dn(14)';
NODE_NAME     C840 1
 '@T6G_MB_LIB.T6G(SCH_1):PAGE352_I79@PURE_QUANTA.Q_CAP_DIFFBUS(CHIPS)':
 '1': CDS_PINID='\1\';
NODE_NAME     U6012 Y34
 '@T6G_MB_LIB.T6G(SCH_1):PAGE415_I38@PURE_QUANTA.PT5161LRS(CHIPS)':
 'B_PERP1': CDS_PINID='B_PERP1';
NET_NAME
'P5E_CPU0_P2_TX_C_DN<15>'
 '@T6G_MB_LIB.T6G(SCH_1):P5E_CPU0_P2_TX_C_DN'<15>:
 C_SIGNAL='@t6g_mb_lib.t6g(sch_1):p5e_cpu0_p2_tx_c_dn(15)';
NODE_NAME     C838 1
 '@T6G_MB_LIB.T6G(SCH_1):PAGE352_I80@PURE_QUANTA.Q_CAP_DIFFBUS(CHIPS)':
 '1': CDS_PINID='\1\';
NODE_NAME     U6012 N34
 '@T6G_MB_LIB.T6G(SCH_1):PAGE415_I38@PURE_QUANTA.PT5161LRS(CHIPS)':
 'B_PERP0': CDS_PINID='B_PERP0';
NET_NAME
'P5E_CPU0_P2_TX_C_DN<1>'
 '@T6G_MB_LIB.T6G(SCH_1):P5E_CPU0_P2_TX_C_DN'<1>:
 C_SIGNAL='@t6g_mb_lib.t6g(sch_1):p5e_cpu0_p2_tx_c_dn(1)';
NODE_NAME     C866 1
 '@T6G_MB_LIB.T6G(SCH_1):PAGE352_I24@PURE_QUANTA.Q_CAP_DIFFBUS(CHIPS)':
 '1': CDS_PINID='\1\';
NODE_NAME     U6012 EN35
 '@T6G_MB_LIB.T6G(SCH_1):PAGE415_I37@PURE_QUANTA.PT5161LRS(CHIPS)':
 'B_PERN14': CDS_PINID='B_PERN14';
NET_NAME
'P5E_CPU0_P2_TX_C_DN<2>'
 '@T6G_MB_LIB.T6G(SCH_1):P5E_CPU0_P2_TX_C_DN'<2>:
 C_SIGNAL='@t6g_mb_lib.t6g(sch_1):p5e_cpu0_p2_tx_c_dn(2)';
NODE_NAME     C864 1
 '@T6G_MB_LIB.T6G(SCH_1):PAGE352_I25@PURE_QUANTA.Q_CAP_DIFFBUS(CHIPS)':
 '1': CDS_PINID='\1\';
NODE_NAME     U6012 ED34
 '@T6G_MB_LIB.T6G(SCH_1):PAGE415_I37@PURE_QUANTA.PT5161LRS(CHIPS)':
 'B_PERP13': CDS_PINID='B_PERP13';
NET_NAME
'P5E_CPU0_P2_TX_C_DN<3>'
 '@T6G_MB_LIB.T6G(SCH_1):P5E_CPU0_P2_TX_C_DN'<3>:
 C_SIGNAL='@t6g_mb_lib.t6g(sch_1):p5e_cpu0_p2_tx_c_dn(3)';
NODE_NAME     C862 1
 '@T6G_MB_LIB.T6G(SCH_1):PAGE352_I28@PURE_QUANTA.Q_CAP_DIFFBUS(CHIPS)':
 '1': CDS_PINID='\1\';
NODE_NAME     U6012 DU34
 '@T6G_MB_LIB.T6G(SCH_1):PAGE415_I37@PURE_QUANTA.PT5161LRS(CHIPS)':
 'B_PERP12': CDS_PINID='B_PERP12';
NET_NAME
'P5E_CPU0_P2_TX_C_DN<4>'
 '@T6G_MB_LIB.T6G(SCH_1):P5E_CPU0_P2_TX_C_DN'<4>:
 C_SIGNAL='@t6g_mb_lib.t6g(sch_1):p5e_cpu0_p2_tx_c_dn(4)';
NODE_NAME     C860 1
 '@T6G_MB_LIB.T6G(SCH_1):PAGE352_I30@PURE_QUANTA.Q_CAP_DIFFBUS(CHIPS)':
 '1': CDS_PINID='\1\';
NODE_NAME     U6012 DK34
 '@T6G_MB_LIB.T6G(SCH_1):PAGE415_I37@PURE_QUANTA.PT5161LRS(CHIPS)':
 'B_PERP11': CDS_PINID='B_PERP11';
NET_NAME
'P5E_CPU0_P2_TX_C_DN<5>'
 '@T6G_MB_LIB.T6G(SCH_1):P5E_CPU0_P2_TX_C_DN'<5>:
 C_SIGNAL='@t6g_mb_lib.t6g(sch_1):p5e_cpu0_p2_tx_c_dn(5)';
NODE_NAME     C858 1
 '@T6G_MB_LIB.T6G(SCH_1):PAGE352_I37@PURE_QUANTA.Q_CAP_DIFFBUS(CHIPS)':
 '1': CDS_PINID='\1\';
NODE_NAME     U6012 DC34
 '@T6G_MB_LIB.T6G(SCH_1):PAGE415_I37@PURE_QUANTA.PT5161LRS(CHIPS)':
 'B_PERP10': CDS_PINID='B_PERP10';
NET_NAME
'P5E_CPU0_P2_TX_C_DN<6>'
 '@T6G_MB_LIB.T6G(SCH_1):P5E_CPU0_P2_TX_C_DN'<6>:
 C_SIGNAL='@t6g_mb_lib.t6g(sch_1):p5e_cpu0_p2_tx_c_dn(6)';
NODE_NAME     C856 1
 '@T6G_MB_LIB.T6G(SCH_1):PAGE352_I39@PURE_QUANTA.Q_CAP_DIFFBUS(CHIPS)':
 '1': CDS_PINID='\1\';
NODE_NAME     U6012 CT34
 '@T6G_MB_LIB.T6G(SCH_1):PAGE415_I37@PURE_QUANTA.PT5161LRS(CHIPS)':
 'B_PERP9': CDS_PINID='B_PERP9';
NET_NAME
'P5E_CPU0_P2_TX_C_DN<7>'
 '@T6G_MB_LIB.T6G(SCH_1):P5E_CPU0_P2_TX_C_DN'<7>:
 C_SIGNAL='@t6g_mb_lib.t6g(sch_1):p5e_cpu0_p2_tx_c_dn(7)';
NODE_NAME     C854 1
 '@T6G_MB_LIB.T6G(SCH_1):PAGE352_I41@PURE_QUANTA.Q_CAP_DIFFBUS(CHIPS)':
 '1': CDS_PINID='\1\';
NODE_NAME     U6012 CJ34
 '@T6G_MB_LIB.T6G(SCH_1):PAGE415_I37@PURE_QUANTA.PT5161LRS(CHIPS)':
 'B_PERP8': CDS_PINID='B_PERP8';
NET_NAME
'P5E_CPU0_P2_TX_C_DN<8>'
 '@T6G_MB_LIB.T6G(SCH_1):P5E_CPU0_P2_TX_C_DN'<8>:
 C_SIGNAL='@t6g_mb_lib.t6g(sch_1):p5e_cpu0_p2_tx_c_dn(8)';
NODE_NAME     C852 1
 '@T6G_MB_LIB.T6G(SCH_1):PAGE352_I61@PURE_QUANTA.Q_CAP_DIFFBUS(CHIPS)':
 '1': CDS_PINID='\1\';
NODE_NAME     U6012 CB34
 '@T6G_MB_LIB.T6G(SCH_1):PAGE415_I38@PURE_QUANTA.PT5161LRS(CHIPS)':
 'B_PERP7': CDS_PINID='B_PERP7';
NET_NAME
'P5E_CPU0_P2_TX_C_DN<9>'
 '@T6G_MB_LIB.T6G(SCH_1):P5E_CPU0_P2_TX_C_DN'<9>:
 C_SIGNAL='@t6g_mb_lib.t6g(sch_1):p5e_cpu0_p2_tx_c_dn(9)';
NODE_NAME     C850 1
 '@T6G_MB_LIB.T6G(SCH_1):PAGE352_I64@PURE_QUANTA.Q_CAP_DIFFBUS(CHIPS)':
 '1': CDS_PINID='\1\';
NODE_NAME     U6012 BR34
 '@T6G_MB_LIB.T6G(SCH_1):PAGE415_I38@PURE_QUANTA.PT5161LRS(CHIPS)':
 'B_PERP6': CDS_PINID='B_PERP6';
NET_NAME
'P5E_CPU0_P2_TX_C_DP<0>'
 '@T6G_MB_LIB.T6G(SCH_1):P5E_CPU0_P2_TX_C_DP'<0>:
 C_SIGNAL='@t6g_mb_lib.t6g(sch_1):p5e_cpu0_p2_tx_c_dp(0)';
NODE_NAME     C869 1
 '@T6G_MB_LIB.T6G(SCH_1):PAGE352_I21@PURE_QUANTA.Q_CAP_DIFFBUS(CHIPS)':
 '1': CDS_PINID='\1\';
NODE_NAME     U6012 EY35
 '@T6G_MB_LIB.T6G(SCH_1):PAGE415_I37@PURE_QUANTA.PT5161LRS(CHIPS)':
 'B_PERN15': CDS_PINID='B_PERN15';
NET_NAME
'P5E_CPU0_P2_TX_C_DP<10>'
 '@T6G_MB_LIB.T6G(SCH_1):P5E_CPU0_P2_TX_C_DP'<10>:
 C_SIGNAL='@t6g_mb_lib.t6g(sch_1):p5e_cpu0_p2_tx_c_dp(10)';
NODE_NAME     C849 1
 '@T6G_MB_LIB.T6G(SCH_1):PAGE352_I65@PURE_QUANTA.Q_CAP_DIFFBUS(CHIPS)':
 '1': CDS_PINID='\1\';
NODE_NAME     U6012 BK35
 '@T6G_MB_LIB.T6G(SCH_1):PAGE415_I38@PURE_QUANTA.PT5161LRS(CHIPS)':
 'B_PERN5': CDS_PINID='B_PERN5';
NET_NAME
'P5E_CPU0_P2_TX_C_DP<11>'
 '@T6G_MB_LIB.T6G(SCH_1):P5E_CPU0_P2_TX_C_DP'<11>:
 C_SIGNAL='@t6g_mb_lib.t6g(sch_1):p5e_cpu0_p2_tx_c_dp(11)';
NODE_NAME     C847 1
 '@T6G_MB_LIB.T6G(SCH_1):PAGE352_I67@PURE_QUANTA.Q_CAP_DIFFBUS(CHIPS)':
 '1': CDS_PINID='\1\';
NODE_NAME     U6012 BC35
 '@T6G_MB_LIB.T6G(SCH_1):PAGE415_I38@PURE_QUANTA.PT5161LRS(CHIPS)':
 'B_PERN4': CDS_PINID='B_PERN4';
NET_NAME
'P5E_CPU0_P2_TX_C_DP<12>'
 '@T6G_MB_LIB.T6G(SCH_1):P5E_CPU0_P2_TX_C_DP'<12>:
 C_SIGNAL='@t6g_mb_lib.t6g(sch_1):p5e_cpu0_p2_tx_c_dp(12)';
NODE_NAME     C845 1
 '@T6G_MB_LIB.T6G(SCH_1):PAGE352_I69@PURE_QUANTA.Q_CAP_DIFFBUS(CHIPS)':
 '1': CDS_PINID='\1\';
NODE_NAME     U6012 AT35
 '@T6G_MB_LIB.T6G(SCH_1):PAGE415_I38@PURE_QUANTA.PT5161LRS(CHIPS)':
 'B_PERN3': CDS_PINID='B_PERN3';
NET_NAME
'P5E_CPU0_P2_TX_C_DP<13>'
 '@T6G_MB_LIB.T6G(SCH_1):P5E_CPU0_P2_TX_C_DP'<13>:
 C_SIGNAL='@t6g_mb_lib.t6g(sch_1):p5e_cpu0_p2_tx_c_dp(13)';
NODE_NAME     C843 1
 '@T6G_MB_LIB.T6G(SCH_1):PAGE352_I77@PURE_QUANTA.Q_CAP_DIFFBUS(CHIPS)':
 '1': CDS_PINID='\1\';
NODE_NAME     U6012 AJ35
 '@T6G_MB_LIB.T6G(SCH_1):PAGE415_I38@PURE_QUANTA.PT5161LRS(CHIPS)':
 'B_PERN2': CDS_PINID='B_PERN2';
NET_NAME
'P5E_CPU0_P2_TX_C_DP<14>'
 '@T6G_MB_LIB.T6G(SCH_1):P5E_CPU0_P2_TX_C_DP'<14>:
 C_SIGNAL='@t6g_mb_lib.t6g(sch_1):p5e_cpu0_p2_tx_c_dp(14)';
NODE_NAME     C841 1
 '@T6G_MB_LIB.T6G(SCH_1):PAGE352_I78@PURE_QUANTA.Q_CAP_DIFFBUS(CHIPS)':
 '1': CDS_PINID='\1\';
NODE_NAME     U6012 AB35
 '@T6G_MB_LIB.T6G(SCH_1):PAGE415_I38@PURE_QUANTA.PT5161LRS(CHIPS)':
 'B_PERN1': CDS_PINID='B_PERN1';
NET_NAME
'P5E_CPU0_P2_TX_C_DP<15>'
 '@T6G_MB_LIB.T6G(SCH_1):P5E_CPU0_P2_TX_C_DP'<15>:
 C_SIGNAL='@t6g_mb_lib.t6g(sch_1):p5e_cpu0_p2_tx_c_dp(15)';
NODE_NAME     C839 1
 '@T6G_MB_LIB.T6G(SCH_1):PAGE352_I81@PURE_QUANTA.Q_CAP_DIFFBUS(CHIPS)':
 '1': CDS_PINID='\1\';
NODE_NAME     U6012 R35
 '@T6G_MB_LIB.T6G(SCH_1):PAGE415_I38@PURE_QUANTA.PT5161LRS(CHIPS)':
 'B_PERN0': CDS_PINID='B_PERN0';
NET_NAME
'P5E_CPU0_P2_TX_C_DP<1>'
 '@T6G_MB_LIB.T6G(SCH_1):P5E_CPU0_P2_TX_C_DP'<1>:
 C_SIGNAL='@t6g_mb_lib.t6g(sch_1):p5e_cpu0_p2_tx_c_dp(1)';
NODE_NAME     C867 1
 '@T6G_MB_LIB.T6G(SCH_1):PAGE352_I23@PURE_QUANTA.Q_CAP_DIFFBUS(CHIPS)':
 '1': CDS_PINID='\1\';
NODE_NAME     U6012 EL34
 '@T6G_MB_LIB.T6G(SCH_1):PAGE415_I37@PURE_QUANTA.PT5161LRS(CHIPS)':
 'B_PERP14': CDS_PINID='B_PERP14';
NET_NAME
'P5E_CPU0_P2_TX_C_DP<2>'
 '@T6G_MB_LIB.T6G(SCH_1):P5E_CPU0_P2_TX_C_DP'<2>:
 C_SIGNAL='@t6g_mb_lib.t6g(sch_1):p5e_cpu0_p2_tx_c_dp(2)';
NODE_NAME     C865 1
 '@T6G_MB_LIB.T6G(SCH_1):PAGE352_I26@PURE_QUANTA.Q_CAP_DIFFBUS(CHIPS)':
 '1': CDS_PINID='\1\';
NODE_NAME     U6012 EF35
 '@T6G_MB_LIB.T6G(SCH_1):PAGE415_I37@PURE_QUANTA.PT5161LRS(CHIPS)':
 'B_PERN13': CDS_PINID='B_PERN13';
NET_NAME
'P5E_CPU0_P2_TX_C_DP<3>'
 '@T6G_MB_LIB.T6G(SCH_1):P5E_CPU0_P2_TX_C_DP'<3>:
 C_SIGNAL='@t6g_mb_lib.t6g(sch_1):p5e_cpu0_p2_tx_c_dp(3)';
NODE_NAME     C863 1
 '@T6G_MB_LIB.T6G(SCH_1):PAGE352_I27@PURE_QUANTA.Q_CAP_DIFFBUS(CHIPS)':
 '1': CDS_PINID='\1\';
NODE_NAME     U6012 DW35
 '@T6G_MB_LIB.T6G(SCH_1):PAGE415_I37@PURE_QUANTA.PT5161LRS(CHIPS)':
 'B_PERN12': CDS_PINID='B_PERN12';
NET_NAME
'P5E_CPU0_P2_TX_C_DP<4>'
 '@T6G_MB_LIB.T6G(SCH_1):P5E_CPU0_P2_TX_C_DP'<4>:
 C_SIGNAL='@t6g_mb_lib.t6g(sch_1):p5e_cpu0_p2_tx_c_dp(4)';
NODE_NAME     C861 1
 '@T6G_MB_LIB.T6G(SCH_1):PAGE352_I29@PURE_QUANTA.Q_CAP_DIFFBUS(CHIPS)':
 '1': CDS_PINID='\1\';
NODE_NAME     U6012 DM35
 '@T6G_MB_LIB.T6G(SCH_1):PAGE415_I37@PURE_QUANTA.PT5161LRS(CHIPS)':
 'B_PERN11': CDS_PINID='B_PERN11';
NET_NAME
'P5E_CPU0_P2_TX_C_DP<5>'
 '@T6G_MB_LIB.T6G(SCH_1):P5E_CPU0_P2_TX_C_DP'<5>:
 C_SIGNAL='@t6g_mb_lib.t6g(sch_1):p5e_cpu0_p2_tx_c_dp(5)';
NODE_NAME     C859 1
 '@T6G_MB_LIB.T6G(SCH_1):PAGE352_I36@PURE_QUANTA.Q_CAP_DIFFBUS(CHIPS)':
 '1': CDS_PINID='\1\';
NODE_NAME     U6012 DE35
 '@T6G_MB_LIB.T6G(SCH_1):PAGE415_I37@PURE_QUANTA.PT5161LRS(CHIPS)':
 'B_PERN10': CDS_PINID='B_PERN10';
NET_NAME
'P5E_CPU0_P2_TX_C_DP<6>'
 '@T6G_MB_LIB.T6G(SCH_1):P5E_CPU0_P2_TX_C_DP'<6>:
 C_SIGNAL='@t6g_mb_lib.t6g(sch_1):p5e_cpu0_p2_tx_c_dp(6)';
NODE_NAME     C857 1
 '@T6G_MB_LIB.T6G(SCH_1):PAGE352_I38@PURE_QUANTA.Q_CAP_DIFFBUS(CHIPS)':
 '1': CDS_PINID='\1\';
NODE_NAME     U6012 CV35
 '@T6G_MB_LIB.T6G(SCH_1):PAGE415_I37@PURE_QUANTA.PT5161LRS(CHIPS)':
 'B_PERN9': CDS_PINID='B_PERN9';
NET_NAME
'P5E_CPU0_P2_TX_C_DP<7>'
 '@T6G_MB_LIB.T6G(SCH_1):P5E_CPU0_P2_TX_C_DP'<7>:
 C_SIGNAL='@t6g_mb_lib.t6g(sch_1):p5e_cpu0_p2_tx_c_dp(7)';
NODE_NAME     C855 1
 '@T6G_MB_LIB.T6G(SCH_1):PAGE352_I40@PURE_QUANTA.Q_CAP_DIFFBUS(CHIPS)':
 '1': CDS_PINID='\1\';
NODE_NAME     U6012 CL35
 '@T6G_MB_LIB.T6G(SCH_1):PAGE415_I37@PURE_QUANTA.PT5161LRS(CHIPS)':
 'B_PERN8': CDS_PINID='B_PERN8';
NET_NAME
'P5E_CPU0_P2_TX_C_DP<8>'
 '@T6G_MB_LIB.T6G(SCH_1):P5E_CPU0_P2_TX_C_DP'<8>:
 C_SIGNAL='@t6g_mb_lib.t6g(sch_1):p5e_cpu0_p2_tx_c_dp(8)';
NODE_NAME     C853 1
 '@T6G_MB_LIB.T6G(SCH_1):PAGE352_I62@PURE_QUANTA.Q_CAP_DIFFBUS(CHIPS)':
 '1': CDS_PINID='\1\';
NODE_NAME     U6012 CD35
 '@T6G_MB_LIB.T6G(SCH_1):PAGE415_I38@PURE_QUANTA.PT5161LRS(CHIPS)':
 'B_PERN7': CDS_PINID='B_PERN7';
NET_NAME
'P5E_CPU0_P2_TX_C_DP<9>'
 '@T6G_MB_LIB.T6G(SCH_1):P5E_CPU0_P2_TX_C_DP'<9>:
 C_SIGNAL='@t6g_mb_lib.t6g(sch_1):p5e_cpu0_p2_tx_c_dp(9)';
NODE_NAME     C851 1
 '@T6G_MB_LIB.T6G(SCH_1):PAGE352_I63@PURE_QUANTA.Q_CAP_DIFFBUS(CHIPS)':
 '1': CDS_PINID='\1\';
NODE_NAME     U6012 BU35
 '@T6G_MB_LIB.T6G(SCH_1):PAGE415_I38@PURE_QUANTA.PT5161LRS(CHIPS)':
 'B_PERN6': CDS_PINID='B_PERN6';
NET_NAME
'P5E_CPU0_P2_TX_DN<0>'
 '@T6G_MB_LIB.T6G(SCH_1):P5E_CPU0_P2_TX_DN'<0>:
 C_SIGNAL='@t6g_mb_lib.t6g(sch_1):p5e_cpu0_p2_tx_dn(0)';
NODE_NAME     U25 BT35
 '@T6G_MB_LIB.T6G(SCH_1):PAGE25_I147@PURE_QUANTA.GENOA_SP5(CHIPS)':
 'P2_TXN0': CDS_PINID='P2_TXN0';
NODE_NAME     C868 2
 '@T6G_MB_LIB.T6G(SCH_1):PAGE352_I22@PURE_QUANTA.Q_CAP_DIFFBUS(CHIPS)':
 '2': CDS_PINID='\2\';
NET_NAME
'P5E_CPU0_P2_TX_DN<10>'
 '@T6G_MB_LIB.T6G(SCH_1):P5E_CPU0_P2_TX_DN'<10>:
 C_SIGNAL='@t6g_mb_lib.t6g(sch_1):p5e_cpu0_p2_tx_dn(10)';
NODE_NAME     U25 BU26
 '@T6G_MB_LIB.T6G(SCH_1):PAGE25_I147@PURE_QUANTA.GENOA_SP5(CHIPS)':
 'P2_TXN10': CDS_PINID='P2_TXN10';
NODE_NAME     C848 2
 '@T6G_MB_LIB.T6G(SCH_1):PAGE352_I66@PURE_QUANTA.Q_CAP_DIFFBUS(CHIPS)':
 '2': CDS_PINID='\2\';
NET_NAME
'P5E_CPU0_P2_TX_DN<11>'
 '@T6G_MB_LIB.T6G(SCH_1):P5E_CPU0_P2_TX_DN'<11>:
 C_SIGNAL='@t6g_mb_lib.t6g(sch_1):p5e_cpu0_p2_tx_dn(11)';
NODE_NAME     U25 CA26
 '@T6G_MB_LIB.T6G(SCH_1):PAGE25_I147@PURE_QUANTA.GENOA_SP5(CHIPS)':
 'P2_TXN11': CDS_PINID='P2_TXN11';
NODE_NAME     C846 2
 '@T6G_MB_LIB.T6G(SCH_1):PAGE352_I68@PURE_QUANTA.Q_CAP_DIFFBUS(CHIPS)':
 '2': CDS_PINID='\2\';
NET_NAME
'P5E_CPU0_P2_TX_DN<12>'
 '@T6G_MB_LIB.T6G(SCH_1):P5E_CPU0_P2_TX_DN'<12>:
 C_SIGNAL='@t6g_mb_lib.t6g(sch_1):p5e_cpu0_p2_tx_dn(12)';
NODE_NAME     U25 BW26
 '@T6G_MB_LIB.T6G(SCH_1):PAGE25_I147@PURE_QUANTA.GENOA_SP5(CHIPS)':
 'P2_TXN12': CDS_PINID='P2_TXN12';
NODE_NAME     C844 2
 '@T6G_MB_LIB.T6G(SCH_1):PAGE352_I70@PURE_QUANTA.Q_CAP_DIFFBUS(CHIPS)':
 '2': CDS_PINID='\2\';
NET_NAME
'P5E_CPU0_P2_TX_DN<13>'
 '@T6G_MB_LIB.T6G(SCH_1):P5E_CPU0_P2_TX_DN'<13>:
 C_SIGNAL='@t6g_mb_lib.t6g(sch_1):p5e_cpu0_p2_tx_dn(13)';
NODE_NAME     U25 BU23
 '@T6G_MB_LIB.T6G(SCH_1):PAGE25_I147@PURE_QUANTA.GENOA_SP5(CHIPS)':
 'P2_TXN13': CDS_PINID='P2_TXN13';
NODE_NAME     C842 2
 '@T6G_MB_LIB.T6G(SCH_1):PAGE352_I76@PURE_QUANTA.Q_CAP_DIFFBUS(CHIPS)':
 '2': CDS_PINID='\2\';
NET_NAME
'P5E_CPU0_P2_TX_DN<14>'
 '@T6G_MB_LIB.T6G(SCH_1):P5E_CPU0_P2_TX_DN'<14>:
 C_SIGNAL='@t6g_mb_lib.t6g(sch_1):p5e_cpu0_p2_tx_dn(14)';
NODE_NAME     U25 CA23
 '@T6G_MB_LIB.T6G(SCH_1):PAGE25_I147@PURE_QUANTA.GENOA_SP5(CHIPS)':
 'P2_TXN14': CDS_PINID='P2_TXN14';
NODE_NAME     C840 2
 '@T6G_MB_LIB.T6G(SCH_1):PAGE352_I79@PURE_QUANTA.Q_CAP_DIFFBUS(CHIPS)':
 '2': CDS_PINID='\2\';
NET_NAME
'P5E_CPU0_P2_TX_DN<15>'
 '@T6G_MB_LIB.T6G(SCH_1):P5E_CPU0_P2_TX_DN'<15>:
 C_SIGNAL='@t6g_mb_lib.t6g(sch_1):p5e_cpu0_p2_tx_dn(15)';
NODE_NAME     U25 BW23
 '@T6G_MB_LIB.T6G(SCH_1):PAGE25_I147@PURE_QUANTA.GENOA_SP5(CHIPS)':
 'P2_TXN15': CDS_PINID='P2_TXN15';
NODE_NAME     C838 2
 '@T6G_MB_LIB.T6G(SCH_1):PAGE352_I80@PURE_QUANTA.Q_CAP_DIFFBUS(CHIPS)':
 '2': CDS_PINID='\2\';
NET_NAME
'P5E_CPU0_P2_TX_DN<1>'
 '@T6G_MB_LIB.T6G(SCH_1):P5E_CPU0_P2_TX_DN'<1>:
 C_SIGNAL='@t6g_mb_lib.t6g(sch_1):p5e_cpu0_p2_tx_dn(1)';
NODE_NAME     U25 BV35
 '@T6G_MB_LIB.T6G(SCH_1):PAGE25_I147@PURE_QUANTA.GENOA_SP5(CHIPS)':
 'P2_TXN1': CDS_PINID='P2_TXN1';
NODE_NAME     C866 2
 '@T6G_MB_LIB.T6G(SCH_1):PAGE352_I24@PURE_QUANTA.Q_CAP_DIFFBUS(CHIPS)':
 '2': CDS_PINID='\2\';
NET_NAME
'P5E_CPU0_P2_TX_DN<2>'
 '@T6G_MB_LIB.T6G(SCH_1):P5E_CPU0_P2_TX_DN'<2>:
 C_SIGNAL='@t6g_mb_lib.t6g(sch_1):p5e_cpu0_p2_tx_dn(2)';
NODE_NAME     U25 CB35
 '@T6G_MB_LIB.T6G(SCH_1):PAGE25_I147@PURE_QUANTA.GENOA_SP5(CHIPS)':
 'P2_TXN2': CDS_PINID='P2_TXN2';
NODE_NAME     C864 2
 '@T6G_MB_LIB.T6G(SCH_1):PAGE352_I25@PURE_QUANTA.Q_CAP_DIFFBUS(CHIPS)':
 '2': CDS_PINID='\2\';
NET_NAME
'P5E_CPU0_P2_TX_DN<3>'
 '@T6G_MB_LIB.T6G(SCH_1):P5E_CPU0_P2_TX_DN'<3>:
 C_SIGNAL='@t6g_mb_lib.t6g(sch_1):p5e_cpu0_p2_tx_dn(3)';
NODE_NAME     U25 BY35
 '@T6G_MB_LIB.T6G(SCH_1):PAGE25_I147@PURE_QUANTA.GENOA_SP5(CHIPS)':
 'P2_TXN3': CDS_PINID='P2_TXN3';
NODE_NAME     C862 2
 '@T6G_MB_LIB.T6G(SCH_1):PAGE352_I28@PURE_QUANTA.Q_CAP_DIFFBUS(CHIPS)':
 '2': CDS_PINID='\2\';
NET_NAME
'P5E_CPU0_P2_TX_DN<4>'
 '@T6G_MB_LIB.T6G(SCH_1):P5E_CPU0_P2_TX_DN'<4>:
 C_SIGNAL='@t6g_mb_lib.t6g(sch_1):p5e_cpu0_p2_tx_dn(4)';
NODE_NAME     U25 BU32
 '@T6G_MB_LIB.T6G(SCH_1):PAGE25_I147@PURE_QUANTA.GENOA_SP5(CHIPS)':
 'P2_TXN4': CDS_PINID='P2_TXN4';
NODE_NAME     C860 2
 '@T6G_MB_LIB.T6G(SCH_1):PAGE352_I30@PURE_QUANTA.Q_CAP_DIFFBUS(CHIPS)':
 '2': CDS_PINID='\2\';
NET_NAME
'P5E_CPU0_P2_TX_DN<5>'
 '@T6G_MB_LIB.T6G(SCH_1):P5E_CPU0_P2_TX_DN'<5>:
 C_SIGNAL='@t6g_mb_lib.t6g(sch_1):p5e_cpu0_p2_tx_dn(5)';
NODE_NAME     U25 CA32
 '@T6G_MB_LIB.T6G(SCH_1):PAGE25_I147@PURE_QUANTA.GENOA_SP5(CHIPS)':
 'P2_TXN5': CDS_PINID='P2_TXN5';
NODE_NAME     C858 2
 '@T6G_MB_LIB.T6G(SCH_1):PAGE352_I37@PURE_QUANTA.Q_CAP_DIFFBUS(CHIPS)':
 '2': CDS_PINID='\2\';
NET_NAME
'P5E_CPU0_P2_TX_DN<6>'
 '@T6G_MB_LIB.T6G(SCH_1):P5E_CPU0_P2_TX_DN'<6>:
 C_SIGNAL='@t6g_mb_lib.t6g(sch_1):p5e_cpu0_p2_tx_dn(6)';
NODE_NAME     U25 BW32
 '@T6G_MB_LIB.T6G(SCH_1):PAGE25_I147@PURE_QUANTA.GENOA_SP5(CHIPS)':
 'P2_TXN6': CDS_PINID='P2_TXN6';
NODE_NAME     C856 2
 '@T6G_MB_LIB.T6G(SCH_1):PAGE352_I39@PURE_QUANTA.Q_CAP_DIFFBUS(CHIPS)':
 '2': CDS_PINID='\2\';
NET_NAME
'P5E_CPU0_P2_TX_DN<7>'
 '@T6G_MB_LIB.T6G(SCH_1):P5E_CPU0_P2_TX_DN'<7>:
 C_SIGNAL='@t6g_mb_lib.t6g(sch_1):p5e_cpu0_p2_tx_dn(7)';
NODE_NAME     U25 BU29
 '@T6G_MB_LIB.T6G(SCH_1):PAGE25_I147@PURE_QUANTA.GENOA_SP5(CHIPS)':
 'P2_TXN7': CDS_PINID='P2_TXN7';
NODE_NAME     C854 2
 '@T6G_MB_LIB.T6G(SCH_1):PAGE352_I41@PURE_QUANTA.Q_CAP_DIFFBUS(CHIPS)':
 '2': CDS_PINID='\2\';
NET_NAME
'P5E_CPU0_P2_TX_DN<8>'
 '@T6G_MB_LIB.T6G(SCH_1):P5E_CPU0_P2_TX_DN'<8>:
 C_SIGNAL='@t6g_mb_lib.t6g(sch_1):p5e_cpu0_p2_tx_dn(8)';
NODE_NAME     U25 CA29
 '@T6G_MB_LIB.T6G(SCH_1):PAGE25_I147@PURE_QUANTA.GENOA_SP5(CHIPS)':
 'P2_TXN8': CDS_PINID='P2_TXN8';
NODE_NAME     C852 2
 '@T6G_MB_LIB.T6G(SCH_1):PAGE352_I61@PURE_QUANTA.Q_CAP_DIFFBUS(CHIPS)':
 '2': CDS_PINID='\2\';
NET_NAME
'P5E_CPU0_P2_TX_DN<9>'
 '@T6G_MB_LIB.T6G(SCH_1):P5E_CPU0_P2_TX_DN'<9>:
 C_SIGNAL='@t6g_mb_lib.t6g(sch_1):p5e_cpu0_p2_tx_dn(9)';
NODE_NAME     U25 BW29
 '@T6G_MB_LIB.T6G(SCH_1):PAGE25_I147@PURE_QUANTA.GENOA_SP5(CHIPS)':
 'P2_TXN9': CDS_PINID='P2_TXN9';
NODE_NAME     C850 2
 '@T6G_MB_LIB.T6G(SCH_1):PAGE352_I64@PURE_QUANTA.Q_CAP_DIFFBUS(CHIPS)':
 '2': CDS_PINID='\2\';
NET_NAME
'P5E_CPU0_P2_TX_DP<0>'
 '@T6G_MB_LIB.T6G(SCH_1):P5E_CPU0_P2_TX_DP'<0>:
 C_SIGNAL='@t6g_mb_lib.t6g(sch_1):p5e_cpu0_p2_tx_dp(0)';
NODE_NAME     U25 BT36
 '@T6G_MB_LIB.T6G(SCH_1):PAGE25_I147@PURE_QUANTA.GENOA_SP5(CHIPS)':
 'P2_TXP0': CDS_PINID='P2_TXP0';
NODE_NAME     C869 2
 '@T6G_MB_LIB.T6G(SCH_1):PAGE352_I21@PURE_QUANTA.Q_CAP_DIFFBUS(CHIPS)':
 '2': CDS_PINID='\2\';
NET_NAME
'P5E_CPU0_P2_TX_DP<10>'
 '@T6G_MB_LIB.T6G(SCH_1):P5E_CPU0_P2_TX_DP'<10>:
 C_SIGNAL='@t6g_mb_lib.t6g(sch_1):p5e_cpu0_p2_tx_dp(10)';
NODE_NAME     U25 BU27
 '@T6G_MB_LIB.T6G(SCH_1):PAGE25_I147@PURE_QUANTA.GENOA_SP5(CHIPS)':
 'P2_TXP10': CDS_PINID='P2_TXP10';
NODE_NAME     C849 2
 '@T6G_MB_LIB.T6G(SCH_1):PAGE352_I65@PURE_QUANTA.Q_CAP_DIFFBUS(CHIPS)':
 '2': CDS_PINID='\2\';
NET_NAME
'P5E_CPU0_P2_TX_DP<11>'
 '@T6G_MB_LIB.T6G(SCH_1):P5E_CPU0_P2_TX_DP'<11>:
 C_SIGNAL='@t6g_mb_lib.t6g(sch_1):p5e_cpu0_p2_tx_dp(11)';
NODE_NAME     U25 CA27
 '@T6G_MB_LIB.T6G(SCH_1):PAGE25_I147@PURE_QUANTA.GENOA_SP5(CHIPS)':
 'P2_TXP11': CDS_PINID='P2_TXP11';
NODE_NAME     C847 2
 '@T6G_MB_LIB.T6G(SCH_1):PAGE352_I67@PURE_QUANTA.Q_CAP_DIFFBUS(CHIPS)':
 '2': CDS_PINID='\2\';
NET_NAME
'P5E_CPU0_P2_TX_DP<12>'
 '@T6G_MB_LIB.T6G(SCH_1):P5E_CPU0_P2_TX_DP'<12>:
 C_SIGNAL='@t6g_mb_lib.t6g(sch_1):p5e_cpu0_p2_tx_dp(12)';
NODE_NAME     U25 BW27
 '@T6G_MB_LIB.T6G(SCH_1):PAGE25_I147@PURE_QUANTA.GENOA_SP5(CHIPS)':
 'P2_TXP12': CDS_PINID='P2_TXP12';
NODE_NAME     C845 2
 '@T6G_MB_LIB.T6G(SCH_1):PAGE352_I69@PURE_QUANTA.Q_CAP_DIFFBUS(CHIPS)':
 '2': CDS_PINID='\2\';
NET_NAME
'P5E_CPU0_P2_TX_DP<13>'
 '@T6G_MB_LIB.T6G(SCH_1):P5E_CPU0_P2_TX_DP'<13>:
 C_SIGNAL='@t6g_mb_lib.t6g(sch_1):p5e_cpu0_p2_tx_dp(13)';
NODE_NAME     U25 BU24
 '@T6G_MB_LIB.T6G(SCH_1):PAGE25_I147@PURE_QUANTA.GENOA_SP5(CHIPS)':
 'P2_TXP13': CDS_PINID='P2_TXP13';
NODE_NAME     C843 2
 '@T6G_MB_LIB.T6G(SCH_1):PAGE352_I77@PURE_QUANTA.Q_CAP_DIFFBUS(CHIPS)':
 '2': CDS_PINID='\2\';
NET_NAME
'P5E_CPU0_P2_TX_DP<14>'
 '@T6G_MB_LIB.T6G(SCH_1):P5E_CPU0_P2_TX_DP'<14>:
 C_SIGNAL='@t6g_mb_lib.t6g(sch_1):p5e_cpu0_p2_tx_dp(14)';
NODE_NAME     U25 CA24
 '@T6G_MB_LIB.T6G(SCH_1):PAGE25_I147@PURE_QUANTA.GENOA_SP5(CHIPS)':
 'P2_TXP14': CDS_PINID='P2_TXP14';
NODE_NAME     C841 2
 '@T6G_MB_LIB.T6G(SCH_1):PAGE352_I78@PURE_QUANTA.Q_CAP_DIFFBUS(CHIPS)':
 '2': CDS_PINID='\2\';
NET_NAME
'P5E_CPU0_P2_TX_DP<15>'
 '@T6G_MB_LIB.T6G(SCH_1):P5E_CPU0_P2_TX_DP'<15>:
 C_SIGNAL='@t6g_mb_lib.t6g(sch_1):p5e_cpu0_p2_tx_dp(15)';
NODE_NAME     U25 BW24
 '@T6G_MB_LIB.T6G(SCH_1):PAGE25_I147@PURE_QUANTA.GENOA_SP5(CHIPS)':
 'P2_TXP15': CDS_PINID='P2_TXP15';
NODE_NAME     C839 2
 '@T6G_MB_LIB.T6G(SCH_1):PAGE352_I81@PURE_QUANTA.Q_CAP_DIFFBUS(CHIPS)':
 '2': CDS_PINID='\2\';
NET_NAME
'P5E_CPU0_P2_TX_DP<1>'
 '@T6G_MB_LIB.T6G(SCH_1):P5E_CPU0_P2_TX_DP'<1>:
 C_SIGNAL='@t6g_mb_lib.t6g(sch_1):p5e_cpu0_p2_tx_dp(1)';
NODE_NAME     U25 BV36
 '@T6G_MB_LIB.T6G(SCH_1):PAGE25_I147@PURE_QUANTA.GENOA_SP5(CHIPS)':
 'P2_TXP1': CDS_PINID='P2_TXP1';
NODE_NAME     C867 2
 '@T6G_MB_LIB.T6G(SCH_1):PAGE352_I23@PURE_QUANTA.Q_CAP_DIFFBUS(CHIPS)':
 '2': CDS_PINID='\2\';
NET_NAME
'P5E_CPU0_P2_TX_DP<2>'
 '@T6G_MB_LIB.T6G(SCH_1):P5E_CPU0_P2_TX_DP'<2>:
 C_SIGNAL='@t6g_mb_lib.t6g(sch_1):p5e_cpu0_p2_tx_dp(2)';
NODE_NAME     U25 CB36
 '@T6G_MB_LIB.T6G(SCH_1):PAGE25_I147@PURE_QUANTA.GENOA_SP5(CHIPS)':
 'P2_TXP2': CDS_PINID='P2_TXP2';
NODE_NAME     C865 2
 '@T6G_MB_LIB.T6G(SCH_1):PAGE352_I26@PURE_QUANTA.Q_CAP_DIFFBUS(CHIPS)':
 '2': CDS_PINID='\2\';
NET_NAME
'P5E_CPU0_P2_TX_DP<3>'
 '@T6G_MB_LIB.T6G(SCH_1):P5E_CPU0_P2_TX_DP'<3>:
 C_SIGNAL='@t6g_mb_lib.t6g(sch_1):p5e_cpu0_p2_tx_dp(3)';
NODE_NAME     U25 BY36
 '@T6G_MB_LIB.T6G(SCH_1):PAGE25_I147@PURE_QUANTA.GENOA_SP5(CHIPS)':
 'P2_TXP3': CDS_PINID='P2_TXP3';
NODE_NAME     C863 2
 '@T6G_MB_LIB.T6G(SCH_1):PAGE352_I27@PURE_QUANTA.Q_CAP_DIFFBUS(CHIPS)':
 '2': CDS_PINID='\2\';
NET_NAME
'P5E_CPU0_P2_TX_DP<4>'
 '@T6G_MB_LIB.T6G(SCH_1):P5E_CPU0_P2_TX_DP'<4>:
 C_SIGNAL='@t6g_mb_lib.t6g(sch_1):p5e_cpu0_p2_tx_dp(4)';
NODE_NAME     U25 BU33
 '@T6G_MB_LIB.T6G(SCH_1):PAGE25_I147@PURE_QUANTA.GENOA_SP5(CHIPS)':
 'P2_TXP4': CDS_PINID='P2_TXP4';
NODE_NAME     C861 2
 '@T6G_MB_LIB.T6G(SCH_1):PAGE352_I29@PURE_QUANTA.Q_CAP_DIFFBUS(CHIPS)':
 '2': CDS_PINID='\2\';
NET_NAME
'P5E_CPU0_P2_TX_DP<5>'
 '@T6G_MB_LIB.T6G(SCH_1):P5E_CPU0_P2_TX_DP'<5>:
 C_SIGNAL='@t6g_mb_lib.t6g(sch_1):p5e_cpu0_p2_tx_dp(5)';
NODE_NAME     U25 CA33
 '@T6G_MB_LIB.T6G(SCH_1):PAGE25_I147@PURE_QUANTA.GENOA_SP5(CHIPS)':
 'P2_TXP5': CDS_PINID='P2_TXP5';
NODE_NAME     C859 2
 '@T6G_MB_LIB.T6G(SCH_1):PAGE352_I36@PURE_QUANTA.Q_CAP_DIFFBUS(CHIPS)':
 '2': CDS_PINID='\2\';
NET_NAME
'P5E_CPU0_P2_TX_DP<6>'
 '@T6G_MB_LIB.T6G(SCH_1):P5E_CPU0_P2_TX_DP'<6>:
 C_SIGNAL='@t6g_mb_lib.t6g(sch_1):p5e_cpu0_p2_tx_dp(6)';
NODE_NAME     U25 BW33
 '@T6G_MB_LIB.T6G(SCH_1):PAGE25_I147@PURE_QUANTA.GENOA_SP5(CHIPS)':
 'P2_TXP6': CDS_PINID='P2_TXP6';
NODE_NAME     C857 2
 '@T6G_MB_LIB.T6G(SCH_1):PAGE352_I38@PURE_QUANTA.Q_CAP_DIFFBUS(CHIPS)':
 '2': CDS_PINID='\2\';
NET_NAME
'P5E_CPU0_P2_TX_DP<7>'
 '@T6G_MB_LIB.T6G(SCH_1):P5E_CPU0_P2_TX_DP'<7>:
 C_SIGNAL='@t6g_mb_lib.t6g(sch_1):p5e_cpu0_p2_tx_dp(7)';
NODE_NAME     U25 BU30
 '@T6G_MB_LIB.T6G(SCH_1):PAGE25_I147@PURE_QUANTA.GENOA_SP5(CHIPS)':
 'P2_TXP7': CDS_PINID='P2_TXP7';
NODE_NAME     C855 2
 '@T6G_MB_LIB.T6G(SCH_1):PAGE352_I40@PURE_QUANTA.Q_CAP_DIFFBUS(CHIPS)':
 '2': CDS_PINID='\2\';
NET_NAME
'P5E_CPU0_P2_TX_DP<8>'
 '@T6G_MB_LIB.T6G(SCH_1):P5E_CPU0_P2_TX_DP'<8>:
 C_SIGNAL='@t6g_mb_lib.t6g(sch_1):p5e_cpu0_p2_tx_dp(8)';
NODE_NAME     U25 CA30
 '@T6G_MB_LIB.T6G(SCH_1):PAGE25_I147@PURE_QUANTA.GENOA_SP5(CHIPS)':
 'P2_TXP8': CDS_PINID='P2_TXP8';
NODE_NAME     C853 2
 '@T6G_MB_LIB.T6G(SCH_1):PAGE352_I62@PURE_QUANTA.Q_CAP_DIFFBUS(CHIPS)':
 '2': CDS_PINID='\2\';
NET_NAME
'P5E_CPU0_P2_TX_DP<9>'
 '@T6G_MB_LIB.T6G(SCH_1):P5E_CPU0_P2_TX_DP'<9>:
 C_SIGNAL='@t6g_mb_lib.t6g(sch_1):p5e_cpu0_p2_tx_dp(9)';
NODE_NAME     U25 BW30
 '@T6G_MB_LIB.T6G(SCH_1):PAGE25_I147@PURE_QUANTA.GENOA_SP5(CHIPS)':
 'P2_TXP9': CDS_PINID='P2_TXP9';
NODE_NAME     C851 2
 '@T6G_MB_LIB.T6G(SCH_1):PAGE352_I63@PURE_QUANTA.Q_CAP_DIFFBUS(CHIPS)':
 '2': CDS_PINID='\2\';
NET_NAME
'P5E_CPU0_P3_RX_BUF_DN<0>'
 '@T6G_MB_LIB.T6G(SCH_1):P5E_CPU0_P3_RX_BUF_DN'<0>:
 C_SIGNAL='@t6g_mb_lib.t6g(sch_1):p5e_cpu0_p3_rx_buf_dn(0)';
NODE_NAME     U6013 EV2
 '@T6G_MB_LIB.T6G(SCH_1):PAGE428_I38@PURE_QUANTA.PT5161LRS(CHIPS)':
 'A_PERN15': CDS_PINID='A_PERN15';
NODE_NAME     J106 F1
 '@T6G_MB_LIB.T6G(SCH_1):PAGE327_I74@PURE_QUANTA.CONN112_10137002101LF(CHIPS)':
 'F1': CDS_PINID='F1';
NET_NAME
'P5E_CPU0_P3_RX_BUF_DN<10>'
 '@T6G_MB_LIB.T6G(SCH_1):P5E_CPU0_P3_RX_BUF_DN'<10>:
 C_SIGNAL='@t6g_mb_lib.t6g(sch_1):p5e_cpu0_p3_rx_buf_dn(10)';
NODE_NAME     U6013 BH2
 '@T6G_MB_LIB.T6G(SCH_1):PAGE428_I1@PURE_QUANTA.PT5161LRS(CHIPS)':
 'A_PERN5': CDS_PINID='A_PERN5';
NODE_NAME     J105 F3
 '@T6G_MB_LIB.T6G(SCH_1):PAGE326_I75@PURE_QUANTA.CONN112_10137002101LF(CHIPS)':
 'F3': CDS_PINID='F3';
NET_NAME
'P5E_CPU0_P3_RX_BUF_DN<11>'
 '@T6G_MB_LIB.T6G(SCH_1):P5E_CPU0_P3_RX_BUF_DN'<11>:
 C_SIGNAL='@t6g_mb_lib.t6g(sch_1):p5e_cpu0_p3_rx_buf_dn(11)';
NODE_NAME     U6013 BA2
 '@T6G_MB_LIB.T6G(SCH_1):PAGE428_I1@PURE_QUANTA.PT5161LRS(CHIPS)':
 'A_PERN4': CDS_PINID='A_PERN4';
NODE_NAME     J105 E4
 '@T6G_MB_LIB.T6G(SCH_1):PAGE326_I75@PURE_QUANTA.CONN112_10137002101LF(CHIPS)':
 'E4': CDS_PINID='E4';
NET_NAME
'P5E_CPU0_P3_RX_BUF_DN<12>'
 '@T6G_MB_LIB.T6G(SCH_1):P5E_CPU0_P3_RX_BUF_DN'<12>:
 C_SIGNAL='@t6g_mb_lib.t6g(sch_1):p5e_cpu0_p3_rx_buf_dn(12)';
NODE_NAME     U6013 AP2
 '@T6G_MB_LIB.T6G(SCH_1):PAGE428_I1@PURE_QUANTA.PT5161LRS(CHIPS)':
 'A_PERN3': CDS_PINID='A_PERN3';
NODE_NAME     J105 F5
 '@T6G_MB_LIB.T6G(SCH_1):PAGE326_I76@PURE_QUANTA.CONN112_10137002101LF(CHIPS)':
 'F5': CDS_PINID='F5';
NET_NAME
'P5E_CPU0_P3_RX_BUF_DN<13>'
 '@T6G_MB_LIB.T6G(SCH_1):P5E_CPU0_P3_RX_BUF_DN'<13>:
 C_SIGNAL='@t6g_mb_lib.t6g(sch_1):p5e_cpu0_p3_rx_buf_dn(13)';
NODE_NAME     U6013 AG2
 '@T6G_MB_LIB.T6G(SCH_1):PAGE428_I1@PURE_QUANTA.PT5161LRS(CHIPS)':
 'A_PERN2': CDS_PINID='A_PERN2';
NODE_NAME     J105 E6
 '@T6G_MB_LIB.T6G(SCH_1):PAGE326_I76@PURE_QUANTA.CONN112_10137002101LF(CHIPS)':
 'E6': CDS_PINID='E6';
NET_NAME
'P5E_CPU0_P3_RX_BUF_DN<14>'
 '@T6G_MB_LIB.T6G(SCH_1):P5E_CPU0_P3_RX_BUF_DN'<14>:
 C_SIGNAL='@t6g_mb_lib.t6g(sch_1):p5e_cpu0_p3_rx_buf_dn(14)';
NODE_NAME     U6013 Y2
 '@T6G_MB_LIB.T6G(SCH_1):PAGE428_I1@PURE_QUANTA.PT5161LRS(CHIPS)':
 'A_PERN1': CDS_PINID='A_PERN1';
NODE_NAME     J105 F7
 '@T6G_MB_LIB.T6G(SCH_1):PAGE326_I76@PURE_QUANTA.CONN112_10137002101LF(CHIPS)':
 'F7': CDS_PINID='F7';
NET_NAME
'P5E_CPU0_P3_RX_BUF_DN<15>'
 '@T6G_MB_LIB.T6G(SCH_1):P5E_CPU0_P3_RX_BUF_DN'<15>:
 C_SIGNAL='@t6g_mb_lib.t6g(sch_1):p5e_cpu0_p3_rx_buf_dn(15)';
NODE_NAME     U6013 N2
 '@T6G_MB_LIB.T6G(SCH_1):PAGE428_I1@PURE_QUANTA.PT5161LRS(CHIPS)':
 'A_PERN0': CDS_PINID='A_PERN0';
NODE_NAME     J105 E8
 '@T6G_MB_LIB.T6G(SCH_1):PAGE326_I76@PURE_QUANTA.CONN112_10137002101LF(CHIPS)':
 'E8': CDS_PINID='E8';
NET_NAME
'P5E_CPU0_P3_RX_BUF_DN<1>'
 '@T6G_MB_LIB.T6G(SCH_1):P5E_CPU0_P3_RX_BUF_DN'<1>:
 C_SIGNAL='@t6g_mb_lib.t6g(sch_1):p5e_cpu0_p3_rx_buf_dn(1)';
NODE_NAME     U6013 EL2
 '@T6G_MB_LIB.T6G(SCH_1):PAGE428_I38@PURE_QUANTA.PT5161LRS(CHIPS)':
 'A_PERN14': CDS_PINID='A_PERN14';
NODE_NAME     J106 E2
 '@T6G_MB_LIB.T6G(SCH_1):PAGE327_I74@PURE_QUANTA.CONN112_10137002101LF(CHIPS)':
 'E2': CDS_PINID='E2';
NET_NAME
'P5E_CPU0_P3_RX_BUF_DN<2>'
 '@T6G_MB_LIB.T6G(SCH_1):P5E_CPU0_P3_RX_BUF_DN'<2>:
 C_SIGNAL='@t6g_mb_lib.t6g(sch_1):p5e_cpu0_p3_rx_buf_dn(2)';
NODE_NAME     U6013 ED2
 '@T6G_MB_LIB.T6G(SCH_1):PAGE428_I38@PURE_QUANTA.PT5161LRS(CHIPS)':
 'A_PERN13': CDS_PINID='A_PERN13';
NODE_NAME     J106 F3
 '@T6G_MB_LIB.T6G(SCH_1):PAGE327_I74@PURE_QUANTA.CONN112_10137002101LF(CHIPS)':
 'F3': CDS_PINID='F3';
NET_NAME
'P5E_CPU0_P3_RX_BUF_DN<3>'
 '@T6G_MB_LIB.T6G(SCH_1):P5E_CPU0_P3_RX_BUF_DN'<3>:
 C_SIGNAL='@t6g_mb_lib.t6g(sch_1):p5e_cpu0_p3_rx_buf_dn(3)';
NODE_NAME     U6013 DU2
 '@T6G_MB_LIB.T6G(SCH_1):PAGE428_I38@PURE_QUANTA.PT5161LRS(CHIPS)':
 'A_PERN12': CDS_PINID='A_PERN12';
NODE_NAME     J106 E4
 '@T6G_MB_LIB.T6G(SCH_1):PAGE327_I74@PURE_QUANTA.CONN112_10137002101LF(CHIPS)':
 'E4': CDS_PINID='E4';
NET_NAME
'P5E_CPU0_P3_RX_BUF_DN<4>'
 '@T6G_MB_LIB.T6G(SCH_1):P5E_CPU0_P3_RX_BUF_DN'<4>:
 C_SIGNAL='@t6g_mb_lib.t6g(sch_1):p5e_cpu0_p3_rx_buf_dn(4)';
NODE_NAME     U6013 DK2
 '@T6G_MB_LIB.T6G(SCH_1):PAGE428_I38@PURE_QUANTA.PT5161LRS(CHIPS)':
 'A_PERN11': CDS_PINID='A_PERN11';
NODE_NAME     J106 F5
 '@T6G_MB_LIB.T6G(SCH_1):PAGE327_I19@PURE_QUANTA.CONN112_10137002101LF(CHIPS)':
 'F5': CDS_PINID='F5';
NET_NAME
'P5E_CPU0_P3_RX_BUF_DN<5>'
 '@T6G_MB_LIB.T6G(SCH_1):P5E_CPU0_P3_RX_BUF_DN'<5>:
 C_SIGNAL='@t6g_mb_lib.t6g(sch_1):p5e_cpu0_p3_rx_buf_dn(5)';
NODE_NAME     U6013 DC2
 '@T6G_MB_LIB.T6G(SCH_1):PAGE428_I38@PURE_QUANTA.PT5161LRS(CHIPS)':
 'A_PERN10': CDS_PINID='A_PERN10';
NODE_NAME     J106 E6
 '@T6G_MB_LIB.T6G(SCH_1):PAGE327_I19@PURE_QUANTA.CONN112_10137002101LF(CHIPS)':
 'E6': CDS_PINID='E6';
NET_NAME
'P5E_CPU0_P3_RX_BUF_DN<6>'
 '@T6G_MB_LIB.T6G(SCH_1):P5E_CPU0_P3_RX_BUF_DN'<6>:
 C_SIGNAL='@t6g_mb_lib.t6g(sch_1):p5e_cpu0_p3_rx_buf_dn(6)';
NODE_NAME     U6013 CT2
 '@T6G_MB_LIB.T6G(SCH_1):PAGE428_I38@PURE_QUANTA.PT5161LRS(CHIPS)':
 'A_PERN9': CDS_PINID='A_PERN9';
NODE_NAME     J106 F7
 '@T6G_MB_LIB.T6G(SCH_1):PAGE327_I19@PURE_QUANTA.CONN112_10137002101LF(CHIPS)':
 'F7': CDS_PINID='F7';
NET_NAME
'P5E_CPU0_P3_RX_BUF_DN<7>'
 '@T6G_MB_LIB.T6G(SCH_1):P5E_CPU0_P3_RX_BUF_DN'<7>:
 C_SIGNAL='@t6g_mb_lib.t6g(sch_1):p5e_cpu0_p3_rx_buf_dn(7)';
NODE_NAME     U6013 CJ2
 '@T6G_MB_LIB.T6G(SCH_1):PAGE428_I38@PURE_QUANTA.PT5161LRS(CHIPS)':
 'A_PERN8': CDS_PINID='A_PERN8';
NODE_NAME     J106 E8
 '@T6G_MB_LIB.T6G(SCH_1):PAGE327_I19@PURE_QUANTA.CONN112_10137002101LF(CHIPS)':
 'E8': CDS_PINID='E8';
NET_NAME
'P5E_CPU0_P3_RX_BUF_DN<8>'
 '@T6G_MB_LIB.T6G(SCH_1):P5E_CPU0_P3_RX_BUF_DN'<8>:
 C_SIGNAL='@t6g_mb_lib.t6g(sch_1):p5e_cpu0_p3_rx_buf_dn(8)';
NODE_NAME     U6013 CB2
 '@T6G_MB_LIB.T6G(SCH_1):PAGE428_I1@PURE_QUANTA.PT5161LRS(CHIPS)':
 'A_PERN7': CDS_PINID='A_PERN7';
NODE_NAME     J105 F1
 '@T6G_MB_LIB.T6G(SCH_1):PAGE326_I75@PURE_QUANTA.CONN112_10137002101LF(CHIPS)':
 'F1': CDS_PINID='F1';
NET_NAME
'P5E_CPU0_P3_RX_BUF_DN<9>'
 '@T6G_MB_LIB.T6G(SCH_1):P5E_CPU0_P3_RX_BUF_DN'<9>:
 C_SIGNAL='@t6g_mb_lib.t6g(sch_1):p5e_cpu0_p3_rx_buf_dn(9)';
NODE_NAME     U6013 BR2
 '@T6G_MB_LIB.T6G(SCH_1):PAGE428_I1@PURE_QUANTA.PT5161LRS(CHIPS)':
 'A_PERN6': CDS_PINID='A_PERN6';
NODE_NAME     J105 E2
 '@T6G_MB_LIB.T6G(SCH_1):PAGE326_I75@PURE_QUANTA.CONN112_10137002101LF(CHIPS)':
 'E2': CDS_PINID='E2';
NET_NAME
'P5E_CPU0_P3_RX_BUF_DP<0>'
 '@T6G_MB_LIB.T6G(SCH_1):P5E_CPU0_P3_RX_BUF_DP'<0>:
 C_SIGNAL='@t6g_mb_lib.t6g(sch_1):p5e_cpu0_p3_rx_buf_dp(0)';
NODE_NAME     U6013 EY1
 '@T6G_MB_LIB.T6G(SCH_1):PAGE428_I38@PURE_QUANTA.PT5161LRS(CHIPS)':
 'A_PERP15': CDS_PINID='A_PERP15';
NODE_NAME     J106 G1
 '@T6G_MB_LIB.T6G(SCH_1):PAGE327_I74@PURE_QUANTA.CONN112_10137002101LF(CHIPS)':
 'G1': CDS_PINID='G1';
NET_NAME
'P5E_CPU0_P3_RX_BUF_DP<10>'
 '@T6G_MB_LIB.T6G(SCH_1):P5E_CPU0_P3_RX_BUF_DP'<10>:
 C_SIGNAL='@t6g_mb_lib.t6g(sch_1):p5e_cpu0_p3_rx_buf_dp(10)';
NODE_NAME     U6013 BK1
 '@T6G_MB_LIB.T6G(SCH_1):PAGE428_I1@PURE_QUANTA.PT5161LRS(CHIPS)':
 'A_PERP5': CDS_PINID='A_PERP5';
NODE_NAME     J105 G3
 '@T6G_MB_LIB.T6G(SCH_1):PAGE326_I75@PURE_QUANTA.CONN112_10137002101LF(CHIPS)':
 'G3': CDS_PINID='G3';
NET_NAME
'P5E_CPU0_P3_RX_BUF_DP<11>'
 '@T6G_MB_LIB.T6G(SCH_1):P5E_CPU0_P3_RX_BUF_DP'<11>:
 C_SIGNAL='@t6g_mb_lib.t6g(sch_1):p5e_cpu0_p3_rx_buf_dp(11)';
NODE_NAME     U6013 BC1
 '@T6G_MB_LIB.T6G(SCH_1):PAGE428_I1@PURE_QUANTA.PT5161LRS(CHIPS)':
 'A_PERP4': CDS_PINID='A_PERP4';
NODE_NAME     J105 F4
 '@T6G_MB_LIB.T6G(SCH_1):PAGE326_I75@PURE_QUANTA.CONN112_10137002101LF(CHIPS)':
 'F4': CDS_PINID='F4';
NET_NAME
'P5E_CPU0_P3_RX_BUF_DP<12>'
 '@T6G_MB_LIB.T6G(SCH_1):P5E_CPU0_P3_RX_BUF_DP'<12>:
 C_SIGNAL='@t6g_mb_lib.t6g(sch_1):p5e_cpu0_p3_rx_buf_dp(12)';
NODE_NAME     U6013 AT1
 '@T6G_MB_LIB.T6G(SCH_1):PAGE428_I1@PURE_QUANTA.PT5161LRS(CHIPS)':
 'A_PERP3': CDS_PINID='A_PERP3';
NODE_NAME     J105 G5
 '@T6G_MB_LIB.T6G(SCH_1):PAGE326_I76@PURE_QUANTA.CONN112_10137002101LF(CHIPS)':
 'G5': CDS_PINID='G5';
NET_NAME
'P5E_CPU0_P3_RX_BUF_DP<13>'
 '@T6G_MB_LIB.T6G(SCH_1):P5E_CPU0_P3_RX_BUF_DP'<13>:
 C_SIGNAL='@t6g_mb_lib.t6g(sch_1):p5e_cpu0_p3_rx_buf_dp(13)';
NODE_NAME     U6013 AJ1
 '@T6G_MB_LIB.T6G(SCH_1):PAGE428_I1@PURE_QUANTA.PT5161LRS(CHIPS)':
 'A_PERP2': CDS_PINID='A_PERP2';
NODE_NAME     J105 F6
 '@T6G_MB_LIB.T6G(SCH_1):PAGE326_I76@PURE_QUANTA.CONN112_10137002101LF(CHIPS)':
 'F6': CDS_PINID='F6';
NET_NAME
'P5E_CPU0_P3_RX_BUF_DP<14>'
 '@T6G_MB_LIB.T6G(SCH_1):P5E_CPU0_P3_RX_BUF_DP'<14>:
 C_SIGNAL='@t6g_mb_lib.t6g(sch_1):p5e_cpu0_p3_rx_buf_dp(14)';
NODE_NAME     U6013 AB1
 '@T6G_MB_LIB.T6G(SCH_1):PAGE428_I1@PURE_QUANTA.PT5161LRS(CHIPS)':
 'A_PERP1': CDS_PINID='A_PERP1';
NODE_NAME     J105 G7
 '@T6G_MB_LIB.T6G(SCH_1):PAGE326_I76@PURE_QUANTA.CONN112_10137002101LF(CHIPS)':
 'G7': CDS_PINID='G7';
NET_NAME
'P5E_CPU0_P3_RX_BUF_DP<15>'
 '@T6G_MB_LIB.T6G(SCH_1):P5E_CPU0_P3_RX_BUF_DP'<15>:
 C_SIGNAL='@t6g_mb_lib.t6g(sch_1):p5e_cpu0_p3_rx_buf_dp(15)';
NODE_NAME     U6013 R1
 '@T6G_MB_LIB.T6G(SCH_1):PAGE428_I1@PURE_QUANTA.PT5161LRS(CHIPS)':
 'A_PERP0': CDS_PINID='A_PERP0';
NODE_NAME     J105 F8
 '@T6G_MB_LIB.T6G(SCH_1):PAGE326_I76@PURE_QUANTA.CONN112_10137002101LF(CHIPS)':
 'F8': CDS_PINID='F8';
NET_NAME
'P5E_CPU0_P3_RX_BUF_DP<1>'
 '@T6G_MB_LIB.T6G(SCH_1):P5E_CPU0_P3_RX_BUF_DP'<1>:
 C_SIGNAL='@t6g_mb_lib.t6g(sch_1):p5e_cpu0_p3_rx_buf_dp(1)';
NODE_NAME     U6013 EN1
 '@T6G_MB_LIB.T6G(SCH_1):PAGE428_I38@PURE_QUANTA.PT5161LRS(CHIPS)':
 'A_PERP14': CDS_PINID='A_PERP14';
NODE_NAME     J106 F2
 '@T6G_MB_LIB.T6G(SCH_1):PAGE327_I74@PURE_QUANTA.CONN112_10137002101LF(CHIPS)':
 'F2': CDS_PINID='F2';
NET_NAME
'P5E_CPU0_P3_RX_BUF_DP<2>'
 '@T6G_MB_LIB.T6G(SCH_1):P5E_CPU0_P3_RX_BUF_DP'<2>:
 C_SIGNAL='@t6g_mb_lib.t6g(sch_1):p5e_cpu0_p3_rx_buf_dp(2)';
NODE_NAME     U6013 EF1
 '@T6G_MB_LIB.T6G(SCH_1):PAGE428_I38@PURE_QUANTA.PT5161LRS(CHIPS)':
 'A_PERP13': CDS_PINID='A_PERP13';
NODE_NAME     J106 G3
 '@T6G_MB_LIB.T6G(SCH_1):PAGE327_I74@PURE_QUANTA.CONN112_10137002101LF(CHIPS)':
 'G3': CDS_PINID='G3';
NET_NAME
'P5E_CPU0_P3_RX_BUF_DP<3>'
 '@T6G_MB_LIB.T6G(SCH_1):P5E_CPU0_P3_RX_BUF_DP'<3>:
 C_SIGNAL='@t6g_mb_lib.t6g(sch_1):p5e_cpu0_p3_rx_buf_dp(3)';
NODE_NAME     U6013 DW1
 '@T6G_MB_LIB.T6G(SCH_1):PAGE428_I38@PURE_QUANTA.PT5161LRS(CHIPS)':
 'A_PERP12': CDS_PINID='A_PERP12';
NODE_NAME     J106 F4
 '@T6G_MB_LIB.T6G(SCH_1):PAGE327_I74@PURE_QUANTA.CONN112_10137002101LF(CHIPS)':
 'F4': CDS_PINID='F4';
NET_NAME
'P5E_CPU0_P3_RX_BUF_DP<4>'
 '@T6G_MB_LIB.T6G(SCH_1):P5E_CPU0_P3_RX_BUF_DP'<4>:
 C_SIGNAL='@t6g_mb_lib.t6g(sch_1):p5e_cpu0_p3_rx_buf_dp(4)';
NODE_NAME     U6013 DM1
 '@T6G_MB_LIB.T6G(SCH_1):PAGE428_I38@PURE_QUANTA.PT5161LRS(CHIPS)':
 'A_PERP11': CDS_PINID='A_PERP11';
NODE_NAME     J106 G5
 '@T6G_MB_LIB.T6G(SCH_1):PAGE327_I19@PURE_QUANTA.CONN112_10137002101LF(CHIPS)':
 'G5': CDS_PINID='G5';
NET_NAME
'P5E_CPU0_P3_RX_BUF_DP<5>'
 '@T6G_MB_LIB.T6G(SCH_1):P5E_CPU0_P3_RX_BUF_DP'<5>:
 C_SIGNAL='@t6g_mb_lib.t6g(sch_1):p5e_cpu0_p3_rx_buf_dp(5)';
NODE_NAME     U6013 DE1
 '@T6G_MB_LIB.T6G(SCH_1):PAGE428_I38@PURE_QUANTA.PT5161LRS(CHIPS)':
 'A_PERP10': CDS_PINID='A_PERP10';
NODE_NAME     J106 F6
 '@T6G_MB_LIB.T6G(SCH_1):PAGE327_I19@PURE_QUANTA.CONN112_10137002101LF(CHIPS)':
 'F6': CDS_PINID='F6';
NET_NAME
'P5E_CPU0_P3_RX_BUF_DP<6>'
 '@T6G_MB_LIB.T6G(SCH_1):P5E_CPU0_P3_RX_BUF_DP'<6>:
 C_SIGNAL='@t6g_mb_lib.t6g(sch_1):p5e_cpu0_p3_rx_buf_dp(6)';
NODE_NAME     U6013 CV1
 '@T6G_MB_LIB.T6G(SCH_1):PAGE428_I38@PURE_QUANTA.PT5161LRS(CHIPS)':
 'A_PERP9': CDS_PINID='A_PERP9';
NODE_NAME     J106 G7
 '@T6G_MB_LIB.T6G(SCH_1):PAGE327_I19@PURE_QUANTA.CONN112_10137002101LF(CHIPS)':
 'G7': CDS_PINID='G7';
NET_NAME
'P5E_CPU0_P3_RX_BUF_DP<7>'
 '@T6G_MB_LIB.T6G(SCH_1):P5E_CPU0_P3_RX_BUF_DP'<7>:
 C_SIGNAL='@t6g_mb_lib.t6g(sch_1):p5e_cpu0_p3_rx_buf_dp(7)';
NODE_NAME     U6013 CL1
 '@T6G_MB_LIB.T6G(SCH_1):PAGE428_I38@PURE_QUANTA.PT5161LRS(CHIPS)':
 'A_PERP8': CDS_PINID='A_PERP8';
NODE_NAME     J106 F8
 '@T6G_MB_LIB.T6G(SCH_1):PAGE327_I19@PURE_QUANTA.CONN112_10137002101LF(CHIPS)':
 'F8': CDS_PINID='F8';
NET_NAME
'P5E_CPU0_P3_RX_BUF_DP<8>'
 '@T6G_MB_LIB.T6G(SCH_1):P5E_CPU0_P3_RX_BUF_DP'<8>:
 C_SIGNAL='@t6g_mb_lib.t6g(sch_1):p5e_cpu0_p3_rx_buf_dp(8)';
NODE_NAME     U6013 CD1
 '@T6G_MB_LIB.T6G(SCH_1):PAGE428_I1@PURE_QUANTA.PT5161LRS(CHIPS)':
 'A_PERP7': CDS_PINID='A_PERP7';
NODE_NAME     J105 G1
 '@T6G_MB_LIB.T6G(SCH_1):PAGE326_I75@PURE_QUANTA.CONN112_10137002101LF(CHIPS)':
 'G1': CDS_PINID='G1';
NET_NAME
'P5E_CPU0_P3_RX_BUF_DP<9>'
 '@T6G_MB_LIB.T6G(SCH_1):P5E_CPU0_P3_RX_BUF_DP'<9>:
 C_SIGNAL='@t6g_mb_lib.t6g(sch_1):p5e_cpu0_p3_rx_buf_dp(9)';
NODE_NAME     U6013 BU1
 '@T6G_MB_LIB.T6G(SCH_1):PAGE428_I1@PURE_QUANTA.PT5161LRS(CHIPS)':
 'A_PERP6': CDS_PINID='A_PERP6';
NODE_NAME     J105 F2
 '@T6G_MB_LIB.T6G(SCH_1):PAGE326_I75@PURE_QUANTA.CONN112_10137002101LF(CHIPS)':
 'F2': CDS_PINID='F2';
NET_NAME
'P5E_CPU0_P3_RX_DN<0>'
 '@T6G_MB_LIB.T6G(SCH_1):P5E_CPU0_P3_RX_DN'<0>:
 C_SIGNAL='@t6g_mb_lib.t6g(sch_1):p5e_cpu0_p3_rx_dn(0)';
NODE_NAME     U25 CV36
 '@T6G_MB_LIB.T6G(SCH_1):PAGE25_I148@PURE_QUANTA.GENOA_SP5(CHIPS)':
 'P3_RXN0': CDS_PINID='P3_RXN0';
NODE_NAME     U6013 EW29
 '@T6G_MB_LIB.T6G(SCH_1):PAGE427_I38@PURE_QUANTA.PT5161LRS(CHIPS)':
 'A_PETN15': CDS_PINID='A_PETN15';
NET_NAME
'P5E_CPU0_P3_RX_DN<10>'
 '@T6G_MB_LIB.T6G(SCH_1):P5E_CPU0_P3_RX_DN'<10>:
 C_SIGNAL='@t6g_mb_lib.t6g(sch_1):p5e_cpu0_p3_rx_dn(10)';
NODE_NAME     U25 DC27
 '@T6G_MB_LIB.T6G(SCH_1):PAGE25_I148@PURE_QUANTA.GENOA_SP5(CHIPS)':
 'P3_RXN10': CDS_PINID='P3_RXN10';
NODE_NAME     U6013 BJ29
 '@T6G_MB_LIB.T6G(SCH_1):PAGE427_I1@PURE_QUANTA.PT5161LRS(CHIPS)':
 'A_PETN5': CDS_PINID='A_PETN5';
NET_NAME
'P5E_CPU0_P3_RX_DN<11>'
 '@T6G_MB_LIB.T6G(SCH_1):P5E_CPU0_P3_RX_DN'<11>:
 C_SIGNAL='@t6g_mb_lib.t6g(sch_1):p5e_cpu0_p3_rx_dn(11)';
NODE_NAME     U25 DA27
 '@T6G_MB_LIB.T6G(SCH_1):PAGE25_I148@PURE_QUANTA.GENOA_SP5(CHIPS)':
 'P3_RXN11': CDS_PINID='P3_RXN11';
NODE_NAME     U6013 BB29
 '@T6G_MB_LIB.T6G(SCH_1):PAGE427_I1@PURE_QUANTA.PT5161LRS(CHIPS)':
 'A_PETN4': CDS_PINID='A_PETN4';
NET_NAME
'P5E_CPU0_P3_RX_DN<12>'
 '@T6G_MB_LIB.T6G(SCH_1):P5E_CPU0_P3_RX_DN'<12>:
 C_SIGNAL='@t6g_mb_lib.t6g(sch_1):p5e_cpu0_p3_rx_dn(12)';
NODE_NAME     U25 CW24
 '@T6G_MB_LIB.T6G(SCH_1):PAGE25_I148@PURE_QUANTA.GENOA_SP5(CHIPS)':
 'P3_RXN12': CDS_PINID='P3_RXN12';
NODE_NAME     U6013 AR29
 '@T6G_MB_LIB.T6G(SCH_1):PAGE427_I1@PURE_QUANTA.PT5161LRS(CHIPS)':
 'A_PETN3': CDS_PINID='A_PETN3';
NET_NAME
'P5E_CPU0_P3_RX_DN<13>'
 '@T6G_MB_LIB.T6G(SCH_1):P5E_CPU0_P3_RX_DN'<13>:
 C_SIGNAL='@t6g_mb_lib.t6g(sch_1):p5e_cpu0_p3_rx_dn(13)';
NODE_NAME     U25 DC24
 '@T6G_MB_LIB.T6G(SCH_1):PAGE25_I148@PURE_QUANTA.GENOA_SP5(CHIPS)':
 'P3_RXN13': CDS_PINID='P3_RXN13';
NODE_NAME     U6013 AH29
 '@T6G_MB_LIB.T6G(SCH_1):PAGE427_I1@PURE_QUANTA.PT5161LRS(CHIPS)':
 'A_PETN2': CDS_PINID='A_PETN2';
NET_NAME
'P5E_CPU0_P3_RX_DN<14>'
 '@T6G_MB_LIB.T6G(SCH_1):P5E_CPU0_P3_RX_DN'<14>:
 C_SIGNAL='@t6g_mb_lib.t6g(sch_1):p5e_cpu0_p3_rx_dn(14)';
NODE_NAME     U25 DA24
 '@T6G_MB_LIB.T6G(SCH_1):PAGE25_I148@PURE_QUANTA.GENOA_SP5(CHIPS)':
 'P3_RXN14': CDS_PINID='P3_RXN14';
NODE_NAME     U6013 AA29
 '@T6G_MB_LIB.T6G(SCH_1):PAGE427_I1@PURE_QUANTA.PT5161LRS(CHIPS)':
 'A_PETN1': CDS_PINID='A_PETN1';
NET_NAME
'P5E_CPU0_P3_RX_DN<15>'
 '@T6G_MB_LIB.T6G(SCH_1):P5E_CPU0_P3_RX_DN'<15>:
 C_SIGNAL='@t6g_mb_lib.t6g(sch_1):p5e_cpu0_p3_rx_dn(15)';
NODE_NAME     U25 CU24
 '@T6G_MB_LIB.T6G(SCH_1):PAGE25_I148@PURE_QUANTA.GENOA_SP5(CHIPS)':
 'P3_RXN15': CDS_PINID='P3_RXN15';
NODE_NAME     U6013 P29
 '@T6G_MB_LIB.T6G(SCH_1):PAGE427_I1@PURE_QUANTA.PT5161LRS(CHIPS)':
 'A_PETN0': CDS_PINID='A_PETN0';
NET_NAME
'P5E_CPU0_P3_RX_DN<1>'
 '@T6G_MB_LIB.T6G(SCH_1):P5E_CPU0_P3_RX_DN'<1>:
 C_SIGNAL='@t6g_mb_lib.t6g(sch_1):p5e_cpu0_p3_rx_dn(1)';
NODE_NAME     U25 CY36
 '@T6G_MB_LIB.T6G(SCH_1):PAGE25_I148@PURE_QUANTA.GENOA_SP5(CHIPS)':
 'P3_RXN1': CDS_PINID='P3_RXN1';
NODE_NAME     U6013 EM29
 '@T6G_MB_LIB.T6G(SCH_1):PAGE427_I38@PURE_QUANTA.PT5161LRS(CHIPS)':
 'A_PETN14': CDS_PINID='A_PETN14';
NET_NAME
'P5E_CPU0_P3_RX_DN<2>'
 '@T6G_MB_LIB.T6G(SCH_1):P5E_CPU0_P3_RX_DN'<2>:
 C_SIGNAL='@t6g_mb_lib.t6g(sch_1):p5e_cpu0_p3_rx_dn(2)';
NODE_NAME     U25 DB36
 '@T6G_MB_LIB.T6G(SCH_1):PAGE25_I148@PURE_QUANTA.GENOA_SP5(CHIPS)':
 'P3_RXN2': CDS_PINID='P3_RXN2';
NODE_NAME     U6013 EE29
 '@T6G_MB_LIB.T6G(SCH_1):PAGE427_I38@PURE_QUANTA.PT5161LRS(CHIPS)':
 'A_PETN13': CDS_PINID='A_PETN13';
NET_NAME
'P5E_CPU0_P3_RX_DN<3>'
 '@T6G_MB_LIB.T6G(SCH_1):P5E_CPU0_P3_RX_DN'<3>:
 C_SIGNAL='@t6g_mb_lib.t6g(sch_1):p5e_cpu0_p3_rx_dn(3)';
NODE_NAME     U25 CW33
 '@T6G_MB_LIB.T6G(SCH_1):PAGE25_I148@PURE_QUANTA.GENOA_SP5(CHIPS)':
 'P3_RXN3': CDS_PINID='P3_RXN3';
NODE_NAME     U6013 DV29
 '@T6G_MB_LIB.T6G(SCH_1):PAGE427_I38@PURE_QUANTA.PT5161LRS(CHIPS)':
 'A_PETN12': CDS_PINID='A_PETN12';
NET_NAME
'P5E_CPU0_P3_RX_DN<4>'
 '@T6G_MB_LIB.T6G(SCH_1):P5E_CPU0_P3_RX_DN'<4>:
 C_SIGNAL='@t6g_mb_lib.t6g(sch_1):p5e_cpu0_p3_rx_dn(4)';
NODE_NAME     U25 DC33
 '@T6G_MB_LIB.T6G(SCH_1):PAGE25_I148@PURE_QUANTA.GENOA_SP5(CHIPS)':
 'P3_RXN4': CDS_PINID='P3_RXN4';
NODE_NAME     U6013 DL29
 '@T6G_MB_LIB.T6G(SCH_1):PAGE427_I38@PURE_QUANTA.PT5161LRS(CHIPS)':
 'A_PETN11': CDS_PINID='A_PETN11';
NET_NAME
'P5E_CPU0_P3_RX_DN<5>'
 '@T6G_MB_LIB.T6G(SCH_1):P5E_CPU0_P3_RX_DN'<5>:
 C_SIGNAL='@t6g_mb_lib.t6g(sch_1):p5e_cpu0_p3_rx_dn(5)';
NODE_NAME     U25 DA33
 '@T6G_MB_LIB.T6G(SCH_1):PAGE25_I148@PURE_QUANTA.GENOA_SP5(CHIPS)':
 'P3_RXN5': CDS_PINID='P3_RXN5';
NODE_NAME     U6013 DD29
 '@T6G_MB_LIB.T6G(SCH_1):PAGE427_I38@PURE_QUANTA.PT5161LRS(CHIPS)':
 'A_PETN10': CDS_PINID='A_PETN10';
NET_NAME
'P5E_CPU0_P3_RX_DN<6>'
 '@T6G_MB_LIB.T6G(SCH_1):P5E_CPU0_P3_RX_DN'<6>:
 C_SIGNAL='@t6g_mb_lib.t6g(sch_1):p5e_cpu0_p3_rx_dn(6)';
NODE_NAME     U25 CW30
 '@T6G_MB_LIB.T6G(SCH_1):PAGE25_I148@PURE_QUANTA.GENOA_SP5(CHIPS)':
 'P3_RXN6': CDS_PINID='P3_RXN6';
NODE_NAME     U6013 CU29
 '@T6G_MB_LIB.T6G(SCH_1):PAGE427_I38@PURE_QUANTA.PT5161LRS(CHIPS)':
 'A_PETN9': CDS_PINID='A_PETN9';
NET_NAME
'P5E_CPU0_P3_RX_DN<7>'
 '@T6G_MB_LIB.T6G(SCH_1):P5E_CPU0_P3_RX_DN'<7>:
 C_SIGNAL='@t6g_mb_lib.t6g(sch_1):p5e_cpu0_p3_rx_dn(7)';
NODE_NAME     U25 DC30
 '@T6G_MB_LIB.T6G(SCH_1):PAGE25_I148@PURE_QUANTA.GENOA_SP5(CHIPS)':
 'P3_RXN7': CDS_PINID='P3_RXN7';
NODE_NAME     U6013 CK29
 '@T6G_MB_LIB.T6G(SCH_1):PAGE427_I38@PURE_QUANTA.PT5161LRS(CHIPS)':
 'A_PETN8': CDS_PINID='A_PETN8';
NET_NAME
'P5E_CPU0_P3_RX_DN<8>'
 '@T6G_MB_LIB.T6G(SCH_1):P5E_CPU0_P3_RX_DN'<8>:
 C_SIGNAL='@t6g_mb_lib.t6g(sch_1):p5e_cpu0_p3_rx_dn(8)';
NODE_NAME     U25 DA30
 '@T6G_MB_LIB.T6G(SCH_1):PAGE25_I148@PURE_QUANTA.GENOA_SP5(CHIPS)':
 'P3_RXN8': CDS_PINID='P3_RXN8';
NODE_NAME     U6013 CC29
 '@T6G_MB_LIB.T6G(SCH_1):PAGE427_I1@PURE_QUANTA.PT5161LRS(CHIPS)':
 'A_PETN7': CDS_PINID='A_PETN7';
NET_NAME
'P5E_CPU0_P3_RX_DN<9>'
 '@T6G_MB_LIB.T6G(SCH_1):P5E_CPU0_P3_RX_DN'<9>:
 C_SIGNAL='@t6g_mb_lib.t6g(sch_1):p5e_cpu0_p3_rx_dn(9)';
NODE_NAME     U25 CW27
 '@T6G_MB_LIB.T6G(SCH_1):PAGE25_I148@PURE_QUANTA.GENOA_SP5(CHIPS)':
 'P3_RXN9': CDS_PINID='P3_RXN9';
NODE_NAME     U6013 BT29
 '@T6G_MB_LIB.T6G(SCH_1):PAGE427_I1@PURE_QUANTA.PT5161LRS(CHIPS)':
 'A_PETN6': CDS_PINID='A_PETN6';
NET_NAME
'P5E_CPU0_P3_RX_DP<0>'
 '@T6G_MB_LIB.T6G(SCH_1):P5E_CPU0_P3_RX_DP'<0>:
 C_SIGNAL='@t6g_mb_lib.t6g(sch_1):p5e_cpu0_p3_rx_dp(0)';
NODE_NAME     U25 CV35
 '@T6G_MB_LIB.T6G(SCH_1):PAGE25_I148@PURE_QUANTA.GENOA_SP5(CHIPS)':
 'P3_RXP0': CDS_PINID='P3_RXP0';
NODE_NAME     U6013 EU26
 '@T6G_MB_LIB.T6G(SCH_1):PAGE427_I38@PURE_QUANTA.PT5161LRS(CHIPS)':
 'A_PETP15': CDS_PINID='A_PETP15';
NET_NAME
'P5E_CPU0_P3_RX_DP<10>'
 '@T6G_MB_LIB.T6G(SCH_1):P5E_CPU0_P3_RX_DP'<10>:
 C_SIGNAL='@t6g_mb_lib.t6g(sch_1):p5e_cpu0_p3_rx_dp(10)';
NODE_NAME     U25 DC26
 '@T6G_MB_LIB.T6G(SCH_1):PAGE25_I148@PURE_QUANTA.GENOA_SP5(CHIPS)':
 'P3_RXP10': CDS_PINID='P3_RXP10';
NODE_NAME     U6013 BG26
 '@T6G_MB_LIB.T6G(SCH_1):PAGE427_I1@PURE_QUANTA.PT5161LRS(CHIPS)':
 'A_PETP5': CDS_PINID='A_PETP5';
NET_NAME
'P5E_CPU0_P3_RX_DP<11>'
 '@T6G_MB_LIB.T6G(SCH_1):P5E_CPU0_P3_RX_DP'<11>:
 C_SIGNAL='@t6g_mb_lib.t6g(sch_1):p5e_cpu0_p3_rx_dp(11)';
NODE_NAME     U25 DA26
 '@T6G_MB_LIB.T6G(SCH_1):PAGE25_I148@PURE_QUANTA.GENOA_SP5(CHIPS)':
 'P3_RXP11': CDS_PINID='P3_RXP11';
NODE_NAME     U6013 AY26
 '@T6G_MB_LIB.T6G(SCH_1):PAGE427_I1@PURE_QUANTA.PT5161LRS(CHIPS)':
 'A_PETP4': CDS_PINID='A_PETP4';
NET_NAME
'P5E_CPU0_P3_RX_DP<12>'
 '@T6G_MB_LIB.T6G(SCH_1):P5E_CPU0_P3_RX_DP'<12>:
 C_SIGNAL='@t6g_mb_lib.t6g(sch_1):p5e_cpu0_p3_rx_dp(12)';
NODE_NAME     U25 CW23
 '@T6G_MB_LIB.T6G(SCH_1):PAGE25_I148@PURE_QUANTA.GENOA_SP5(CHIPS)':
 'P3_RXP12': CDS_PINID='P3_RXP12';
NODE_NAME     U6013 AN26
 '@T6G_MB_LIB.T6G(SCH_1):PAGE427_I1@PURE_QUANTA.PT5161LRS(CHIPS)':
 'A_PETP3': CDS_PINID='A_PETP3';
NET_NAME
'P5E_CPU0_P3_RX_DP<13>'
 '@T6G_MB_LIB.T6G(SCH_1):P5E_CPU0_P3_RX_DP'<13>:
 C_SIGNAL='@t6g_mb_lib.t6g(sch_1):p5e_cpu0_p3_rx_dp(13)';
NODE_NAME     U25 DC23
 '@T6G_MB_LIB.T6G(SCH_1):PAGE25_I148@PURE_QUANTA.GENOA_SP5(CHIPS)':
 'P3_RXP13': CDS_PINID='P3_RXP13';
NODE_NAME     U6013 AF26
 '@T6G_MB_LIB.T6G(SCH_1):PAGE427_I1@PURE_QUANTA.PT5161LRS(CHIPS)':
 'A_PETP2': CDS_PINID='A_PETP2';
NET_NAME
'P5E_CPU0_P3_RX_DP<14>'
 '@T6G_MB_LIB.T6G(SCH_1):P5E_CPU0_P3_RX_DP'<14>:
 C_SIGNAL='@t6g_mb_lib.t6g(sch_1):p5e_cpu0_p3_rx_dp(14)';
NODE_NAME     U25 DA23
 '@T6G_MB_LIB.T6G(SCH_1):PAGE25_I148@PURE_QUANTA.GENOA_SP5(CHIPS)':
 'P3_RXP14': CDS_PINID='P3_RXP14';
NODE_NAME     U6013 W26
 '@T6G_MB_LIB.T6G(SCH_1):PAGE427_I1@PURE_QUANTA.PT5161LRS(CHIPS)':
 'A_PETP1': CDS_PINID='A_PETP1';
NET_NAME
'P5E_CPU0_P3_RX_DP<15>'
 '@T6G_MB_LIB.T6G(SCH_1):P5E_CPU0_P3_RX_DP'<15>:
 C_SIGNAL='@t6g_mb_lib.t6g(sch_1):p5e_cpu0_p3_rx_dp(15)';
NODE_NAME     U25 CU23
 '@T6G_MB_LIB.T6G(SCH_1):PAGE25_I148@PURE_QUANTA.GENOA_SP5(CHIPS)':
 'P3_RXP15': CDS_PINID='P3_RXP15';
NODE_NAME     U6013 M26
 '@T6G_MB_LIB.T6G(SCH_1):PAGE427_I1@PURE_QUANTA.PT5161LRS(CHIPS)':
 'A_PETP0': CDS_PINID='A_PETP0';
NET_NAME
'P5E_CPU0_P3_RX_DP<1>'
 '@T6G_MB_LIB.T6G(SCH_1):P5E_CPU0_P3_RX_DP'<1>:
 C_SIGNAL='@t6g_mb_lib.t6g(sch_1):p5e_cpu0_p3_rx_dp(1)';
NODE_NAME     U25 CY35
 '@T6G_MB_LIB.T6G(SCH_1):PAGE25_I148@PURE_QUANTA.GENOA_SP5(CHIPS)':
 'P3_RXP1': CDS_PINID='P3_RXP1';
NODE_NAME     U6013 EK26
 '@T6G_MB_LIB.T6G(SCH_1):PAGE427_I38@PURE_QUANTA.PT5161LRS(CHIPS)':
 'A_PETP14': CDS_PINID='A_PETP14';
NET_NAME
'P5E_CPU0_P3_RX_DP<2>'
 '@T6G_MB_LIB.T6G(SCH_1):P5E_CPU0_P3_RX_DP'<2>:
 C_SIGNAL='@t6g_mb_lib.t6g(sch_1):p5e_cpu0_p3_rx_dp(2)';
NODE_NAME     U25 DB35
 '@T6G_MB_LIB.T6G(SCH_1):PAGE25_I148@PURE_QUANTA.GENOA_SP5(CHIPS)':
 'P3_RXP2': CDS_PINID='P3_RXP2';
NODE_NAME     U6013 EC26
 '@T6G_MB_LIB.T6G(SCH_1):PAGE427_I38@PURE_QUANTA.PT5161LRS(CHIPS)':
 'A_PETP13': CDS_PINID='A_PETP13';
NET_NAME
'P5E_CPU0_P3_RX_DP<3>'
 '@T6G_MB_LIB.T6G(SCH_1):P5E_CPU0_P3_RX_DP'<3>:
 C_SIGNAL='@t6g_mb_lib.t6g(sch_1):p5e_cpu0_p3_rx_dp(3)';
NODE_NAME     U25 CW32
 '@T6G_MB_LIB.T6G(SCH_1):PAGE25_I148@PURE_QUANTA.GENOA_SP5(CHIPS)':
 'P3_RXP3': CDS_PINID='P3_RXP3';
NODE_NAME     U6013 DT26
 '@T6G_MB_LIB.T6G(SCH_1):PAGE427_I38@PURE_QUANTA.PT5161LRS(CHIPS)':
 'A_PETP12': CDS_PINID='A_PETP12';
NET_NAME
'P5E_CPU0_P3_RX_DP<4>'
 '@T6G_MB_LIB.T6G(SCH_1):P5E_CPU0_P3_RX_DP'<4>:
 C_SIGNAL='@t6g_mb_lib.t6g(sch_1):p5e_cpu0_p3_rx_dp(4)';
NODE_NAME     U25 DC32
 '@T6G_MB_LIB.T6G(SCH_1):PAGE25_I148@PURE_QUANTA.GENOA_SP5(CHIPS)':
 'P3_RXP4': CDS_PINID='P3_RXP4';
NODE_NAME     U6013 DJ26
 '@T6G_MB_LIB.T6G(SCH_1):PAGE427_I38@PURE_QUANTA.PT5161LRS(CHIPS)':
 'A_PETP11': CDS_PINID='A_PETP11';
NET_NAME
'P5E_CPU0_P3_RX_DP<5>'
 '@T6G_MB_LIB.T6G(SCH_1):P5E_CPU0_P3_RX_DP'<5>:
 C_SIGNAL='@t6g_mb_lib.t6g(sch_1):p5e_cpu0_p3_rx_dp(5)';
NODE_NAME     U25 DA32
 '@T6G_MB_LIB.T6G(SCH_1):PAGE25_I148@PURE_QUANTA.GENOA_SP5(CHIPS)':
 'P3_RXP5': CDS_PINID='P3_RXP5';
NODE_NAME     U6013 DB26
 '@T6G_MB_LIB.T6G(SCH_1):PAGE427_I38@PURE_QUANTA.PT5161LRS(CHIPS)':
 'A_PETP10': CDS_PINID='A_PETP10';
NET_NAME
'P5E_CPU0_P3_RX_DP<6>'
 '@T6G_MB_LIB.T6G(SCH_1):P5E_CPU0_P3_RX_DP'<6>:
 C_SIGNAL='@t6g_mb_lib.t6g(sch_1):p5e_cpu0_p3_rx_dp(6)';
NODE_NAME     U25 CW29
 '@T6G_MB_LIB.T6G(SCH_1):PAGE25_I148@PURE_QUANTA.GENOA_SP5(CHIPS)':
 'P3_RXP6': CDS_PINID='P3_RXP6';
NODE_NAME     U6013 CR26
 '@T6G_MB_LIB.T6G(SCH_1):PAGE427_I38@PURE_QUANTA.PT5161LRS(CHIPS)':
 'A_PETP9': CDS_PINID='A_PETP9';
NET_NAME
'P5E_CPU0_P3_RX_DP<7>'
 '@T6G_MB_LIB.T6G(SCH_1):P5E_CPU0_P3_RX_DP'<7>:
 C_SIGNAL='@t6g_mb_lib.t6g(sch_1):p5e_cpu0_p3_rx_dp(7)';
NODE_NAME     U25 DC29
 '@T6G_MB_LIB.T6G(SCH_1):PAGE25_I148@PURE_QUANTA.GENOA_SP5(CHIPS)':
 'P3_RXP7': CDS_PINID='P3_RXP7';
NODE_NAME     U6013 CH26
 '@T6G_MB_LIB.T6G(SCH_1):PAGE427_I38@PURE_QUANTA.PT5161LRS(CHIPS)':
 'A_PETP8': CDS_PINID='A_PETP8';
NET_NAME
'P5E_CPU0_P3_RX_DP<8>'
 '@T6G_MB_LIB.T6G(SCH_1):P5E_CPU0_P3_RX_DP'<8>:
 C_SIGNAL='@t6g_mb_lib.t6g(sch_1):p5e_cpu0_p3_rx_dp(8)';
NODE_NAME     U25 DA29
 '@T6G_MB_LIB.T6G(SCH_1):PAGE25_I148@PURE_QUANTA.GENOA_SP5(CHIPS)':
 'P3_RXP8': CDS_PINID='P3_RXP8';
NODE_NAME     U6013 CA26
 '@T6G_MB_LIB.T6G(SCH_1):PAGE427_I1@PURE_QUANTA.PT5161LRS(CHIPS)':
 'A_PETP7': CDS_PINID='A_PETP7';
NET_NAME
'P5E_CPU0_P3_RX_DP<9>'
 '@T6G_MB_LIB.T6G(SCH_1):P5E_CPU0_P3_RX_DP'<9>:
 C_SIGNAL='@t6g_mb_lib.t6g(sch_1):p5e_cpu0_p3_rx_dp(9)';
NODE_NAME     U25 CW26
 '@T6G_MB_LIB.T6G(SCH_1):PAGE25_I148@PURE_QUANTA.GENOA_SP5(CHIPS)':
 'P3_RXP9': CDS_PINID='P3_RXP9';
NODE_NAME     U6013 BP26
 '@T6G_MB_LIB.T6G(SCH_1):PAGE427_I1@PURE_QUANTA.PT5161LRS(CHIPS)':
 'A_PETP6': CDS_PINID='A_PETP6';
NET_NAME
'P5E_CPU0_P3_TX_BUF_C_DN<0>'
 '@T6G_MB_LIB.T6G(SCH_1):P5E_CPU0_P3_TX_BUF_C_DN'<0>:
 C_SIGNAL='@t6g_mb_lib.t6g(sch_1):p5e_cpu0_p3_tx_buf_c_dn(0)';
NODE_NAME     C6598 1
 '@T6G_MB_LIB.T6G(SCH_1):PAGE429_I39@PURE_QUANTA.Q_CAP_DIFFBUS(CHIPS)':
 '1': CDS_PINID='\1\';
NODE_NAME     J106 L1
 '@T6G_MB_LIB.T6G(SCH_1):PAGE327_I74@PURE_QUANTA.CONN112_10137002101LF(CHIPS)':
 'L1': CDS_PINID='L1';
NET_NAME
'P5E_CPU0_P3_TX_BUF_C_DN<10>'
 '@T6G_MB_LIB.T6G(SCH_1):P5E_CPU0_P3_TX_BUF_C_DN'<10>:
 C_SIGNAL='@t6g_mb_lib.t6g(sch_1):p5e_cpu0_p3_tx_buf_c_dn(10)';
NODE_NAME     C6618 1
 '@T6G_MB_LIB.T6G(SCH_1):PAGE429_I99@PURE_QUANTA.Q_CAP_DIFFBUS(CHIPS)':
 '1': CDS_PINID='\1\';
NODE_NAME     J105 L3
 '@T6G_MB_LIB.T6G(SCH_1):PAGE326_I75@PURE_QUANTA.CONN112_10137002101LF(CHIPS)':
 'L3': CDS_PINID='L3';
NET_NAME
'P5E_CPU0_P3_TX_BUF_C_DN<11>'
 '@T6G_MB_LIB.T6G(SCH_1):P5E_CPU0_P3_TX_BUF_C_DN'<11>:
 C_SIGNAL='@t6g_mb_lib.t6g(sch_1):p5e_cpu0_p3_tx_buf_c_dn(11)';
NODE_NAME     C6620 1
 '@T6G_MB_LIB.T6G(SCH_1):PAGE429_I98@PURE_QUANTA.Q_CAP_DIFFBUS(CHIPS)':
 '1': CDS_PINID='\1\';
NODE_NAME     J105 K4
 '@T6G_MB_LIB.T6G(SCH_1):PAGE326_I75@PURE_QUANTA.CONN112_10137002101LF(CHIPS)':
 'K4': CDS_PINID='K4';
NET_NAME
'P5E_CPU0_P3_TX_BUF_C_DN<12>'
 '@T6G_MB_LIB.T6G(SCH_1):P5E_CPU0_P3_TX_BUF_C_DN'<12>:
 C_SIGNAL='@t6g_mb_lib.t6g(sch_1):p5e_cpu0_p3_tx_buf_c_dn(12)';
NODE_NAME     C6622 1
 '@T6G_MB_LIB.T6G(SCH_1):PAGE429_I97@PURE_QUANTA.Q_CAP_DIFFBUS(CHIPS)':
 '1': CDS_PINID='\1\';
NODE_NAME     J105 L5
 '@T6G_MB_LIB.T6G(SCH_1):PAGE326_I76@PURE_QUANTA.CONN112_10137002101LF(CHIPS)':
 'L5': CDS_PINID='L5';
NET_NAME
'P5E_CPU0_P3_TX_BUF_C_DN<13>'
 '@T6G_MB_LIB.T6G(SCH_1):P5E_CPU0_P3_TX_BUF_C_DN'<13>:
 C_SIGNAL='@t6g_mb_lib.t6g(sch_1):p5e_cpu0_p3_tx_buf_c_dn(13)';
NODE_NAME     C6624 1
 '@T6G_MB_LIB.T6G(SCH_1):PAGE429_I95@PURE_QUANTA.Q_CAP_DIFFBUS(CHIPS)':
 '1': CDS_PINID='\1\';
NODE_NAME     J105 K6
 '@T6G_MB_LIB.T6G(SCH_1):PAGE326_I76@PURE_QUANTA.CONN112_10137002101LF(CHIPS)':
 'K6': CDS_PINID='K6';
NET_NAME
'P5E_CPU0_P3_TX_BUF_C_DN<14>'
 '@T6G_MB_LIB.T6G(SCH_1):P5E_CPU0_P3_TX_BUF_C_DN'<14>:
 C_SIGNAL='@t6g_mb_lib.t6g(sch_1):p5e_cpu0_p3_tx_buf_c_dn(14)';
NODE_NAME     C6626 1
 '@T6G_MB_LIB.T6G(SCH_1):PAGE429_I92@PURE_QUANTA.Q_CAP_DIFFBUS(CHIPS)':
 '1': CDS_PINID='\1\';
NODE_NAME     J105 L7
 '@T6G_MB_LIB.T6G(SCH_1):PAGE326_I76@PURE_QUANTA.CONN112_10137002101LF(CHIPS)':
 'L7': CDS_PINID='L7';
NET_NAME
'P5E_CPU0_P3_TX_BUF_C_DN<15>'
 '@T6G_MB_LIB.T6G(SCH_1):P5E_CPU0_P3_TX_BUF_C_DN'<15>:
 C_SIGNAL='@t6g_mb_lib.t6g(sch_1):p5e_cpu0_p3_tx_buf_c_dn(15)';
NODE_NAME     C6628 1
 '@T6G_MB_LIB.T6G(SCH_1):PAGE429_I90@PURE_QUANTA.Q_CAP_DIFFBUS(CHIPS)':
 '1': CDS_PINID='\1\';
NODE_NAME     J105 K8
 '@T6G_MB_LIB.T6G(SCH_1):PAGE326_I76@PURE_QUANTA.CONN112_10137002101LF(CHIPS)':
 'K8': CDS_PINID='K8';
NET_NAME
'P5E_CPU0_P3_TX_BUF_C_DN<1>'
 '@T6G_MB_LIB.T6G(SCH_1):P5E_CPU0_P3_TX_BUF_C_DN'<1>:
 C_SIGNAL='@t6g_mb_lib.t6g(sch_1):p5e_cpu0_p3_tx_buf_c_dn(1)';
NODE_NAME     C6600 1
 '@T6G_MB_LIB.T6G(SCH_1):PAGE429_I37@PURE_QUANTA.Q_CAP_DIFFBUS(CHIPS)':
 '1': CDS_PINID='\1\';
NODE_NAME     J106 K2
 '@T6G_MB_LIB.T6G(SCH_1):PAGE327_I74@PURE_QUANTA.CONN112_10137002101LF(CHIPS)':
 'K2': CDS_PINID='K2';
NET_NAME
'P5E_CPU0_P3_TX_BUF_C_DN<2>'
 '@T6G_MB_LIB.T6G(SCH_1):P5E_CPU0_P3_TX_BUF_C_DN'<2>:
 C_SIGNAL='@t6g_mb_lib.t6g(sch_1):p5e_cpu0_p3_tx_buf_c_dn(2)';
NODE_NAME     C6602 1
 '@T6G_MB_LIB.T6G(SCH_1):PAGE429_I35@PURE_QUANTA.Q_CAP_DIFFBUS(CHIPS)':
 '1': CDS_PINID='\1\';
NODE_NAME     J106 L3
 '@T6G_MB_LIB.T6G(SCH_1):PAGE327_I74@PURE_QUANTA.CONN112_10137002101LF(CHIPS)':
 'L3': CDS_PINID='L3';
NET_NAME
'P5E_CPU0_P3_TX_BUF_C_DN<3>'
 '@T6G_MB_LIB.T6G(SCH_1):P5E_CPU0_P3_TX_BUF_C_DN'<3>:
 C_SIGNAL='@t6g_mb_lib.t6g(sch_1):p5e_cpu0_p3_tx_buf_c_dn(3)';
NODE_NAME     C6604 1
 '@T6G_MB_LIB.T6G(SCH_1):PAGE429_I33@PURE_QUANTA.Q_CAP_DIFFBUS(CHIPS)':
 '1': CDS_PINID='\1\';
NODE_NAME     J106 K4
 '@T6G_MB_LIB.T6G(SCH_1):PAGE327_I74@PURE_QUANTA.CONN112_10137002101LF(CHIPS)':
 'K4': CDS_PINID='K4';
NET_NAME
'P5E_CPU0_P3_TX_BUF_C_DN<4>'
 '@T6G_MB_LIB.T6G(SCH_1):P5E_CPU0_P3_TX_BUF_C_DN'<4>:
 C_SIGNAL='@t6g_mb_lib.t6g(sch_1):p5e_cpu0_p3_tx_buf_c_dn(4)';
NODE_NAME     C6606 1
 '@T6G_MB_LIB.T6G(SCH_1):PAGE429_I31@PURE_QUANTA.Q_CAP_DIFFBUS(CHIPS)':
 '1': CDS_PINID='\1\';
NODE_NAME     J106 L5
 '@T6G_MB_LIB.T6G(SCH_1):PAGE327_I19@PURE_QUANTA.CONN112_10137002101LF(CHIPS)':
 'L5': CDS_PINID='L5';
NET_NAME
'P5E_CPU0_P3_TX_BUF_C_DN<5>'
 '@T6G_MB_LIB.T6G(SCH_1):P5E_CPU0_P3_TX_BUF_C_DN'<5>:
 C_SIGNAL='@t6g_mb_lib.t6g(sch_1):p5e_cpu0_p3_tx_buf_c_dn(5)';
NODE_NAME     C6608 1
 '@T6G_MB_LIB.T6G(SCH_1):PAGE429_I23@PURE_QUANTA.Q_CAP_DIFFBUS(CHIPS)':
 '1': CDS_PINID='\1\';
NODE_NAME     J106 K6
 '@T6G_MB_LIB.T6G(SCH_1):PAGE327_I19@PURE_QUANTA.CONN112_10137002101LF(CHIPS)':
 'K6': CDS_PINID='K6';
NET_NAME
'P5E_CPU0_P3_TX_BUF_C_DN<6>'
 '@T6G_MB_LIB.T6G(SCH_1):P5E_CPU0_P3_TX_BUF_C_DN'<6>:
 C_SIGNAL='@t6g_mb_lib.t6g(sch_1):p5e_cpu0_p3_tx_buf_c_dn(6)';
NODE_NAME     C6610 1
 '@T6G_MB_LIB.T6G(SCH_1):PAGE429_I21@PURE_QUANTA.Q_CAP_DIFFBUS(CHIPS)':
 '1': CDS_PINID='\1\';
NODE_NAME     J106 L7
 '@T6G_MB_LIB.T6G(SCH_1):PAGE327_I19@PURE_QUANTA.CONN112_10137002101LF(CHIPS)':
 'L7': CDS_PINID='L7';
NET_NAME
'P5E_CPU0_P3_TX_BUF_C_DN<7>'
 '@T6G_MB_LIB.T6G(SCH_1):P5E_CPU0_P3_TX_BUF_C_DN'<7>:
 C_SIGNAL='@t6g_mb_lib.t6g(sch_1):p5e_cpu0_p3_tx_buf_c_dn(7)';
NODE_NAME     C6612 1
 '@T6G_MB_LIB.T6G(SCH_1):PAGE429_I20@PURE_QUANTA.Q_CAP_DIFFBUS(CHIPS)':
 '1': CDS_PINID='\1\';
NODE_NAME     J106 K8
 '@T6G_MB_LIB.T6G(SCH_1):PAGE327_I19@PURE_QUANTA.CONN112_10137002101LF(CHIPS)':
 'K8': CDS_PINID='K8';
NET_NAME
'P5E_CPU0_P3_TX_BUF_C_DN<8>'
 '@T6G_MB_LIB.T6G(SCH_1):P5E_CPU0_P3_TX_BUF_C_DN'<8>:
 C_SIGNAL='@t6g_mb_lib.t6g(sch_1):p5e_cpu0_p3_tx_buf_c_dn(8)';
NODE_NAME     C6614 1
 '@T6G_MB_LIB.T6G(SCH_1):PAGE429_I104@PURE_QUANTA.Q_CAP_DIFFBUS(CHIPS)':
 '1': CDS_PINID='\1\';
NODE_NAME     J105 L1
 '@T6G_MB_LIB.T6G(SCH_1):PAGE326_I75@PURE_QUANTA.CONN112_10137002101LF(CHIPS)':
 'L1': CDS_PINID='L1';
NET_NAME
'P5E_CPU0_P3_TX_BUF_C_DN<9>'
 '@T6G_MB_LIB.T6G(SCH_1):P5E_CPU0_P3_TX_BUF_C_DN'<9>:
 C_SIGNAL='@t6g_mb_lib.t6g(sch_1):p5e_cpu0_p3_tx_buf_c_dn(9)';
NODE_NAME     C6616 1
 '@T6G_MB_LIB.T6G(SCH_1):PAGE429_I103@PURE_QUANTA.Q_CAP_DIFFBUS(CHIPS)':
 '1': CDS_PINID='\1\';
NODE_NAME     J105 K2
 '@T6G_MB_LIB.T6G(SCH_1):PAGE326_I75@PURE_QUANTA.CONN112_10137002101LF(CHIPS)':
 'K2': CDS_PINID='K2';
NET_NAME
'P5E_CPU0_P3_TX_BUF_C_DP<0>'
 '@T6G_MB_LIB.T6G(SCH_1):P5E_CPU0_P3_TX_BUF_C_DP'<0>:
 C_SIGNAL='@t6g_mb_lib.t6g(sch_1):p5e_cpu0_p3_tx_buf_c_dp(0)';
NODE_NAME     C6597 1
 '@T6G_MB_LIB.T6G(SCH_1):PAGE429_I40@PURE_QUANTA.Q_CAP_DIFFBUS(CHIPS)':
 '1': CDS_PINID='\1\';
NODE_NAME     J106 M1
 '@T6G_MB_LIB.T6G(SCH_1):PAGE327_I74@PURE_QUANTA.CONN112_10137002101LF(CHIPS)':
 'M1': CDS_PINID='M1';
NET_NAME
'P5E_CPU0_P3_TX_BUF_C_DP<10>'
 '@T6G_MB_LIB.T6G(SCH_1):P5E_CPU0_P3_TX_BUF_C_DP'<10>:
 C_SIGNAL='@t6g_mb_lib.t6g(sch_1):p5e_cpu0_p3_tx_buf_c_dp(10)';
NODE_NAME     C6617 1
 '@T6G_MB_LIB.T6G(SCH_1):PAGE429_I101@PURE_QUANTA.Q_CAP_DIFFBUS(CHIPS)':
 '1': CDS_PINID='\1\';
NODE_NAME     J105 M3
 '@T6G_MB_LIB.T6G(SCH_1):PAGE326_I75@PURE_QUANTA.CONN112_10137002101LF(CHIPS)':
 'M3': CDS_PINID='M3';
NET_NAME
'P5E_CPU0_P3_TX_BUF_C_DP<11>'
 '@T6G_MB_LIB.T6G(SCH_1):P5E_CPU0_P3_TX_BUF_C_DP'<11>:
 C_SIGNAL='@t6g_mb_lib.t6g(sch_1):p5e_cpu0_p3_tx_buf_c_dp(11)';
NODE_NAME     C6619 1
 '@T6G_MB_LIB.T6G(SCH_1):PAGE429_I100@PURE_QUANTA.Q_CAP_DIFFBUS(CHIPS)':
 '1': CDS_PINID='\1\';
NODE_NAME     J105 L4
 '@T6G_MB_LIB.T6G(SCH_1):PAGE326_I75@PURE_QUANTA.CONN112_10137002101LF(CHIPS)':
 'L4': CDS_PINID='L4';
NET_NAME
'P5E_CPU0_P3_TX_BUF_C_DP<12>'
 '@T6G_MB_LIB.T6G(SCH_1):P5E_CPU0_P3_TX_BUF_C_DP'<12>:
 C_SIGNAL='@t6g_mb_lib.t6g(sch_1):p5e_cpu0_p3_tx_buf_c_dp(12)';
NODE_NAME     C6621 1
 '@T6G_MB_LIB.T6G(SCH_1):PAGE429_I96@PURE_QUANTA.Q_CAP_DIFFBUS(CHIPS)':
 '1': CDS_PINID='\1\';
NODE_NAME     J105 M5
 '@T6G_MB_LIB.T6G(SCH_1):PAGE326_I76@PURE_QUANTA.CONN112_10137002101LF(CHIPS)':
 'M5': CDS_PINID='M5';
NET_NAME
'P5E_CPU0_P3_TX_BUF_C_DP<13>'
 '@T6G_MB_LIB.T6G(SCH_1):P5E_CPU0_P3_TX_BUF_C_DP'<13>:
 C_SIGNAL='@t6g_mb_lib.t6g(sch_1):p5e_cpu0_p3_tx_buf_c_dp(13)';
NODE_NAME     C6623 1
 '@T6G_MB_LIB.T6G(SCH_1):PAGE429_I94@PURE_QUANTA.Q_CAP_DIFFBUS(CHIPS)':
 '1': CDS_PINID='\1\';
NODE_NAME     J105 L6
 '@T6G_MB_LIB.T6G(SCH_1):PAGE326_I76@PURE_QUANTA.CONN112_10137002101LF(CHIPS)':
 'L6': CDS_PINID='L6';
NET_NAME
'P5E_CPU0_P3_TX_BUF_C_DP<14>'
 '@T6G_MB_LIB.T6G(SCH_1):P5E_CPU0_P3_TX_BUF_C_DP'<14>:
 C_SIGNAL='@t6g_mb_lib.t6g(sch_1):p5e_cpu0_p3_tx_buf_c_dp(14)';
NODE_NAME     C6625 1
 '@T6G_MB_LIB.T6G(SCH_1):PAGE429_I91@PURE_QUANTA.Q_CAP_DIFFBUS(CHIPS)':
 '1': CDS_PINID='\1\';
NODE_NAME     J105 M7
 '@T6G_MB_LIB.T6G(SCH_1):PAGE326_I76@PURE_QUANTA.CONN112_10137002101LF(CHIPS)':
 'M7': CDS_PINID='M7';
NET_NAME
'P5E_CPU0_P3_TX_BUF_C_DP<15>'
 '@T6G_MB_LIB.T6G(SCH_1):P5E_CPU0_P3_TX_BUF_C_DP'<15>:
 C_SIGNAL='@t6g_mb_lib.t6g(sch_1):p5e_cpu0_p3_tx_buf_c_dp(15)';
NODE_NAME     C6627 1
 '@T6G_MB_LIB.T6G(SCH_1):PAGE429_I93@PURE_QUANTA.Q_CAP_DIFFBUS(CHIPS)':
 '1': CDS_PINID='\1\';
NODE_NAME     J105 L8
 '@T6G_MB_LIB.T6G(SCH_1):PAGE326_I76@PURE_QUANTA.CONN112_10137002101LF(CHIPS)':
 'L8': CDS_PINID='L8';
NET_NAME
'P5E_CPU0_P3_TX_BUF_C_DP<1>'
 '@T6G_MB_LIB.T6G(SCH_1):P5E_CPU0_P3_TX_BUF_C_DP'<1>:
 C_SIGNAL='@t6g_mb_lib.t6g(sch_1):p5e_cpu0_p3_tx_buf_c_dp(1)';
NODE_NAME     C6599 1
 '@T6G_MB_LIB.T6G(SCH_1):PAGE429_I38@PURE_QUANTA.Q_CAP_DIFFBUS(CHIPS)':
 '1': CDS_PINID='\1\';
NODE_NAME     J106 L2
 '@T6G_MB_LIB.T6G(SCH_1):PAGE327_I74@PURE_QUANTA.CONN112_10137002101LF(CHIPS)':
 'L2': CDS_PINID='L2';
NET_NAME
'P5E_CPU0_P3_TX_BUF_C_DP<2>'
 '@T6G_MB_LIB.T6G(SCH_1):P5E_CPU0_P3_TX_BUF_C_DP'<2>:
 C_SIGNAL='@t6g_mb_lib.t6g(sch_1):p5e_cpu0_p3_tx_buf_c_dp(2)';
NODE_NAME     C6601 1
 '@T6G_MB_LIB.T6G(SCH_1):PAGE429_I36@PURE_QUANTA.Q_CAP_DIFFBUS(CHIPS)':
 '1': CDS_PINID='\1\';
NODE_NAME     J106 M3
 '@T6G_MB_LIB.T6G(SCH_1):PAGE327_I74@PURE_QUANTA.CONN112_10137002101LF(CHIPS)':
 'M3': CDS_PINID='M3';
NET_NAME
'P5E_CPU0_P3_TX_BUF_C_DP<3>'
 '@T6G_MB_LIB.T6G(SCH_1):P5E_CPU0_P3_TX_BUF_C_DP'<3>:
 C_SIGNAL='@t6g_mb_lib.t6g(sch_1):p5e_cpu0_p3_tx_buf_c_dp(3)';
NODE_NAME     C6603 1
 '@T6G_MB_LIB.T6G(SCH_1):PAGE429_I34@PURE_QUANTA.Q_CAP_DIFFBUS(CHIPS)':
 '1': CDS_PINID='\1\';
NODE_NAME     J106 L4
 '@T6G_MB_LIB.T6G(SCH_1):PAGE327_I74@PURE_QUANTA.CONN112_10137002101LF(CHIPS)':
 'L4': CDS_PINID='L4';
NET_NAME
'P5E_CPU0_P3_TX_BUF_C_DP<4>'
 '@T6G_MB_LIB.T6G(SCH_1):P5E_CPU0_P3_TX_BUF_C_DP'<4>:
 C_SIGNAL='@t6g_mb_lib.t6g(sch_1):p5e_cpu0_p3_tx_buf_c_dp(4)';
NODE_NAME     C6605 1
 '@T6G_MB_LIB.T6G(SCH_1):PAGE429_I32@PURE_QUANTA.Q_CAP_DIFFBUS(CHIPS)':
 '1': CDS_PINID='\1\';
NODE_NAME     J106 M5
 '@T6G_MB_LIB.T6G(SCH_1):PAGE327_I19@PURE_QUANTA.CONN112_10137002101LF(CHIPS)':
 'M5': CDS_PINID='M5';
NET_NAME
'P5E_CPU0_P3_TX_BUF_C_DP<5>'
 '@T6G_MB_LIB.T6G(SCH_1):P5E_CPU0_P3_TX_BUF_C_DP'<5>:
 C_SIGNAL='@t6g_mb_lib.t6g(sch_1):p5e_cpu0_p3_tx_buf_c_dp(5)';
NODE_NAME     C6607 1
 '@T6G_MB_LIB.T6G(SCH_1):PAGE429_I24@PURE_QUANTA.Q_CAP_DIFFBUS(CHIPS)':
 '1': CDS_PINID='\1\';
NODE_NAME     J106 L6
 '@T6G_MB_LIB.T6G(SCH_1):PAGE327_I19@PURE_QUANTA.CONN112_10137002101LF(CHIPS)':
 'L6': CDS_PINID='L6';
NET_NAME
'P5E_CPU0_P3_TX_BUF_C_DP<6>'
 '@T6G_MB_LIB.T6G(SCH_1):P5E_CPU0_P3_TX_BUF_C_DP'<6>:
 C_SIGNAL='@t6g_mb_lib.t6g(sch_1):p5e_cpu0_p3_tx_buf_c_dp(6)';
NODE_NAME     C6609 1
 '@T6G_MB_LIB.T6G(SCH_1):PAGE429_I22@PURE_QUANTA.Q_CAP_DIFFBUS(CHIPS)':
 '1': CDS_PINID='\1\';
NODE_NAME     J106 M7
 '@T6G_MB_LIB.T6G(SCH_1):PAGE327_I19@PURE_QUANTA.CONN112_10137002101LF(CHIPS)':
 'M7': CDS_PINID='M7';
NET_NAME
'P5E_CPU0_P3_TX_BUF_C_DP<7>'
 '@T6G_MB_LIB.T6G(SCH_1):P5E_CPU0_P3_TX_BUF_C_DP'<7>:
 C_SIGNAL='@t6g_mb_lib.t6g(sch_1):p5e_cpu0_p3_tx_buf_c_dp(7)';
NODE_NAME     C6611 1
 '@T6G_MB_LIB.T6G(SCH_1):PAGE429_I19@PURE_QUANTA.Q_CAP_DIFFBUS(CHIPS)':
 '1': CDS_PINID='\1\';
NODE_NAME     J106 L8
 '@T6G_MB_LIB.T6G(SCH_1):PAGE327_I19@PURE_QUANTA.CONN112_10137002101LF(CHIPS)':
 'L8': CDS_PINID='L8';
NET_NAME
'P5E_CPU0_P3_TX_BUF_C_DP<8>'
 '@T6G_MB_LIB.T6G(SCH_1):P5E_CPU0_P3_TX_BUF_C_DP'<8>:
 C_SIGNAL='@t6g_mb_lib.t6g(sch_1):p5e_cpu0_p3_tx_buf_c_dp(8)';
NODE_NAME     C6613 1
 '@T6G_MB_LIB.T6G(SCH_1):PAGE429_I105@PURE_QUANTA.Q_CAP_DIFFBUS(CHIPS)':
 '1': CDS_PINID='\1\';
NODE_NAME     J105 M1
 '@T6G_MB_LIB.T6G(SCH_1):PAGE326_I75@PURE_QUANTA.CONN112_10137002101LF(CHIPS)':
 'M1': CDS_PINID='M1';
NET_NAME
'P5E_CPU0_P3_TX_BUF_C_DP<9>'
 '@T6G_MB_LIB.T6G(SCH_1):P5E_CPU0_P3_TX_BUF_C_DP'<9>:
 C_SIGNAL='@t6g_mb_lib.t6g(sch_1):p5e_cpu0_p3_tx_buf_c_dp(9)';
NODE_NAME     C6615 1
 '@T6G_MB_LIB.T6G(SCH_1):PAGE429_I102@PURE_QUANTA.Q_CAP_DIFFBUS(CHIPS)':
 '1': CDS_PINID='\1\';
NODE_NAME     J105 L2
 '@T6G_MB_LIB.T6G(SCH_1):PAGE326_I75@PURE_QUANTA.CONN112_10137002101LF(CHIPS)':
 'L2': CDS_PINID='L2';
NET_NAME
'P5E_CPU0_P3_TX_BUF_DN<0>'
 '@T6G_MB_LIB.T6G(SCH_1):P5E_CPU0_P3_TX_BUF_DN'<0>:
 C_SIGNAL='@t6g_mb_lib.t6g(sch_1):p5e_cpu0_p3_tx_buf_dn(0)';
NODE_NAME     C6598 2
 '@T6G_MB_LIB.T6G(SCH_1):PAGE429_I39@PURE_QUANTA.Q_CAP_DIFFBUS(CHIPS)':
 '2': CDS_PINID='\2\';
NODE_NAME     U6013 EW10
 '@T6G_MB_LIB.T6G(SCH_1):PAGE429_I142@PURE_QUANTA.PT5161LRS(CHIPS)':
 'B_PETN15': CDS_PINID='B_PETN15';
NET_NAME
'P5E_CPU0_P3_TX_BUF_DN<10>'
 '@T6G_MB_LIB.T6G(SCH_1):P5E_CPU0_P3_TX_BUF_DN'<10>:
 C_SIGNAL='@t6g_mb_lib.t6g(sch_1):p5e_cpu0_p3_tx_buf_dn(10)';
NODE_NAME     U6013 BJ10
 '@T6G_MB_LIB.T6G(SCH_1):PAGE429_I51@PURE_QUANTA.PT5161LRS(CHIPS)':
 'B_PETN5': CDS_PINID='B_PETN5';
NODE_NAME     C6618 2
 '@T6G_MB_LIB.T6G(SCH_1):PAGE429_I99@PURE_QUANTA.Q_CAP_DIFFBUS(CHIPS)':
 '2': CDS_PINID='\2\';
NET_NAME
'P5E_CPU0_P3_TX_BUF_DN<11>'
 '@T6G_MB_LIB.T6G(SCH_1):P5E_CPU0_P3_TX_BUF_DN'<11>:
 C_SIGNAL='@t6g_mb_lib.t6g(sch_1):p5e_cpu0_p3_tx_buf_dn(11)';
NODE_NAME     U6013 BB10
 '@T6G_MB_LIB.T6G(SCH_1):PAGE429_I51@PURE_QUANTA.PT5161LRS(CHIPS)':
 'B_PETN4': CDS_PINID='B_PETN4';
NODE_NAME     C6620 2
 '@T6G_MB_LIB.T6G(SCH_1):PAGE429_I98@PURE_QUANTA.Q_CAP_DIFFBUS(CHIPS)':
 '2': CDS_PINID='\2\';
NET_NAME
'P5E_CPU0_P3_TX_BUF_DN<12>'
 '@T6G_MB_LIB.T6G(SCH_1):P5E_CPU0_P3_TX_BUF_DN'<12>:
 C_SIGNAL='@t6g_mb_lib.t6g(sch_1):p5e_cpu0_p3_tx_buf_dn(12)';
NODE_NAME     U6013 AR10
 '@T6G_MB_LIB.T6G(SCH_1):PAGE429_I51@PURE_QUANTA.PT5161LRS(CHIPS)':
 'B_PETN3': CDS_PINID='B_PETN3';
NODE_NAME     C6622 2
 '@T6G_MB_LIB.T6G(SCH_1):PAGE429_I97@PURE_QUANTA.Q_CAP_DIFFBUS(CHIPS)':
 '2': CDS_PINID='\2\';
NET_NAME
'P5E_CPU0_P3_TX_BUF_DN<13>'
 '@T6G_MB_LIB.T6G(SCH_1):P5E_CPU0_P3_TX_BUF_DN'<13>:
 C_SIGNAL='@t6g_mb_lib.t6g(sch_1):p5e_cpu0_p3_tx_buf_dn(13)';
NODE_NAME     U6013 AH10
 '@T6G_MB_LIB.T6G(SCH_1):PAGE429_I51@PURE_QUANTA.PT5161LRS(CHIPS)':
 'B_PETN2': CDS_PINID='B_PETN2';
NODE_NAME     C6624 2
 '@T6G_MB_LIB.T6G(SCH_1):PAGE429_I95@PURE_QUANTA.Q_CAP_DIFFBUS(CHIPS)':
 '2': CDS_PINID='\2\';
NET_NAME
'P5E_CPU0_P3_TX_BUF_DN<14>'
 '@T6G_MB_LIB.T6G(SCH_1):P5E_CPU0_P3_TX_BUF_DN'<14>:
 C_SIGNAL='@t6g_mb_lib.t6g(sch_1):p5e_cpu0_p3_tx_buf_dn(14)';
NODE_NAME     U6013 AA10
 '@T6G_MB_LIB.T6G(SCH_1):PAGE429_I51@PURE_QUANTA.PT5161LRS(CHIPS)':
 'B_PETN1': CDS_PINID='B_PETN1';
NODE_NAME     C6626 2
 '@T6G_MB_LIB.T6G(SCH_1):PAGE429_I92@PURE_QUANTA.Q_CAP_DIFFBUS(CHIPS)':
 '2': CDS_PINID='\2\';
NET_NAME
'P5E_CPU0_P3_TX_BUF_DN<15>'
 '@T6G_MB_LIB.T6G(SCH_1):P5E_CPU0_P3_TX_BUF_DN'<15>:
 C_SIGNAL='@t6g_mb_lib.t6g(sch_1):p5e_cpu0_p3_tx_buf_dn(15)';
NODE_NAME     U6013 P10
 '@T6G_MB_LIB.T6G(SCH_1):PAGE429_I51@PURE_QUANTA.PT5161LRS(CHIPS)':
 'B_PETN0': CDS_PINID='B_PETN0';
NODE_NAME     C6628 2
 '@T6G_MB_LIB.T6G(SCH_1):PAGE429_I90@PURE_QUANTA.Q_CAP_DIFFBUS(CHIPS)':
 '2': CDS_PINID='\2\';
NET_NAME
'P5E_CPU0_P3_TX_BUF_DN<1>'
 '@T6G_MB_LIB.T6G(SCH_1):P5E_CPU0_P3_TX_BUF_DN'<1>:
 C_SIGNAL='@t6g_mb_lib.t6g(sch_1):p5e_cpu0_p3_tx_buf_dn(1)';
NODE_NAME     C6600 2
 '@T6G_MB_LIB.T6G(SCH_1):PAGE429_I37@PURE_QUANTA.Q_CAP_DIFFBUS(CHIPS)':
 '2': CDS_PINID='\2\';
NODE_NAME     U6013 EM10
 '@T6G_MB_LIB.T6G(SCH_1):PAGE429_I142@PURE_QUANTA.PT5161LRS(CHIPS)':
 'B_PETN14': CDS_PINID='B_PETN14';
NET_NAME
'P5E_CPU0_P3_TX_BUF_DN<2>'
 '@T6G_MB_LIB.T6G(SCH_1):P5E_CPU0_P3_TX_BUF_DN'<2>:
 C_SIGNAL='@t6g_mb_lib.t6g(sch_1):p5e_cpu0_p3_tx_buf_dn(2)';
NODE_NAME     C6602 2
 '@T6G_MB_LIB.T6G(SCH_1):PAGE429_I35@PURE_QUANTA.Q_CAP_DIFFBUS(CHIPS)':
 '2': CDS_PINID='\2\';
NODE_NAME     U6013 EE10
 '@T6G_MB_LIB.T6G(SCH_1):PAGE429_I142@PURE_QUANTA.PT5161LRS(CHIPS)':
 'B_PETN13': CDS_PINID='B_PETN13';
NET_NAME
'P5E_CPU0_P3_TX_BUF_DN<3>'
 '@T6G_MB_LIB.T6G(SCH_1):P5E_CPU0_P3_TX_BUF_DN'<3>:
 C_SIGNAL='@t6g_mb_lib.t6g(sch_1):p5e_cpu0_p3_tx_buf_dn(3)';
NODE_NAME     C6604 2
 '@T6G_MB_LIB.T6G(SCH_1):PAGE429_I33@PURE_QUANTA.Q_CAP_DIFFBUS(CHIPS)':
 '2': CDS_PINID='\2\';
NODE_NAME     U6013 DV10
 '@T6G_MB_LIB.T6G(SCH_1):PAGE429_I142@PURE_QUANTA.PT5161LRS(CHIPS)':
 'B_PETN12': CDS_PINID='B_PETN12';
NET_NAME
'P5E_CPU0_P3_TX_BUF_DN<4>'
 '@T6G_MB_LIB.T6G(SCH_1):P5E_CPU0_P3_TX_BUF_DN'<4>:
 C_SIGNAL='@t6g_mb_lib.t6g(sch_1):p5e_cpu0_p3_tx_buf_dn(4)';
NODE_NAME     C6606 2
 '@T6G_MB_LIB.T6G(SCH_1):PAGE429_I31@PURE_QUANTA.Q_CAP_DIFFBUS(CHIPS)':
 '2': CDS_PINID='\2\';
NODE_NAME     U6013 DL10
 '@T6G_MB_LIB.T6G(SCH_1):PAGE429_I142@PURE_QUANTA.PT5161LRS(CHIPS)':
 'B_PETN11': CDS_PINID='B_PETN11';
NET_NAME
'P5E_CPU0_P3_TX_BUF_DN<5>'
 '@T6G_MB_LIB.T6G(SCH_1):P5E_CPU0_P3_TX_BUF_DN'<5>:
 C_SIGNAL='@t6g_mb_lib.t6g(sch_1):p5e_cpu0_p3_tx_buf_dn(5)';
NODE_NAME     C6608 2
 '@T6G_MB_LIB.T6G(SCH_1):PAGE429_I23@PURE_QUANTA.Q_CAP_DIFFBUS(CHIPS)':
 '2': CDS_PINID='\2\';
NODE_NAME     U6013 DD10
 '@T6G_MB_LIB.T6G(SCH_1):PAGE429_I142@PURE_QUANTA.PT5161LRS(CHIPS)':
 'B_PETN10': CDS_PINID='B_PETN10';
NET_NAME
'P5E_CPU0_P3_TX_BUF_DN<6>'
 '@T6G_MB_LIB.T6G(SCH_1):P5E_CPU0_P3_TX_BUF_DN'<6>:
 C_SIGNAL='@t6g_mb_lib.t6g(sch_1):p5e_cpu0_p3_tx_buf_dn(6)';
NODE_NAME     C6610 2
 '@T6G_MB_LIB.T6G(SCH_1):PAGE429_I21@PURE_QUANTA.Q_CAP_DIFFBUS(CHIPS)':
 '2': CDS_PINID='\2\';
NODE_NAME     U6013 CU10
 '@T6G_MB_LIB.T6G(SCH_1):PAGE429_I142@PURE_QUANTA.PT5161LRS(CHIPS)':
 'B_PETN9': CDS_PINID='B_PETN9';
NET_NAME
'P5E_CPU0_P3_TX_BUF_DN<7>'
 '@T6G_MB_LIB.T6G(SCH_1):P5E_CPU0_P3_TX_BUF_DN'<7>:
 C_SIGNAL='@t6g_mb_lib.t6g(sch_1):p5e_cpu0_p3_tx_buf_dn(7)';
NODE_NAME     C6612 2
 '@T6G_MB_LIB.T6G(SCH_1):PAGE429_I20@PURE_QUANTA.Q_CAP_DIFFBUS(CHIPS)':
 '2': CDS_PINID='\2\';
NODE_NAME     U6013 CK10
 '@T6G_MB_LIB.T6G(SCH_1):PAGE429_I142@PURE_QUANTA.PT5161LRS(CHIPS)':
 'B_PETN8': CDS_PINID='B_PETN8';
NET_NAME
'P5E_CPU0_P3_TX_BUF_DN<8>'
 '@T6G_MB_LIB.T6G(SCH_1):P5E_CPU0_P3_TX_BUF_DN'<8>:
 C_SIGNAL='@t6g_mb_lib.t6g(sch_1):p5e_cpu0_p3_tx_buf_dn(8)';
NODE_NAME     U6013 CC10
 '@T6G_MB_LIB.T6G(SCH_1):PAGE429_I51@PURE_QUANTA.PT5161LRS(CHIPS)':
 'B_PETN7': CDS_PINID='B_PETN7';
NODE_NAME     C6614 2
 '@T6G_MB_LIB.T6G(SCH_1):PAGE429_I104@PURE_QUANTA.Q_CAP_DIFFBUS(CHIPS)':
 '2': CDS_PINID='\2\';
NET_NAME
'P5E_CPU0_P3_TX_BUF_DN<9>'
 '@T6G_MB_LIB.T6G(SCH_1):P5E_CPU0_P3_TX_BUF_DN'<9>:
 C_SIGNAL='@t6g_mb_lib.t6g(sch_1):p5e_cpu0_p3_tx_buf_dn(9)';
NODE_NAME     U6013 BT10
 '@T6G_MB_LIB.T6G(SCH_1):PAGE429_I51@PURE_QUANTA.PT5161LRS(CHIPS)':
 'B_PETN6': CDS_PINID='B_PETN6';
NODE_NAME     C6616 2
 '@T6G_MB_LIB.T6G(SCH_1):PAGE429_I103@PURE_QUANTA.Q_CAP_DIFFBUS(CHIPS)':
 '2': CDS_PINID='\2\';
NET_NAME
'P5E_CPU0_P3_TX_BUF_DP<0>'
 '@T6G_MB_LIB.T6G(SCH_1):P5E_CPU0_P3_TX_BUF_DP'<0>:
 C_SIGNAL='@t6g_mb_lib.t6g(sch_1):p5e_cpu0_p3_tx_buf_dp(0)';
NODE_NAME     C6597 2
 '@T6G_MB_LIB.T6G(SCH_1):PAGE429_I40@PURE_QUANTA.Q_CAP_DIFFBUS(CHIPS)':
 '2': CDS_PINID='\2\';
NODE_NAME     U6013 EU7
 '@T6G_MB_LIB.T6G(SCH_1):PAGE429_I142@PURE_QUANTA.PT5161LRS(CHIPS)':
 'B_PETP15': CDS_PINID='B_PETP15';
NET_NAME
'P5E_CPU0_P3_TX_BUF_DP<10>'
 '@T6G_MB_LIB.T6G(SCH_1):P5E_CPU0_P3_TX_BUF_DP'<10>:
 C_SIGNAL='@t6g_mb_lib.t6g(sch_1):p5e_cpu0_p3_tx_buf_dp(10)';
NODE_NAME     U6013 BG7
 '@T6G_MB_LIB.T6G(SCH_1):PAGE429_I51@PURE_QUANTA.PT5161LRS(CHIPS)':
 'B_PETP5': CDS_PINID='B_PETP5';
NODE_NAME     C6617 2
 '@T6G_MB_LIB.T6G(SCH_1):PAGE429_I101@PURE_QUANTA.Q_CAP_DIFFBUS(CHIPS)':
 '2': CDS_PINID='\2\';
NET_NAME
'P5E_CPU0_P3_TX_BUF_DP<11>'
 '@T6G_MB_LIB.T6G(SCH_1):P5E_CPU0_P3_TX_BUF_DP'<11>:
 C_SIGNAL='@t6g_mb_lib.t6g(sch_1):p5e_cpu0_p3_tx_buf_dp(11)';
NODE_NAME     U6013 AY7
 '@T6G_MB_LIB.T6G(SCH_1):PAGE429_I51@PURE_QUANTA.PT5161LRS(CHIPS)':
 'B_PETP4': CDS_PINID='B_PETP4';
NODE_NAME     C6619 2
 '@T6G_MB_LIB.T6G(SCH_1):PAGE429_I100@PURE_QUANTA.Q_CAP_DIFFBUS(CHIPS)':
 '2': CDS_PINID='\2\';
NET_NAME
'P5E_CPU0_P3_TX_BUF_DP<12>'
 '@T6G_MB_LIB.T6G(SCH_1):P5E_CPU0_P3_TX_BUF_DP'<12>:
 C_SIGNAL='@t6g_mb_lib.t6g(sch_1):p5e_cpu0_p3_tx_buf_dp(12)';
NODE_NAME     U6013 AN7
 '@T6G_MB_LIB.T6G(SCH_1):PAGE429_I51@PURE_QUANTA.PT5161LRS(CHIPS)':
 'B_PETP3': CDS_PINID='B_PETP3';
NODE_NAME     C6621 2
 '@T6G_MB_LIB.T6G(SCH_1):PAGE429_I96@PURE_QUANTA.Q_CAP_DIFFBUS(CHIPS)':
 '2': CDS_PINID='\2\';
NET_NAME
'P5E_CPU0_P3_TX_BUF_DP<13>'
 '@T6G_MB_LIB.T6G(SCH_1):P5E_CPU0_P3_TX_BUF_DP'<13>:
 C_SIGNAL='@t6g_mb_lib.t6g(sch_1):p5e_cpu0_p3_tx_buf_dp(13)';
NODE_NAME     U6013 AF7
 '@T6G_MB_LIB.T6G(SCH_1):PAGE429_I51@PURE_QUANTA.PT5161LRS(CHIPS)':
 'B_PETP2': CDS_PINID='B_PETP2';
NODE_NAME     C6623 2
 '@T6G_MB_LIB.T6G(SCH_1):PAGE429_I94@PURE_QUANTA.Q_CAP_DIFFBUS(CHIPS)':
 '2': CDS_PINID='\2\';
NET_NAME
'P5E_CPU0_P3_TX_BUF_DP<14>'
 '@T6G_MB_LIB.T6G(SCH_1):P5E_CPU0_P3_TX_BUF_DP'<14>:
 C_SIGNAL='@t6g_mb_lib.t6g(sch_1):p5e_cpu0_p3_tx_buf_dp(14)';
NODE_NAME     U6013 W7
 '@T6G_MB_LIB.T6G(SCH_1):PAGE429_I51@PURE_QUANTA.PT5161LRS(CHIPS)':
 'B_PETP1': CDS_PINID='B_PETP1';
NODE_NAME     C6625 2
 '@T6G_MB_LIB.T6G(SCH_1):PAGE429_I91@PURE_QUANTA.Q_CAP_DIFFBUS(CHIPS)':
 '2': CDS_PINID='\2\';
NET_NAME
'P5E_CPU0_P3_TX_BUF_DP<15>'
 '@T6G_MB_LIB.T6G(SCH_1):P5E_CPU0_P3_TX_BUF_DP'<15>:
 C_SIGNAL='@t6g_mb_lib.t6g(sch_1):p5e_cpu0_p3_tx_buf_dp(15)';
NODE_NAME     U6013 M7
 '@T6G_MB_LIB.T6G(SCH_1):PAGE429_I51@PURE_QUANTA.PT5161LRS(CHIPS)':
 'B_PETP0': CDS_PINID='B_PETP0';
NODE_NAME     C6627 2
 '@T6G_MB_LIB.T6G(SCH_1):PAGE429_I93@PURE_QUANTA.Q_CAP_DIFFBUS(CHIPS)':
 '2': CDS_PINID='\2\';
NET_NAME
'P5E_CPU0_P3_TX_BUF_DP<1>'
 '@T6G_MB_LIB.T6G(SCH_1):P5E_CPU0_P3_TX_BUF_DP'<1>:
 C_SIGNAL='@t6g_mb_lib.t6g(sch_1):p5e_cpu0_p3_tx_buf_dp(1)';
NODE_NAME     C6599 2
 '@T6G_MB_LIB.T6G(SCH_1):PAGE429_I38@PURE_QUANTA.Q_CAP_DIFFBUS(CHIPS)':
 '2': CDS_PINID='\2\';
NODE_NAME     U6013 EK7
 '@T6G_MB_LIB.T6G(SCH_1):PAGE429_I142@PURE_QUANTA.PT5161LRS(CHIPS)':
 'B_PETP14': CDS_PINID='B_PETP14';
NET_NAME
'P5E_CPU0_P3_TX_BUF_DP<2>'
 '@T6G_MB_LIB.T6G(SCH_1):P5E_CPU0_P3_TX_BUF_DP'<2>:
 C_SIGNAL='@t6g_mb_lib.t6g(sch_1):p5e_cpu0_p3_tx_buf_dp(2)';
NODE_NAME     C6601 2
 '@T6G_MB_LIB.T6G(SCH_1):PAGE429_I36@PURE_QUANTA.Q_CAP_DIFFBUS(CHIPS)':
 '2': CDS_PINID='\2\';
NODE_NAME     U6013 EC7
 '@T6G_MB_LIB.T6G(SCH_1):PAGE429_I142@PURE_QUANTA.PT5161LRS(CHIPS)':
 'B_PETP13': CDS_PINID='B_PETP13';
NET_NAME
'P5E_CPU0_P3_TX_BUF_DP<3>'
 '@T6G_MB_LIB.T6G(SCH_1):P5E_CPU0_P3_TX_BUF_DP'<3>:
 C_SIGNAL='@t6g_mb_lib.t6g(sch_1):p5e_cpu0_p3_tx_buf_dp(3)';
NODE_NAME     C6603 2
 '@T6G_MB_LIB.T6G(SCH_1):PAGE429_I34@PURE_QUANTA.Q_CAP_DIFFBUS(CHIPS)':
 '2': CDS_PINID='\2\';
NODE_NAME     U6013 DT7
 '@T6G_MB_LIB.T6G(SCH_1):PAGE429_I142@PURE_QUANTA.PT5161LRS(CHIPS)':
 'B_PETP12': CDS_PINID='B_PETP12';
NET_NAME
'P5E_CPU0_P3_TX_BUF_DP<4>'
 '@T6G_MB_LIB.T6G(SCH_1):P5E_CPU0_P3_TX_BUF_DP'<4>:
 C_SIGNAL='@t6g_mb_lib.t6g(sch_1):p5e_cpu0_p3_tx_buf_dp(4)';
NODE_NAME     C6605 2
 '@T6G_MB_LIB.T6G(SCH_1):PAGE429_I32@PURE_QUANTA.Q_CAP_DIFFBUS(CHIPS)':
 '2': CDS_PINID='\2\';
NODE_NAME     U6013 DJ7
 '@T6G_MB_LIB.T6G(SCH_1):PAGE429_I142@PURE_QUANTA.PT5161LRS(CHIPS)':
 'B_PETP11': CDS_PINID='B_PETP11';
NET_NAME
'P5E_CPU0_P3_TX_BUF_DP<5>'
 '@T6G_MB_LIB.T6G(SCH_1):P5E_CPU0_P3_TX_BUF_DP'<5>:
 C_SIGNAL='@t6g_mb_lib.t6g(sch_1):p5e_cpu0_p3_tx_buf_dp(5)';
NODE_NAME     C6607 2
 '@T6G_MB_LIB.T6G(SCH_1):PAGE429_I24@PURE_QUANTA.Q_CAP_DIFFBUS(CHIPS)':
 '2': CDS_PINID='\2\';
NODE_NAME     U6013 DB7
 '@T6G_MB_LIB.T6G(SCH_1):PAGE429_I142@PURE_QUANTA.PT5161LRS(CHIPS)':
 'B_PETP10': CDS_PINID='B_PETP10';
NET_NAME
'P5E_CPU0_P3_TX_BUF_DP<6>'
 '@T6G_MB_LIB.T6G(SCH_1):P5E_CPU0_P3_TX_BUF_DP'<6>:
 C_SIGNAL='@t6g_mb_lib.t6g(sch_1):p5e_cpu0_p3_tx_buf_dp(6)';
NODE_NAME     C6609 2
 '@T6G_MB_LIB.T6G(SCH_1):PAGE429_I22@PURE_QUANTA.Q_CAP_DIFFBUS(CHIPS)':
 '2': CDS_PINID='\2\';
NODE_NAME     U6013 CR7
 '@T6G_MB_LIB.T6G(SCH_1):PAGE429_I142@PURE_QUANTA.PT5161LRS(CHIPS)':
 'B_PETP9': CDS_PINID='B_PETP9';
NET_NAME
'P5E_CPU0_P3_TX_BUF_DP<7>'
 '@T6G_MB_LIB.T6G(SCH_1):P5E_CPU0_P3_TX_BUF_DP'<7>:
 C_SIGNAL='@t6g_mb_lib.t6g(sch_1):p5e_cpu0_p3_tx_buf_dp(7)';
NODE_NAME     C6611 2
 '@T6G_MB_LIB.T6G(SCH_1):PAGE429_I19@PURE_QUANTA.Q_CAP_DIFFBUS(CHIPS)':
 '2': CDS_PINID='\2\';
NODE_NAME     U6013 CH7
 '@T6G_MB_LIB.T6G(SCH_1):PAGE429_I142@PURE_QUANTA.PT5161LRS(CHIPS)':
 'B_PETP8': CDS_PINID='B_PETP8';
NET_NAME
'P5E_CPU0_P3_TX_BUF_DP<8>'
 '@T6G_MB_LIB.T6G(SCH_1):P5E_CPU0_P3_TX_BUF_DP'<8>:
 C_SIGNAL='@t6g_mb_lib.t6g(sch_1):p5e_cpu0_p3_tx_buf_dp(8)';
NODE_NAME     U6013 CA7
 '@T6G_MB_LIB.T6G(SCH_1):PAGE429_I51@PURE_QUANTA.PT5161LRS(CHIPS)':
 'B_PETP7': CDS_PINID='B_PETP7';
NODE_NAME     C6613 2
 '@T6G_MB_LIB.T6G(SCH_1):PAGE429_I105@PURE_QUANTA.Q_CAP_DIFFBUS(CHIPS)':
 '2': CDS_PINID='\2\';
NET_NAME
'P5E_CPU0_P3_TX_BUF_DP<9>'
 '@T6G_MB_LIB.T6G(SCH_1):P5E_CPU0_P3_TX_BUF_DP'<9>:
 C_SIGNAL='@t6g_mb_lib.t6g(sch_1):p5e_cpu0_p3_tx_buf_dp(9)';
NODE_NAME     U6013 BP7
 '@T6G_MB_LIB.T6G(SCH_1):PAGE429_I51@PURE_QUANTA.PT5161LRS(CHIPS)':
 'B_PETP6': CDS_PINID='B_PETP6';
NODE_NAME     C6615 2
 '@T6G_MB_LIB.T6G(SCH_1):PAGE429_I102@PURE_QUANTA.Q_CAP_DIFFBUS(CHIPS)':
 '2': CDS_PINID='\2\';
NET_NAME
'P5E_CPU0_P3_TX_C_DN<0>'
 '@T6G_MB_LIB.T6G(SCH_1):P5E_CPU0_P3_TX_C_DN'<0>:
 C_SIGNAL='@t6g_mb_lib.t6g(sch_1):p5e_cpu0_p3_tx_c_dn(0)';
NODE_NAME     C900 1
 '@T6G_MB_LIB.T6G(SCH_1):PAGE352_I121@PURE_QUANTA.Q_CAP_DIFFBUS(CHIPS)':
 '1': CDS_PINID='\1\';
NODE_NAME     U6013 EV34
 '@T6G_MB_LIB.T6G(SCH_1):PAGE426_I38@PURE_QUANTA.PT5161LRS(CHIPS)':
 'B_PERP15': CDS_PINID='B_PERP15';
NET_NAME
'P5E_CPU0_P3_TX_C_DN<10>'
 '@T6G_MB_LIB.T6G(SCH_1):P5E_CPU0_P3_TX_C_DN'<10>:
 C_SIGNAL='@t6g_mb_lib.t6g(sch_1):p5e_cpu0_p3_tx_c_dn(10)';
NODE_NAME     C880 1
 '@T6G_MB_LIB.T6G(SCH_1):PAGE352_I156@PURE_QUANTA.Q_CAP_DIFFBUS(CHIPS)':
 '1': CDS_PINID='\1\';
NODE_NAME     U6013 BH34
 '@T6G_MB_LIB.T6G(SCH_1):PAGE426_I1@PURE_QUANTA.PT5161LRS(CHIPS)':
 'B_PERP5': CDS_PINID='B_PERP5';
NET_NAME
'P5E_CPU0_P3_TX_C_DN<11>'
 '@T6G_MB_LIB.T6G(SCH_1):P5E_CPU0_P3_TX_C_DN'<11>:
 C_SIGNAL='@t6g_mb_lib.t6g(sch_1):p5e_cpu0_p3_tx_c_dn(11)';
NODE_NAME     C878 1
 '@T6G_MB_LIB.T6G(SCH_1):PAGE352_I157@PURE_QUANTA.Q_CAP_DIFFBUS(CHIPS)':
 '1': CDS_PINID='\1\';
NODE_NAME     U6013 BA34
 '@T6G_MB_LIB.T6G(SCH_1):PAGE426_I1@PURE_QUANTA.PT5161LRS(CHIPS)':
 'B_PERP4': CDS_PINID='B_PERP4';
NET_NAME
'P5E_CPU0_P3_TX_C_DN<12>'
 '@T6G_MB_LIB.T6G(SCH_1):P5E_CPU0_P3_TX_C_DN'<12>:
 C_SIGNAL='@t6g_mb_lib.t6g(sch_1):p5e_cpu0_p3_tx_c_dn(12)';
NODE_NAME     C876 1
 '@T6G_MB_LIB.T6G(SCH_1):PAGE352_I160@PURE_QUANTA.Q_CAP_DIFFBUS(CHIPS)':
 '1': CDS_PINID='\1\';
NODE_NAME     U6013 AP34
 '@T6G_MB_LIB.T6G(SCH_1):PAGE426_I1@PURE_QUANTA.PT5161LRS(CHIPS)':
 'B_PERP3': CDS_PINID='B_PERP3';
NET_NAME
'P5E_CPU0_P3_TX_C_DN<13>'
 '@T6G_MB_LIB.T6G(SCH_1):P5E_CPU0_P3_TX_C_DN'<13>:
 C_SIGNAL='@t6g_mb_lib.t6g(sch_1):p5e_cpu0_p3_tx_c_dn(13)';
NODE_NAME     C874 1
 '@T6G_MB_LIB.T6G(SCH_1):PAGE352_I165@PURE_QUANTA.Q_CAP_DIFFBUS(CHIPS)':
 '1': CDS_PINID='\1\';
NODE_NAME     U6013 AG34
 '@T6G_MB_LIB.T6G(SCH_1):PAGE426_I1@PURE_QUANTA.PT5161LRS(CHIPS)':
 'B_PERP2': CDS_PINID='B_PERP2';
NET_NAME
'P5E_CPU0_P3_TX_C_DN<14>'
 '@T6G_MB_LIB.T6G(SCH_1):P5E_CPU0_P3_TX_C_DN'<14>:
 C_SIGNAL='@t6g_mb_lib.t6g(sch_1):p5e_cpu0_p3_tx_c_dn(14)';
NODE_NAME     C872 1
 '@T6G_MB_LIB.T6G(SCH_1):PAGE352_I167@PURE_QUANTA.Q_CAP_DIFFBUS(CHIPS)':
 '1': CDS_PINID='\1\';
NODE_NAME     U6013 AB35
 '@T6G_MB_LIB.T6G(SCH_1):PAGE426_I1@PURE_QUANTA.PT5161LRS(CHIPS)':
 'B_PERN1': CDS_PINID='B_PERN1';
NET_NAME
'P5E_CPU0_P3_TX_C_DN<15>'
 '@T6G_MB_LIB.T6G(SCH_1):P5E_CPU0_P3_TX_C_DN'<15>:
 C_SIGNAL='@t6g_mb_lib.t6g(sch_1):p5e_cpu0_p3_tx_c_dn(15)';
NODE_NAME     C870 1
 '@T6G_MB_LIB.T6G(SCH_1):PAGE352_I169@PURE_QUANTA.Q_CAP_DIFFBUS(CHIPS)':
 '1': CDS_PINID='\1\';
NODE_NAME     U6013 N34
 '@T6G_MB_LIB.T6G(SCH_1):PAGE426_I1@PURE_QUANTA.PT5161LRS(CHIPS)':
 'B_PERP0': CDS_PINID='B_PERP0';
NET_NAME
'P5E_CPU0_P3_TX_C_DN<1>'
 '@T6G_MB_LIB.T6G(SCH_1):P5E_CPU0_P3_TX_C_DN'<1>:
 C_SIGNAL='@t6g_mb_lib.t6g(sch_1):p5e_cpu0_p3_tx_c_dn(1)';
NODE_NAME     C898 1
 '@T6G_MB_LIB.T6G(SCH_1):PAGE352_I206@PURE_QUANTA.Q_CAP_DIFFBUS(CHIPS)':
 '1': CDS_PINID='\1\';
NODE_NAME     U6013 EN35
 '@T6G_MB_LIB.T6G(SCH_1):PAGE426_I38@PURE_QUANTA.PT5161LRS(CHIPS)':
 'B_PERN14': CDS_PINID='B_PERN14';
NET_NAME
'P5E_CPU0_P3_TX_C_DN<2>'
 '@T6G_MB_LIB.T6G(SCH_1):P5E_CPU0_P3_TX_C_DN'<2>:
 C_SIGNAL='@t6g_mb_lib.t6g(sch_1):p5e_cpu0_p3_tx_c_dn(2)';
NODE_NAME     C896 1
 '@T6G_MB_LIB.T6G(SCH_1):PAGE352_I124@PURE_QUANTA.Q_CAP_DIFFBUS(CHIPS)':
 '1': CDS_PINID='\1\';
NODE_NAME     U6013 ED34
 '@T6G_MB_LIB.T6G(SCH_1):PAGE426_I38@PURE_QUANTA.PT5161LRS(CHIPS)':
 'B_PERP13': CDS_PINID='B_PERP13';
NET_NAME
'P5E_CPU0_P3_TX_C_DN<3>'
 '@T6G_MB_LIB.T6G(SCH_1):P5E_CPU0_P3_TX_C_DN'<3>:
 C_SIGNAL='@t6g_mb_lib.t6g(sch_1):p5e_cpu0_p3_tx_c_dn(3)';
NODE_NAME     C894 1
 '@T6G_MB_LIB.T6G(SCH_1):PAGE352_I126@PURE_QUANTA.Q_CAP_DIFFBUS(CHIPS)':
 '1': CDS_PINID='\1\';
NODE_NAME     U6013 DU34
 '@T6G_MB_LIB.T6G(SCH_1):PAGE426_I38@PURE_QUANTA.PT5161LRS(CHIPS)':
 'B_PERP12': CDS_PINID='B_PERP12';
NET_NAME
'P5E_CPU0_P3_TX_C_DN<4>'
 '@T6G_MB_LIB.T6G(SCH_1):P5E_CPU0_P3_TX_C_DN'<4>:
 C_SIGNAL='@t6g_mb_lib.t6g(sch_1):p5e_cpu0_p3_tx_c_dn(4)';
NODE_NAME     C892 1
 '@T6G_MB_LIB.T6G(SCH_1):PAGE352_I127@PURE_QUANTA.Q_CAP_DIFFBUS(CHIPS)':
 '1': CDS_PINID='\1\';
NODE_NAME     U6013 DK34
 '@T6G_MB_LIB.T6G(SCH_1):PAGE426_I38@PURE_QUANTA.PT5161LRS(CHIPS)':
 'B_PERP11': CDS_PINID='B_PERP11';
NET_NAME
'P5E_CPU0_P3_TX_C_DN<5>'
 '@T6G_MB_LIB.T6G(SCH_1):P5E_CPU0_P3_TX_C_DN'<5>:
 C_SIGNAL='@t6g_mb_lib.t6g(sch_1):p5e_cpu0_p3_tx_c_dn(5)';
NODE_NAME     C890 1
 '@T6G_MB_LIB.T6G(SCH_1):PAGE352_I133@PURE_QUANTA.Q_CAP_DIFFBUS(CHIPS)':
 '1': CDS_PINID='\1\';
NODE_NAME     U6013 DC34
 '@T6G_MB_LIB.T6G(SCH_1):PAGE426_I38@PURE_QUANTA.PT5161LRS(CHIPS)':
 'B_PERP10': CDS_PINID='B_PERP10';
NET_NAME
'P5E_CPU0_P3_TX_C_DN<6>'
 '@T6G_MB_LIB.T6G(SCH_1):P5E_CPU0_P3_TX_C_DN'<6>:
 C_SIGNAL='@t6g_mb_lib.t6g(sch_1):p5e_cpu0_p3_tx_c_dn(6)';
NODE_NAME     C888 1
 '@T6G_MB_LIB.T6G(SCH_1):PAGE352_I135@PURE_QUANTA.Q_CAP_DIFFBUS(CHIPS)':
 '1': CDS_PINID='\1\';
NODE_NAME     U6013 CT34
 '@T6G_MB_LIB.T6G(SCH_1):PAGE426_I38@PURE_QUANTA.PT5161LRS(CHIPS)':
 'B_PERP9': CDS_PINID='B_PERP9';
NET_NAME
'P5E_CPU0_P3_TX_C_DN<7>'
 '@T6G_MB_LIB.T6G(SCH_1):P5E_CPU0_P3_TX_C_DN'<7>:
 C_SIGNAL='@t6g_mb_lib.t6g(sch_1):p5e_cpu0_p3_tx_c_dn(7)';
NODE_NAME     C886 1
 '@T6G_MB_LIB.T6G(SCH_1):PAGE352_I137@PURE_QUANTA.Q_CAP_DIFFBUS(CHIPS)':
 '1': CDS_PINID='\1\';
NODE_NAME     U6013 CJ34
 '@T6G_MB_LIB.T6G(SCH_1):PAGE426_I38@PURE_QUANTA.PT5161LRS(CHIPS)':
 'B_PERP8': CDS_PINID='B_PERP8';
NET_NAME
'P5E_CPU0_P3_TX_C_DN<8>'
 '@T6G_MB_LIB.T6G(SCH_1):P5E_CPU0_P3_TX_C_DN'<8>:
 C_SIGNAL='@t6g_mb_lib.t6g(sch_1):p5e_cpu0_p3_tx_c_dn(8)';
NODE_NAME     C884 1
 '@T6G_MB_LIB.T6G(SCH_1):PAGE352_I151@PURE_QUANTA.Q_CAP_DIFFBUS(CHIPS)':
 '1': CDS_PINID='\1\';
NODE_NAME     U6013 CB34
 '@T6G_MB_LIB.T6G(SCH_1):PAGE426_I1@PURE_QUANTA.PT5161LRS(CHIPS)':
 'B_PERP7': CDS_PINID='B_PERP7';
NET_NAME
'P5E_CPU0_P3_TX_C_DN<9>'
 '@T6G_MB_LIB.T6G(SCH_1):P5E_CPU0_P3_TX_C_DN'<9>:
 C_SIGNAL='@t6g_mb_lib.t6g(sch_1):p5e_cpu0_p3_tx_c_dn(9)';
NODE_NAME     C882 1
 '@T6G_MB_LIB.T6G(SCH_1):PAGE352_I154@PURE_QUANTA.Q_CAP_DIFFBUS(CHIPS)':
 '1': CDS_PINID='\1\';
NODE_NAME     U6013 BR34
 '@T6G_MB_LIB.T6G(SCH_1):PAGE426_I1@PURE_QUANTA.PT5161LRS(CHIPS)':
 'B_PERP6': CDS_PINID='B_PERP6';
NET_NAME
'P5E_CPU0_P3_TX_C_DP<0>'
 '@T6G_MB_LIB.T6G(SCH_1):P5E_CPU0_P3_TX_C_DP'<0>:
 C_SIGNAL='@t6g_mb_lib.t6g(sch_1):p5e_cpu0_p3_tx_c_dp(0)';
NODE_NAME     C901 1
 '@T6G_MB_LIB.T6G(SCH_1):PAGE352_I120@PURE_QUANTA.Q_CAP_DIFFBUS(CHIPS)':
 '1': CDS_PINID='\1\';
NODE_NAME     U6013 EY35
 '@T6G_MB_LIB.T6G(SCH_1):PAGE426_I38@PURE_QUANTA.PT5161LRS(CHIPS)':
 'B_PERN15': CDS_PINID='B_PERN15';
NET_NAME
'P5E_CPU0_P3_TX_C_DP<10>'
 '@T6G_MB_LIB.T6G(SCH_1):P5E_CPU0_P3_TX_C_DP'<10>:
 C_SIGNAL='@t6g_mb_lib.t6g(sch_1):p5e_cpu0_p3_tx_c_dp(10)';
NODE_NAME     C881 1
 '@T6G_MB_LIB.T6G(SCH_1):PAGE352_I155@PURE_QUANTA.Q_CAP_DIFFBUS(CHIPS)':
 '1': CDS_PINID='\1\';
NODE_NAME     U6013 BK35
 '@T6G_MB_LIB.T6G(SCH_1):PAGE426_I1@PURE_QUANTA.PT5161LRS(CHIPS)':
 'B_PERN5': CDS_PINID='B_PERN5';
NET_NAME
'P5E_CPU0_P3_TX_C_DP<11>'
 '@T6G_MB_LIB.T6G(SCH_1):P5E_CPU0_P3_TX_C_DP'<11>:
 C_SIGNAL='@t6g_mb_lib.t6g(sch_1):p5e_cpu0_p3_tx_c_dp(11)';
NODE_NAME     C879 1
 '@T6G_MB_LIB.T6G(SCH_1):PAGE352_I158@PURE_QUANTA.Q_CAP_DIFFBUS(CHIPS)':
 '1': CDS_PINID='\1\';
NODE_NAME     U6013 BC35
 '@T6G_MB_LIB.T6G(SCH_1):PAGE426_I1@PURE_QUANTA.PT5161LRS(CHIPS)':
 'B_PERN4': CDS_PINID='B_PERN4';
NET_NAME
'P5E_CPU0_P3_TX_C_DP<12>'
 '@T6G_MB_LIB.T6G(SCH_1):P5E_CPU0_P3_TX_C_DP'<12>:
 C_SIGNAL='@t6g_mb_lib.t6g(sch_1):p5e_cpu0_p3_tx_c_dp(12)';
NODE_NAME     C877 1
 '@T6G_MB_LIB.T6G(SCH_1):PAGE352_I159@PURE_QUANTA.Q_CAP_DIFFBUS(CHIPS)':
 '1': CDS_PINID='\1\';
NODE_NAME     U6013 AT35
 '@T6G_MB_LIB.T6G(SCH_1):PAGE426_I1@PURE_QUANTA.PT5161LRS(CHIPS)':
 'B_PERN3': CDS_PINID='B_PERN3';
NET_NAME
'P5E_CPU0_P3_TX_C_DP<13>'
 '@T6G_MB_LIB.T6G(SCH_1):P5E_CPU0_P3_TX_C_DP'<13>:
 C_SIGNAL='@t6g_mb_lib.t6g(sch_1):p5e_cpu0_p3_tx_c_dp(13)';
NODE_NAME     C875 1
 '@T6G_MB_LIB.T6G(SCH_1):PAGE352_I164@PURE_QUANTA.Q_CAP_DIFFBUS(CHIPS)':
 '1': CDS_PINID='\1\';
NODE_NAME     U6013 AJ35
 '@T6G_MB_LIB.T6G(SCH_1):PAGE426_I1@PURE_QUANTA.PT5161LRS(CHIPS)':
 'B_PERN2': CDS_PINID='B_PERN2';
NET_NAME
'P5E_CPU0_P3_TX_C_DP<14>'
 '@T6G_MB_LIB.T6G(SCH_1):P5E_CPU0_P3_TX_C_DP'<14>:
 C_SIGNAL='@t6g_mb_lib.t6g(sch_1):p5e_cpu0_p3_tx_c_dp(14)';
NODE_NAME     C873 1
 '@T6G_MB_LIB.T6G(SCH_1):PAGE352_I166@PURE_QUANTA.Q_CAP_DIFFBUS(CHIPS)':
 '1': CDS_PINID='\1\';
NODE_NAME     U6013 Y34
 '@T6G_MB_LIB.T6G(SCH_1):PAGE426_I1@PURE_QUANTA.PT5161LRS(CHIPS)':
 'B_PERP1': CDS_PINID='B_PERP1';
NET_NAME
'P5E_CPU0_P3_TX_C_DP<15>'
 '@T6G_MB_LIB.T6G(SCH_1):P5E_CPU0_P3_TX_C_DP'<15>:
 C_SIGNAL='@t6g_mb_lib.t6g(sch_1):p5e_cpu0_p3_tx_c_dp(15)';
NODE_NAME     C871 1
 '@T6G_MB_LIB.T6G(SCH_1):PAGE352_I168@PURE_QUANTA.Q_CAP_DIFFBUS(CHIPS)':
 '1': CDS_PINID='\1\';
NODE_NAME     U6013 R35
 '@T6G_MB_LIB.T6G(SCH_1):PAGE426_I1@PURE_QUANTA.PT5161LRS(CHIPS)':
 'B_PERN0': CDS_PINID='B_PERN0';
NET_NAME
'P5E_CPU0_P3_TX_C_DP<1>'
 '@T6G_MB_LIB.T6G(SCH_1):P5E_CPU0_P3_TX_C_DP'<1>:
 C_SIGNAL='@t6g_mb_lib.t6g(sch_1):p5e_cpu0_p3_tx_c_dp(1)';
NODE_NAME     C899 1
 '@T6G_MB_LIB.T6G(SCH_1):PAGE352_I122@PURE_QUANTA.Q_CAP_DIFFBUS(CHIPS)':
 '1': CDS_PINID='\1\';
NODE_NAME     U6013 EL34
 '@T6G_MB_LIB.T6G(SCH_1):PAGE426_I38@PURE_QUANTA.PT5161LRS(CHIPS)':
 'B_PERP14': CDS_PINID='B_PERP14';
NET_NAME
'P5E_CPU0_P3_TX_C_DP<2>'
 '@T6G_MB_LIB.T6G(SCH_1):P5E_CPU0_P3_TX_C_DP'<2>:
 C_SIGNAL='@t6g_mb_lib.t6g(sch_1):p5e_cpu0_p3_tx_c_dp(2)';
NODE_NAME     C897 1
 '@T6G_MB_LIB.T6G(SCH_1):PAGE352_I123@PURE_QUANTA.Q_CAP_DIFFBUS(CHIPS)':
 '1': CDS_PINID='\1\';
NODE_NAME     U6013 EF35
 '@T6G_MB_LIB.T6G(SCH_1):PAGE426_I38@PURE_QUANTA.PT5161LRS(CHIPS)':
 'B_PERN13': CDS_PINID='B_PERN13';
NET_NAME
'P5E_CPU0_P3_TX_C_DP<3>'
 '@T6G_MB_LIB.T6G(SCH_1):P5E_CPU0_P3_TX_C_DP'<3>:
 C_SIGNAL='@t6g_mb_lib.t6g(sch_1):p5e_cpu0_p3_tx_c_dp(3)';
NODE_NAME     C895 1
 '@T6G_MB_LIB.T6G(SCH_1):PAGE352_I125@PURE_QUANTA.Q_CAP_DIFFBUS(CHIPS)':
 '1': CDS_PINID='\1\';
NODE_NAME     U6013 DW35
 '@T6G_MB_LIB.T6G(SCH_1):PAGE426_I38@PURE_QUANTA.PT5161LRS(CHIPS)':
 'B_PERN12': CDS_PINID='B_PERN12';
NET_NAME
'P5E_CPU0_P3_TX_C_DP<4>'
 '@T6G_MB_LIB.T6G(SCH_1):P5E_CPU0_P3_TX_C_DP'<4>:
 C_SIGNAL='@t6g_mb_lib.t6g(sch_1):p5e_cpu0_p3_tx_c_dp(4)';
NODE_NAME     C893 1
 '@T6G_MB_LIB.T6G(SCH_1):PAGE352_I128@PURE_QUANTA.Q_CAP_DIFFBUS(CHIPS)':
 '1': CDS_PINID='\1\';
NODE_NAME     U6013 DM35
 '@T6G_MB_LIB.T6G(SCH_1):PAGE426_I38@PURE_QUANTA.PT5161LRS(CHIPS)':
 'B_PERN11': CDS_PINID='B_PERN11';
NET_NAME
'P5E_CPU0_P3_TX_C_DP<5>'
 '@T6G_MB_LIB.T6G(SCH_1):P5E_CPU0_P3_TX_C_DP'<5>:
 C_SIGNAL='@t6g_mb_lib.t6g(sch_1):p5e_cpu0_p3_tx_c_dp(5)';
NODE_NAME     C891 1
 '@T6G_MB_LIB.T6G(SCH_1):PAGE352_I132@PURE_QUANTA.Q_CAP_DIFFBUS(CHIPS)':
 '1': CDS_PINID='\1\';
NODE_NAME     U6013 DE35
 '@T6G_MB_LIB.T6G(SCH_1):PAGE426_I38@PURE_QUANTA.PT5161LRS(CHIPS)':
 'B_PERN10': CDS_PINID='B_PERN10';
NET_NAME
'P5E_CPU0_P3_TX_C_DP<6>'
 '@T6G_MB_LIB.T6G(SCH_1):P5E_CPU0_P3_TX_C_DP'<6>:
 C_SIGNAL='@t6g_mb_lib.t6g(sch_1):p5e_cpu0_p3_tx_c_dp(6)';
NODE_NAME     C889 1
 '@T6G_MB_LIB.T6G(SCH_1):PAGE352_I134@PURE_QUANTA.Q_CAP_DIFFBUS(CHIPS)':
 '1': CDS_PINID='\1\';
NODE_NAME     U6013 CV35
 '@T6G_MB_LIB.T6G(SCH_1):PAGE426_I38@PURE_QUANTA.PT5161LRS(CHIPS)':
 'B_PERN9': CDS_PINID='B_PERN9';
NET_NAME
'P5E_CPU0_P3_TX_C_DP<7>'
 '@T6G_MB_LIB.T6G(SCH_1):P5E_CPU0_P3_TX_C_DP'<7>:
 C_SIGNAL='@t6g_mb_lib.t6g(sch_1):p5e_cpu0_p3_tx_c_dp(7)';
NODE_NAME     C887 1
 '@T6G_MB_LIB.T6G(SCH_1):PAGE352_I136@PURE_QUANTA.Q_CAP_DIFFBUS(CHIPS)':
 '1': CDS_PINID='\1\';
NODE_NAME     U6013 CL35
 '@T6G_MB_LIB.T6G(SCH_1):PAGE426_I38@PURE_QUANTA.PT5161LRS(CHIPS)':
 'B_PERN8': CDS_PINID='B_PERN8';
NET_NAME
'P5E_CPU0_P3_TX_C_DP<8>'
 '@T6G_MB_LIB.T6G(SCH_1):P5E_CPU0_P3_TX_C_DP'<8>:
 C_SIGNAL='@t6g_mb_lib.t6g(sch_1):p5e_cpu0_p3_tx_c_dp(8)';
NODE_NAME     C885 1
 '@T6G_MB_LIB.T6G(SCH_1):PAGE352_I152@PURE_QUANTA.Q_CAP_DIFFBUS(CHIPS)':
 '1': CDS_PINID='\1\';
NODE_NAME     U6013 CD35
 '@T6G_MB_LIB.T6G(SCH_1):PAGE426_I1@PURE_QUANTA.PT5161LRS(CHIPS)':
 'B_PERN7': CDS_PINID='B_PERN7';
NET_NAME
'P5E_CPU0_P3_TX_C_DP<9>'
 '@T6G_MB_LIB.T6G(SCH_1):P5E_CPU0_P3_TX_C_DP'<9>:
 C_SIGNAL='@t6g_mb_lib.t6g(sch_1):p5e_cpu0_p3_tx_c_dp(9)';
NODE_NAME     C883 1
 '@T6G_MB_LIB.T6G(SCH_1):PAGE352_I153@PURE_QUANTA.Q_CAP_DIFFBUS(CHIPS)':
 '1': CDS_PINID='\1\';
NODE_NAME     U6013 BU35
 '@T6G_MB_LIB.T6G(SCH_1):PAGE426_I1@PURE_QUANTA.PT5161LRS(CHIPS)':
 'B_PERN6': CDS_PINID='B_PERN6';
NET_NAME
'P5E_CPU0_P3_TX_DN<0>'
 '@T6G_MB_LIB.T6G(SCH_1):P5E_CPU0_P3_TX_DN'<0>:
 C_SIGNAL='@t6g_mb_lib.t6g(sch_1):p5e_cpu0_p3_tx_dn(0)';
NODE_NAME     U25 CD35
 '@T6G_MB_LIB.T6G(SCH_1):PAGE25_I148@PURE_QUANTA.GENOA_SP5(CHIPS)':
 'P3_TXN0': CDS_PINID='P3_TXN0';
NODE_NAME     C900 2
 '@T6G_MB_LIB.T6G(SCH_1):PAGE352_I121@PURE_QUANTA.Q_CAP_DIFFBUS(CHIPS)':
 '2': CDS_PINID='\2\';
NET_NAME
'P5E_CPU0_P3_TX_DN<10>'
 '@T6G_MB_LIB.T6G(SCH_1):P5E_CPU0_P3_TX_DN'<10>:
 C_SIGNAL='@t6g_mb_lib.t6g(sch_1):p5e_cpu0_p3_tx_dn(10)';
NODE_NAME     U25 CC26
 '@T6G_MB_LIB.T6G(SCH_1):PAGE25_I148@PURE_QUANTA.GENOA_SP5(CHIPS)':
 'P3_TXN10': CDS_PINID='P3_TXN10';
NODE_NAME     C880 2
 '@T6G_MB_LIB.T6G(SCH_1):PAGE352_I156@PURE_QUANTA.Q_CAP_DIFFBUS(CHIPS)':
 '2': CDS_PINID='\2\';
NET_NAME
'P5E_CPU0_P3_TX_DN<11>'
 '@T6G_MB_LIB.T6G(SCH_1):P5E_CPU0_P3_TX_DN'<11>:
 C_SIGNAL='@t6g_mb_lib.t6g(sch_1):p5e_cpu0_p3_tx_dn(11)';
NODE_NAME     U25 CG26
 '@T6G_MB_LIB.T6G(SCH_1):PAGE25_I148@PURE_QUANTA.GENOA_SP5(CHIPS)':
 'P3_TXN11': CDS_PINID='P3_TXN11';
NODE_NAME     C878 2
 '@T6G_MB_LIB.T6G(SCH_1):PAGE352_I157@PURE_QUANTA.Q_CAP_DIFFBUS(CHIPS)':
 '2': CDS_PINID='\2\';
NET_NAME
'P5E_CPU0_P3_TX_DN<12>'
 '@T6G_MB_LIB.T6G(SCH_1):P5E_CPU0_P3_TX_DN'<12>:
 C_SIGNAL='@t6g_mb_lib.t6g(sch_1):p5e_cpu0_p3_tx_dn(12)';
NODE_NAME     U25 CE26
 '@T6G_MB_LIB.T6G(SCH_1):PAGE25_I148@PURE_QUANTA.GENOA_SP5(CHIPS)':
 'P3_TXN12': CDS_PINID='P3_TXN12';
NODE_NAME     C876 2
 '@T6G_MB_LIB.T6G(SCH_1):PAGE352_I160@PURE_QUANTA.Q_CAP_DIFFBUS(CHIPS)':
 '2': CDS_PINID='\2\';
NET_NAME
'P5E_CPU0_P3_TX_DN<13>'
 '@T6G_MB_LIB.T6G(SCH_1):P5E_CPU0_P3_TX_DN'<13>:
 C_SIGNAL='@t6g_mb_lib.t6g(sch_1):p5e_cpu0_p3_tx_dn(13)';
NODE_NAME     U25 CC23
 '@T6G_MB_LIB.T6G(SCH_1):PAGE25_I148@PURE_QUANTA.GENOA_SP5(CHIPS)':
 'P3_TXN13': CDS_PINID='P3_TXN13';
NODE_NAME     C874 2
 '@T6G_MB_LIB.T6G(SCH_1):PAGE352_I165@PURE_QUANTA.Q_CAP_DIFFBUS(CHIPS)':
 '2': CDS_PINID='\2\';
NET_NAME
'P5E_CPU0_P3_TX_DN<14>'
 '@T6G_MB_LIB.T6G(SCH_1):P5E_CPU0_P3_TX_DN'<14>:
 C_SIGNAL='@t6g_mb_lib.t6g(sch_1):p5e_cpu0_p3_tx_dn(14)';
NODE_NAME     U25 CG23
 '@T6G_MB_LIB.T6G(SCH_1):PAGE25_I148@PURE_QUANTA.GENOA_SP5(CHIPS)':
 'P3_TXN14': CDS_PINID='P3_TXN14';
NODE_NAME     C872 2
 '@T6G_MB_LIB.T6G(SCH_1):PAGE352_I167@PURE_QUANTA.Q_CAP_DIFFBUS(CHIPS)':
 '2': CDS_PINID='\2\';
NET_NAME
'P5E_CPU0_P3_TX_DN<15>'
 '@T6G_MB_LIB.T6G(SCH_1):P5E_CPU0_P3_TX_DN'<15>:
 C_SIGNAL='@t6g_mb_lib.t6g(sch_1):p5e_cpu0_p3_tx_dn(15)';
NODE_NAME     U25 CE23
 '@T6G_MB_LIB.T6G(SCH_1):PAGE25_I148@PURE_QUANTA.GENOA_SP5(CHIPS)':
 'P3_TXN15': CDS_PINID='P3_TXN15';
NODE_NAME     C870 2
 '@T6G_MB_LIB.T6G(SCH_1):PAGE352_I169@PURE_QUANTA.Q_CAP_DIFFBUS(CHIPS)':
 '2': CDS_PINID='\2\';
NET_NAME
'P5E_CPU0_P3_TX_DN<1>'
 '@T6G_MB_LIB.T6G(SCH_1):P5E_CPU0_P3_TX_DN'<1>:
 C_SIGNAL='@t6g_mb_lib.t6g(sch_1):p5e_cpu0_p3_tx_dn(1)';
NODE_NAME     U25 CF35
 '@T6G_MB_LIB.T6G(SCH_1):PAGE25_I148@PURE_QUANTA.GENOA_SP5(CHIPS)':
 'P3_TXN1': CDS_PINID='P3_TXN1';
NODE_NAME     C898 2
 '@T6G_MB_LIB.T6G(SCH_1):PAGE352_I206@PURE_QUANTA.Q_CAP_DIFFBUS(CHIPS)':
 '2': CDS_PINID='\2\';
NET_NAME
'P5E_CPU0_P3_TX_DN<2>'
 '@T6G_MB_LIB.T6G(SCH_1):P5E_CPU0_P3_TX_DN'<2>:
 C_SIGNAL='@t6g_mb_lib.t6g(sch_1):p5e_cpu0_p3_tx_dn(2)';
NODE_NAME     U25 CH35
 '@T6G_MB_LIB.T6G(SCH_1):PAGE25_I148@PURE_QUANTA.GENOA_SP5(CHIPS)':
 'P3_TXN2': CDS_PINID='P3_TXN2';
NODE_NAME     C896 2
 '@T6G_MB_LIB.T6G(SCH_1):PAGE352_I124@PURE_QUANTA.Q_CAP_DIFFBUS(CHIPS)':
 '2': CDS_PINID='\2\';
NET_NAME
'P5E_CPU0_P3_TX_DN<3>'
 '@T6G_MB_LIB.T6G(SCH_1):P5E_CPU0_P3_TX_DN'<3>:
 C_SIGNAL='@t6g_mb_lib.t6g(sch_1):p5e_cpu0_p3_tx_dn(3)';
NODE_NAME     U25 CC32
 '@T6G_MB_LIB.T6G(SCH_1):PAGE25_I148@PURE_QUANTA.GENOA_SP5(CHIPS)':
 'P3_TXN3': CDS_PINID='P3_TXN3';
NODE_NAME     C894 2
 '@T6G_MB_LIB.T6G(SCH_1):PAGE352_I126@PURE_QUANTA.Q_CAP_DIFFBUS(CHIPS)':
 '2': CDS_PINID='\2\';
NET_NAME
'P5E_CPU0_P3_TX_DN<4>'
 '@T6G_MB_LIB.T6G(SCH_1):P5E_CPU0_P3_TX_DN'<4>:
 C_SIGNAL='@t6g_mb_lib.t6g(sch_1):p5e_cpu0_p3_tx_dn(4)';
NODE_NAME     U25 CJ32
 '@T6G_MB_LIB.T6G(SCH_1):PAGE25_I148@PURE_QUANTA.GENOA_SP5(CHIPS)':
 'P3_TXN4': CDS_PINID='P3_TXN4';
NODE_NAME     C892 2
 '@T6G_MB_LIB.T6G(SCH_1):PAGE352_I127@PURE_QUANTA.Q_CAP_DIFFBUS(CHIPS)':
 '2': CDS_PINID='\2\';
NET_NAME
'P5E_CPU0_P3_TX_DN<5>'
 '@T6G_MB_LIB.T6G(SCH_1):P5E_CPU0_P3_TX_DN'<5>:
 C_SIGNAL='@t6g_mb_lib.t6g(sch_1):p5e_cpu0_p3_tx_dn(5)';
NODE_NAME     U25 CG32
 '@T6G_MB_LIB.T6G(SCH_1):PAGE25_I148@PURE_QUANTA.GENOA_SP5(CHIPS)':
 'P3_TXN5': CDS_PINID='P3_TXN5';
NODE_NAME     C890 2
 '@T6G_MB_LIB.T6G(SCH_1):PAGE352_I133@PURE_QUANTA.Q_CAP_DIFFBUS(CHIPS)':
 '2': CDS_PINID='\2\';
NET_NAME
'P5E_CPU0_P3_TX_DN<6>'
 '@T6G_MB_LIB.T6G(SCH_1):P5E_CPU0_P3_TX_DN'<6>:
 C_SIGNAL='@t6g_mb_lib.t6g(sch_1):p5e_cpu0_p3_tx_dn(6)';
NODE_NAME     U25 CE32
 '@T6G_MB_LIB.T6G(SCH_1):PAGE25_I148@PURE_QUANTA.GENOA_SP5(CHIPS)':
 'P3_TXN6': CDS_PINID='P3_TXN6';
NODE_NAME     C888 2
 '@T6G_MB_LIB.T6G(SCH_1):PAGE352_I135@PURE_QUANTA.Q_CAP_DIFFBUS(CHIPS)':
 '2': CDS_PINID='\2\';
NET_NAME
'P5E_CPU0_P3_TX_DN<7>'
 '@T6G_MB_LIB.T6G(SCH_1):P5E_CPU0_P3_TX_DN'<7>:
 C_SIGNAL='@t6g_mb_lib.t6g(sch_1):p5e_cpu0_p3_tx_dn(7)';
NODE_NAME     U25 CC29
 '@T6G_MB_LIB.T6G(SCH_1):PAGE25_I148@PURE_QUANTA.GENOA_SP5(CHIPS)':
 'P3_TXN7': CDS_PINID='P3_TXN7';
NODE_NAME     C886 2
 '@T6G_MB_LIB.T6G(SCH_1):PAGE352_I137@PURE_QUANTA.Q_CAP_DIFFBUS(CHIPS)':
 '2': CDS_PINID='\2\';
NET_NAME
'P5E_CPU0_P3_TX_DN<8>'
 '@T6G_MB_LIB.T6G(SCH_1):P5E_CPU0_P3_TX_DN'<8>:
 C_SIGNAL='@t6g_mb_lib.t6g(sch_1):p5e_cpu0_p3_tx_dn(8)';
NODE_NAME     U25 CG29
 '@T6G_MB_LIB.T6G(SCH_1):PAGE25_I148@PURE_QUANTA.GENOA_SP5(CHIPS)':
 'P3_TXN8': CDS_PINID='P3_TXN8';
NODE_NAME     C884 2
 '@T6G_MB_LIB.T6G(SCH_1):PAGE352_I151@PURE_QUANTA.Q_CAP_DIFFBUS(CHIPS)':
 '2': CDS_PINID='\2\';
NET_NAME
'P5E_CPU0_P3_TX_DN<9>'
 '@T6G_MB_LIB.T6G(SCH_1):P5E_CPU0_P3_TX_DN'<9>:
 C_SIGNAL='@t6g_mb_lib.t6g(sch_1):p5e_cpu0_p3_tx_dn(9)';
NODE_NAME     U25 CE29
 '@T6G_MB_LIB.T6G(SCH_1):PAGE25_I148@PURE_QUANTA.GENOA_SP5(CHIPS)':
 'P3_TXN9': CDS_PINID='P3_TXN9';
NODE_NAME     C882 2
 '@T6G_MB_LIB.T6G(SCH_1):PAGE352_I154@PURE_QUANTA.Q_CAP_DIFFBUS(CHIPS)':
 '2': CDS_PINID='\2\';
NET_NAME
'P5E_CPU0_P3_TX_DP<0>'
 '@T6G_MB_LIB.T6G(SCH_1):P5E_CPU0_P3_TX_DP'<0>:
 C_SIGNAL='@t6g_mb_lib.t6g(sch_1):p5e_cpu0_p3_tx_dp(0)';
NODE_NAME     U25 CD36
 '@T6G_MB_LIB.T6G(SCH_1):PAGE25_I148@PURE_QUANTA.GENOA_SP5(CHIPS)':
 'P3_TXP0': CDS_PINID='P3_TXP0';
NODE_NAME     C901 2
 '@T6G_MB_LIB.T6G(SCH_1):PAGE352_I120@PURE_QUANTA.Q_CAP_DIFFBUS(CHIPS)':
 '2': CDS_PINID='\2\';
NET_NAME
'P5E_CPU0_P3_TX_DP<10>'
 '@T6G_MB_LIB.T6G(SCH_1):P5E_CPU0_P3_TX_DP'<10>:
 C_SIGNAL='@t6g_mb_lib.t6g(sch_1):p5e_cpu0_p3_tx_dp(10)';
NODE_NAME     U25 CC27
 '@T6G_MB_LIB.T6G(SCH_1):PAGE25_I148@PURE_QUANTA.GENOA_SP5(CHIPS)':
 'P3_TXP10': CDS_PINID='P3_TXP10';
NODE_NAME     C881 2
 '@T6G_MB_LIB.T6G(SCH_1):PAGE352_I155@PURE_QUANTA.Q_CAP_DIFFBUS(CHIPS)':
 '2': CDS_PINID='\2\';
NET_NAME
'P5E_CPU0_P3_TX_DP<11>'
 '@T6G_MB_LIB.T6G(SCH_1):P5E_CPU0_P3_TX_DP'<11>:
 C_SIGNAL='@t6g_mb_lib.t6g(sch_1):p5e_cpu0_p3_tx_dp(11)';
NODE_NAME     U25 CG27
 '@T6G_MB_LIB.T6G(SCH_1):PAGE25_I148@PURE_QUANTA.GENOA_SP5(CHIPS)':
 'P3_TXP11': CDS_PINID='P3_TXP11';
NODE_NAME     C879 2
 '@T6G_MB_LIB.T6G(SCH_1):PAGE352_I158@PURE_QUANTA.Q_CAP_DIFFBUS(CHIPS)':
 '2': CDS_PINID='\2\';
NET_NAME
'P5E_CPU0_P3_TX_DP<12>'
 '@T6G_MB_LIB.T6G(SCH_1):P5E_CPU0_P3_TX_DP'<12>:
 C_SIGNAL='@t6g_mb_lib.t6g(sch_1):p5e_cpu0_p3_tx_dp(12)';
NODE_NAME     U25 CE27
 '@T6G_MB_LIB.T6G(SCH_1):PAGE25_I148@PURE_QUANTA.GENOA_SP5(CHIPS)':
 'P3_TXP12': CDS_PINID='P3_TXP12';
NODE_NAME     C877 2
 '@T6G_MB_LIB.T6G(SCH_1):PAGE352_I159@PURE_QUANTA.Q_CAP_DIFFBUS(CHIPS)':
 '2': CDS_PINID='\2\';
NET_NAME
'P5E_CPU0_P3_TX_DP<13>'
 '@T6G_MB_LIB.T6G(SCH_1):P5E_CPU0_P3_TX_DP'<13>:
 C_SIGNAL='@t6g_mb_lib.t6g(sch_1):p5e_cpu0_p3_tx_dp(13)';
NODE_NAME     U25 CC24
 '@T6G_MB_LIB.T6G(SCH_1):PAGE25_I148@PURE_QUANTA.GENOA_SP5(CHIPS)':
 'P3_TXP13': CDS_PINID='P3_TXP13';
NODE_NAME     C875 2
 '@T6G_MB_LIB.T6G(SCH_1):PAGE352_I164@PURE_QUANTA.Q_CAP_DIFFBUS(CHIPS)':
 '2': CDS_PINID='\2\';
NET_NAME
'P5E_CPU0_P3_TX_DP<14>'
 '@T6G_MB_LIB.T6G(SCH_1):P5E_CPU0_P3_TX_DP'<14>:
 C_SIGNAL='@t6g_mb_lib.t6g(sch_1):p5e_cpu0_p3_tx_dp(14)';
NODE_NAME     U25 CG24
 '@T6G_MB_LIB.T6G(SCH_1):PAGE25_I148@PURE_QUANTA.GENOA_SP5(CHIPS)':
 'P3_TXP14': CDS_PINID='P3_TXP14';
NODE_NAME     C873 2
 '@T6G_MB_LIB.T6G(SCH_1):PAGE352_I166@PURE_QUANTA.Q_CAP_DIFFBUS(CHIPS)':
 '2': CDS_PINID='\2\';
NET_NAME
'P5E_CPU0_P3_TX_DP<15>'
 '@T6G_MB_LIB.T6G(SCH_1):P5E_CPU0_P3_TX_DP'<15>:
 C_SIGNAL='@t6g_mb_lib.t6g(sch_1):p5e_cpu0_p3_tx_dp(15)';
NODE_NAME     U25 CE24
 '@T6G_MB_LIB.T6G(SCH_1):PAGE25_I148@PURE_QUANTA.GENOA_SP5(CHIPS)':
 'P3_TXP15': CDS_PINID='P3_TXP15';
NODE_NAME     C871 2
 '@T6G_MB_LIB.T6G(SCH_1):PAGE352_I168@PURE_QUANTA.Q_CAP_DIFFBUS(CHIPS)':
 '2': CDS_PINID='\2\';
NET_NAME
'P5E_CPU0_P3_TX_DP<1>'
 '@T6G_MB_LIB.T6G(SCH_1):P5E_CPU0_P3_TX_DP'<1>:
 C_SIGNAL='@t6g_mb_lib.t6g(sch_1):p5e_cpu0_p3_tx_dp(1)';
NODE_NAME     U25 CF36
 '@T6G_MB_LIB.T6G(SCH_1):PAGE25_I148@PURE_QUANTA.GENOA_SP5(CHIPS)':
 'P3_TXP1': CDS_PINID='P3_TXP1';
NODE_NAME     C899 2
 '@T6G_MB_LIB.T6G(SCH_1):PAGE352_I122@PURE_QUANTA.Q_CAP_DIFFBUS(CHIPS)':
 '2': CDS_PINID='\2\';
NET_NAME
'P5E_CPU0_P3_TX_DP<2>'
 '@T6G_MB_LIB.T6G(SCH_1):P5E_CPU0_P3_TX_DP'<2>:
 C_SIGNAL='@t6g_mb_lib.t6g(sch_1):p5e_cpu0_p3_tx_dp(2)';
NODE_NAME     U25 CH36
 '@T6G_MB_LIB.T6G(SCH_1):PAGE25_I148@PURE_QUANTA.GENOA_SP5(CHIPS)':
 'P3_TXP2': CDS_PINID='P3_TXP2';
NODE_NAME     C897 2
 '@T6G_MB_LIB.T6G(SCH_1):PAGE352_I123@PURE_QUANTA.Q_CAP_DIFFBUS(CHIPS)':
 '2': CDS_PINID='\2\';
NET_NAME
'P5E_CPU0_P3_TX_DP<3>'
 '@T6G_MB_LIB.T6G(SCH_1):P5E_CPU0_P3_TX_DP'<3>:
 C_SIGNAL='@t6g_mb_lib.t6g(sch_1):p5e_cpu0_p3_tx_dp(3)';
NODE_NAME     U25 CC33
 '@T6G_MB_LIB.T6G(SCH_1):PAGE25_I148@PURE_QUANTA.GENOA_SP5(CHIPS)':
 'P3_TXP3': CDS_PINID='P3_TXP3';
NODE_NAME     C895 2
 '@T6G_MB_LIB.T6G(SCH_1):PAGE352_I125@PURE_QUANTA.Q_CAP_DIFFBUS(CHIPS)':
 '2': CDS_PINID='\2\';
NET_NAME
'P5E_CPU0_P3_TX_DP<4>'
 '@T6G_MB_LIB.T6G(SCH_1):P5E_CPU0_P3_TX_DP'<4>:
 C_SIGNAL='@t6g_mb_lib.t6g(sch_1):p5e_cpu0_p3_tx_dp(4)';
NODE_NAME     U25 CJ33
 '@T6G_MB_LIB.T6G(SCH_1):PAGE25_I148@PURE_QUANTA.GENOA_SP5(CHIPS)':
 'P3_TXP4': CDS_PINID='P3_TXP4';
NODE_NAME     C893 2
 '@T6G_MB_LIB.T6G(SCH_1):PAGE352_I128@PURE_QUANTA.Q_CAP_DIFFBUS(CHIPS)':
 '2': CDS_PINID='\2\';
NET_NAME
'P5E_CPU0_P3_TX_DP<5>'
 '@T6G_MB_LIB.T6G(SCH_1):P5E_CPU0_P3_TX_DP'<5>:
 C_SIGNAL='@t6g_mb_lib.t6g(sch_1):p5e_cpu0_p3_tx_dp(5)';
NODE_NAME     U25 CG33
 '@T6G_MB_LIB.T6G(SCH_1):PAGE25_I148@PURE_QUANTA.GENOA_SP5(CHIPS)':
 'P3_TXP5': CDS_PINID='P3_TXP5';
NODE_NAME     C891 2
 '@T6G_MB_LIB.T6G(SCH_1):PAGE352_I132@PURE_QUANTA.Q_CAP_DIFFBUS(CHIPS)':
 '2': CDS_PINID='\2\';
NET_NAME
'P5E_CPU0_P3_TX_DP<6>'
 '@T6G_MB_LIB.T6G(SCH_1):P5E_CPU0_P3_TX_DP'<6>:
 C_SIGNAL='@t6g_mb_lib.t6g(sch_1):p5e_cpu0_p3_tx_dp(6)';
NODE_NAME     U25 CE33
 '@T6G_MB_LIB.T6G(SCH_1):PAGE25_I148@PURE_QUANTA.GENOA_SP5(CHIPS)':
 'P3_TXP6': CDS_PINID='P3_TXP6';
NODE_NAME     C889 2
 '@T6G_MB_LIB.T6G(SCH_1):PAGE352_I134@PURE_QUANTA.Q_CAP_DIFFBUS(CHIPS)':
 '2': CDS_PINID='\2\';
NET_NAME
'P5E_CPU0_P3_TX_DP<7>'
 '@T6G_MB_LIB.T6G(SCH_1):P5E_CPU0_P3_TX_DP'<7>:
 C_SIGNAL='@t6g_mb_lib.t6g(sch_1):p5e_cpu0_p3_tx_dp(7)';
NODE_NAME     U25 CC30
 '@T6G_MB_LIB.T6G(SCH_1):PAGE25_I148@PURE_QUANTA.GENOA_SP5(CHIPS)':
 'P3_TXP7': CDS_PINID='P3_TXP7';
NODE_NAME     C887 2
 '@T6G_MB_LIB.T6G(SCH_1):PAGE352_I136@PURE_QUANTA.Q_CAP_DIFFBUS(CHIPS)':
 '2': CDS_PINID='\2\';
NET_NAME
'P5E_CPU0_P3_TX_DP<8>'
 '@T6G_MB_LIB.T6G(SCH_1):P5E_CPU0_P3_TX_DP'<8>:
 C_SIGNAL='@t6g_mb_lib.t6g(sch_1):p5e_cpu0_p3_tx_dp(8)';
NODE_NAME     U25 CG30
 '@T6G_MB_LIB.T6G(SCH_1):PAGE25_I148@PURE_QUANTA.GENOA_SP5(CHIPS)':
 'P3_TXP8': CDS_PINID='P3_TXP8';
NODE_NAME     C885 2
 '@T6G_MB_LIB.T6G(SCH_1):PAGE352_I152@PURE_QUANTA.Q_CAP_DIFFBUS(CHIPS)':
 '2': CDS_PINID='\2\';
NET_NAME
'P5E_CPU0_P3_TX_DP<9>'
 '@T6G_MB_LIB.T6G(SCH_1):P5E_CPU0_P3_TX_DP'<9>:
 C_SIGNAL='@t6g_mb_lib.t6g(sch_1):p5e_cpu0_p3_tx_dp(9)';
NODE_NAME     U25 CE30
 '@T6G_MB_LIB.T6G(SCH_1):PAGE25_I148@PURE_QUANTA.GENOA_SP5(CHIPS)':
 'P3_TXP9': CDS_PINID='P3_TXP9';
NODE_NAME     C883 2
 '@T6G_MB_LIB.T6G(SCH_1):PAGE352_I153@PURE_QUANTA.Q_CAP_DIFFBUS(CHIPS)':
 '2': CDS_PINID='\2\';
NET_NAME
'P5E_CPU1_G1_RX_DN<0>'
 '@T6G_MB_LIB.T6G(SCH_1):P5E_CPU1_G1_RX_DN'<0>:
 C_SIGNAL='@t6g_mb_lib.t6g(sch_1):p5e_cpu1_g1_rx_dn(0)';
NODE_NAME     U26 V40
 '@T6G_MB_LIB.T6G(SCH_1):PAGE49_I214@PURE_QUANTA.GENOA_SP5(CHIPS)':
 'G1_RXN0': CDS_PINID='G1_RXN0';
NODE_NAME     J35 A17
 '@T6G_MB_LIB.T6G(SCH_1):PAGE341_I168@PURE_QUANTA.SCONN168_ME1016810202011(CHIPS)':
 'PERN0': CDS_PINID='PERN0';
NET_NAME
'P5E_CPU1_G1_RX_DN<10>'
 '@T6G_MB_LIB.T6G(SCH_1):P5E_CPU1_G1_RX_DN'<10>:
 C_SIGNAL='@t6g_mb_lib.t6g(sch_1):p5e_cpu1_g1_rx_dn(10)';
NODE_NAME     U26 N49
 '@T6G_MB_LIB.T6G(SCH_1):PAGE49_I214@PURE_QUANTA.GENOA_SP5(CHIPS)':
 'G1_RXN10': CDS_PINID='G1_RXN10';
NODE_NAME     J35 A50
 '@T6G_MB_LIB.T6G(SCH_1):PAGE341_I168@PURE_QUANTA.SCONN168_ME1016810202011(CHIPS)':
 'PERN10': CDS_PINID='PERN10';
NET_NAME
'P5E_CPU1_G1_RX_DN<11>'
 '@T6G_MB_LIB.T6G(SCH_1):P5E_CPU1_G1_RX_DN'<11>:
 C_SIGNAL='@t6g_mb_lib.t6g(sch_1):p5e_cpu1_g1_rx_dn(11)';
NODE_NAME     U26 R49
 '@T6G_MB_LIB.T6G(SCH_1):PAGE49_I214@PURE_QUANTA.GENOA_SP5(CHIPS)':
 'G1_RXN11': CDS_PINID='G1_RXN11';
NODE_NAME     J35 A53
 '@T6G_MB_LIB.T6G(SCH_1):PAGE341_I168@PURE_QUANTA.SCONN168_ME1016810202011(CHIPS)':
 'PERN11': CDS_PINID='PERN11';
NET_NAME
'P5E_CPU1_G1_RX_DN<12>'
 '@T6G_MB_LIB.T6G(SCH_1):P5E_CPU1_G1_RX_DN'<12>:
 C_SIGNAL='@t6g_mb_lib.t6g(sch_1):p5e_cpu1_g1_rx_dn(12)';
NODE_NAME     U26 U49
 '@T6G_MB_LIB.T6G(SCH_1):PAGE49_I214@PURE_QUANTA.GENOA_SP5(CHIPS)':
 'G1_RXN12': CDS_PINID='G1_RXN12';
NODE_NAME     J35 A56
 '@T6G_MB_LIB.T6G(SCH_1):PAGE341_I168@PURE_QUANTA.SCONN168_ME1016810202011(CHIPS)':
 'PERN12': CDS_PINID='PERN12';
NET_NAME
'P5E_CPU1_G1_RX_DN<13>'
 '@T6G_MB_LIB.T6G(SCH_1):P5E_CPU1_G1_RX_DN'<13>:
 C_SIGNAL='@t6g_mb_lib.t6g(sch_1):p5e_cpu1_g1_rx_dn(13)';
NODE_NAME     U26 W52
 '@T6G_MB_LIB.T6G(SCH_1):PAGE49_I214@PURE_QUANTA.GENOA_SP5(CHIPS)':
 'G1_RXN13': CDS_PINID='G1_RXN13';
NODE_NAME     J35 A59
 '@T6G_MB_LIB.T6G(SCH_1):PAGE341_I168@PURE_QUANTA.SCONN168_ME1016810202011(CHIPS)':
 'PERN13': CDS_PINID='PERN13';
NET_NAME
'P5E_CPU1_G1_RX_DN<14>'
 '@T6G_MB_LIB.T6G(SCH_1):P5E_CPU1_G1_RX_DN'<14>:
 C_SIGNAL='@t6g_mb_lib.t6g(sch_1):p5e_cpu1_g1_rx_dn(14)';
NODE_NAME     U26 R52
 '@T6G_MB_LIB.T6G(SCH_1):PAGE49_I214@PURE_QUANTA.GENOA_SP5(CHIPS)':
 'G1_RXN14': CDS_PINID='G1_RXN14';
NODE_NAME     J35 A62
 '@T6G_MB_LIB.T6G(SCH_1):PAGE341_I168@PURE_QUANTA.SCONN168_ME1016810202011(CHIPS)':
 'PERN14': CDS_PINID='PERN14';
NET_NAME
'P5E_CPU1_G1_RX_DN<15>'
 '@T6G_MB_LIB.T6G(SCH_1):P5E_CPU1_G1_RX_DN'<15>:
 C_SIGNAL='@t6g_mb_lib.t6g(sch_1):p5e_cpu1_g1_rx_dn(15)';
NODE_NAME     U26 U52
 '@T6G_MB_LIB.T6G(SCH_1):PAGE49_I214@PURE_QUANTA.GENOA_SP5(CHIPS)':
 'G1_RXN15': CDS_PINID='G1_RXN15';
NODE_NAME     J35 A65
 '@T6G_MB_LIB.T6G(SCH_1):PAGE341_I168@PURE_QUANTA.SCONN168_ME1016810202011(CHIPS)':
 'PERN15': CDS_PINID='PERN15';
NET_NAME
'P5E_CPU1_G1_RX_DN<1>'
 '@T6G_MB_LIB.T6G(SCH_1):P5E_CPU1_G1_RX_DN'<1>:
 C_SIGNAL='@t6g_mb_lib.t6g(sch_1):p5e_cpu1_g1_rx_dn(1)';
NODE_NAME     U26 T40
 '@T6G_MB_LIB.T6G(SCH_1):PAGE49_I214@PURE_QUANTA.GENOA_SP5(CHIPS)':
 'G1_RXN1': CDS_PINID='G1_RXN1';
NODE_NAME     J35 A20
 '@T6G_MB_LIB.T6G(SCH_1):PAGE341_I168@PURE_QUANTA.SCONN168_ME1016810202011(CHIPS)':
 'PERN1': CDS_PINID='PERN1';
NET_NAME
'P5E_CPU1_G1_RX_DN<2>'
 '@T6G_MB_LIB.T6G(SCH_1):P5E_CPU1_G1_RX_DN'<2>:
 C_SIGNAL='@t6g_mb_lib.t6g(sch_1):p5e_cpu1_g1_rx_dn(2)';
NODE_NAME     U26 P40
 '@T6G_MB_LIB.T6G(SCH_1):PAGE49_I214@PURE_QUANTA.GENOA_SP5(CHIPS)':
 'G1_RXN2': CDS_PINID='G1_RXN2';
NODE_NAME     J35 A23
 '@T6G_MB_LIB.T6G(SCH_1):PAGE341_I168@PURE_QUANTA.SCONN168_ME1016810202011(CHIPS)':
 'PERN2': CDS_PINID='PERN2';
NET_NAME
'P5E_CPU1_G1_RX_DN<3>'
 '@T6G_MB_LIB.T6G(SCH_1):P5E_CPU1_G1_RX_DN'<3>:
 C_SIGNAL='@t6g_mb_lib.t6g(sch_1):p5e_cpu1_g1_rx_dn(3)';
NODE_NAME     U26 U43
 '@T6G_MB_LIB.T6G(SCH_1):PAGE49_I214@PURE_QUANTA.GENOA_SP5(CHIPS)':
 'G1_RXN3': CDS_PINID='G1_RXN3';
NODE_NAME     J35 A26
 '@T6G_MB_LIB.T6G(SCH_1):PAGE341_I168@PURE_QUANTA.SCONN168_ME1016810202011(CHIPS)':
 'PERN3': CDS_PINID='PERN3';
NET_NAME
'P5E_CPU1_G1_RX_DN<4>'
 '@T6G_MB_LIB.T6G(SCH_1):P5E_CPU1_G1_RX_DN'<4>:
 C_SIGNAL='@t6g_mb_lib.t6g(sch_1):p5e_cpu1_g1_rx_dn(4)';
NODE_NAME     U26 N43
 '@T6G_MB_LIB.T6G(SCH_1):PAGE49_I214@PURE_QUANTA.GENOA_SP5(CHIPS)':
 'G1_RXN4': CDS_PINID='G1_RXN4';
NODE_NAME     J35 A30
 '@T6G_MB_LIB.T6G(SCH_1):PAGE341_I168@PURE_QUANTA.SCONN168_ME1016810202011(CHIPS)':
 'PERN4': CDS_PINID='PERN4';
NET_NAME
'P5E_CPU1_G1_RX_DN<5>'
 '@T6G_MB_LIB.T6G(SCH_1):P5E_CPU1_G1_RX_DN'<5>:
 C_SIGNAL='@t6g_mb_lib.t6g(sch_1):p5e_cpu1_g1_rx_dn(5)';
NODE_NAME     U26 R43
 '@T6G_MB_LIB.T6G(SCH_1):PAGE49_I214@PURE_QUANTA.GENOA_SP5(CHIPS)':
 'G1_RXN5': CDS_PINID='G1_RXN5';
NODE_NAME     J35 A33
 '@T6G_MB_LIB.T6G(SCH_1):PAGE341_I168@PURE_QUANTA.SCONN168_ME1016810202011(CHIPS)':
 'PERN5': CDS_PINID='PERN5';
NET_NAME
'P5E_CPU1_G1_RX_DN<6>'
 '@T6G_MB_LIB.T6G(SCH_1):P5E_CPU1_G1_RX_DN'<6>:
 C_SIGNAL='@t6g_mb_lib.t6g(sch_1):p5e_cpu1_g1_rx_dn(6)';
NODE_NAME     U26 U46
 '@T6G_MB_LIB.T6G(SCH_1):PAGE49_I214@PURE_QUANTA.GENOA_SP5(CHIPS)':
 'G1_RXN6': CDS_PINID='G1_RXN6';
NODE_NAME     J35 A36
 '@T6G_MB_LIB.T6G(SCH_1):PAGE341_I168@PURE_QUANTA.SCONN168_ME1016810202011(CHIPS)':
 'PERN6': CDS_PINID='PERN6';
NET_NAME
'P5E_CPU1_G1_RX_DN<7>'
 '@T6G_MB_LIB.T6G(SCH_1):P5E_CPU1_G1_RX_DN'<7>:
 C_SIGNAL='@t6g_mb_lib.t6g(sch_1):p5e_cpu1_g1_rx_dn(7)';
NODE_NAME     U26 N46
 '@T6G_MB_LIB.T6G(SCH_1):PAGE49_I214@PURE_QUANTA.GENOA_SP5(CHIPS)':
 'G1_RXN7': CDS_PINID='G1_RXN7';
NODE_NAME     J35 A39
 '@T6G_MB_LIB.T6G(SCH_1):PAGE341_I168@PURE_QUANTA.SCONN168_ME1016810202011(CHIPS)':
 'PERN7': CDS_PINID='PERN7';
NET_NAME
'P5E_CPU1_G1_RX_DN<8>'
 '@T6G_MB_LIB.T6G(SCH_1):P5E_CPU1_G1_RX_DN'<8>:
 C_SIGNAL='@t6g_mb_lib.t6g(sch_1):p5e_cpu1_g1_rx_dn(8)';
NODE_NAME     U26 R46
 '@T6G_MB_LIB.T6G(SCH_1):PAGE49_I214@PURE_QUANTA.GENOA_SP5(CHIPS)':
 'G1_RXN8': CDS_PINID='G1_RXN8';
NODE_NAME     J35 A44
 '@T6G_MB_LIB.T6G(SCH_1):PAGE341_I168@PURE_QUANTA.SCONN168_ME1016810202011(CHIPS)':
 'PERN8': CDS_PINID='PERN8';
NET_NAME
'P5E_CPU1_G1_RX_DN<9>'
 '@T6G_MB_LIB.T6G(SCH_1):P5E_CPU1_G1_RX_DN'<9>:
 C_SIGNAL='@t6g_mb_lib.t6g(sch_1):p5e_cpu1_g1_rx_dn(9)';
NODE_NAME     U26 W49
 '@T6G_MB_LIB.T6G(SCH_1):PAGE49_I214@PURE_QUANTA.GENOA_SP5(CHIPS)':
 'G1_RXN9': CDS_PINID='G1_RXN9';
NODE_NAME     J35 A47
 '@T6G_MB_LIB.T6G(SCH_1):PAGE341_I168@PURE_QUANTA.SCONN168_ME1016810202011(CHIPS)':
 'PERN9': CDS_PINID='PERN9';
NET_NAME
'P5E_CPU1_G1_RX_DP<0>'
 '@T6G_MB_LIB.T6G(SCH_1):P5E_CPU1_G1_RX_DP'<0>:
 C_SIGNAL='@t6g_mb_lib.t6g(sch_1):p5e_cpu1_g1_rx_dp(0)';
NODE_NAME     U26 V41
 '@T6G_MB_LIB.T6G(SCH_1):PAGE49_I214@PURE_QUANTA.GENOA_SP5(CHIPS)':
 'G1_RXP0': CDS_PINID='G1_RXP0';
NODE_NAME     J35 A18
 '@T6G_MB_LIB.T6G(SCH_1):PAGE341_I168@PURE_QUANTA.SCONN168_ME1016810202011(CHIPS)':
 'PERP0': CDS_PINID='PERP0';
NET_NAME
'P5E_CPU1_G1_RX_DP<10>'
 '@T6G_MB_LIB.T6G(SCH_1):P5E_CPU1_G1_RX_DP'<10>:
 C_SIGNAL='@t6g_mb_lib.t6g(sch_1):p5e_cpu1_g1_rx_dp(10)';
NODE_NAME     U26 N50
 '@T6G_MB_LIB.T6G(SCH_1):PAGE49_I214@PURE_QUANTA.GENOA_SP5(CHIPS)':
 'G1_RXP10': CDS_PINID='G1_RXP10';
NODE_NAME     J35 A51
 '@T6G_MB_LIB.T6G(SCH_1):PAGE341_I168@PURE_QUANTA.SCONN168_ME1016810202011(CHIPS)':
 'PERP10': CDS_PINID='PERP10';
NET_NAME
'P5E_CPU1_G1_RX_DP<11>'
 '@T6G_MB_LIB.T6G(SCH_1):P5E_CPU1_G1_RX_DP'<11>:
 C_SIGNAL='@t6g_mb_lib.t6g(sch_1):p5e_cpu1_g1_rx_dp(11)';
NODE_NAME     U26 R50
 '@T6G_MB_LIB.T6G(SCH_1):PAGE49_I214@PURE_QUANTA.GENOA_SP5(CHIPS)':
 'G1_RXP11': CDS_PINID='G1_RXP11';
NODE_NAME     J35 A54
 '@T6G_MB_LIB.T6G(SCH_1):PAGE341_I168@PURE_QUANTA.SCONN168_ME1016810202011(CHIPS)':
 'PERP11': CDS_PINID='PERP11';
NET_NAME
'P5E_CPU1_G1_RX_DP<12>'
 '@T6G_MB_LIB.T6G(SCH_1):P5E_CPU1_G1_RX_DP'<12>:
 C_SIGNAL='@t6g_mb_lib.t6g(sch_1):p5e_cpu1_g1_rx_dp(12)';
NODE_NAME     U26 U50
 '@T6G_MB_LIB.T6G(SCH_1):PAGE49_I214@PURE_QUANTA.GENOA_SP5(CHIPS)':
 'G1_RXP12': CDS_PINID='G1_RXP12';
NODE_NAME     J35 A57
 '@T6G_MB_LIB.T6G(SCH_1):PAGE341_I168@PURE_QUANTA.SCONN168_ME1016810202011(CHIPS)':
 'PERP12': CDS_PINID='PERP12';
NET_NAME
'P5E_CPU1_G1_RX_DP<13>'
 '@T6G_MB_LIB.T6G(SCH_1):P5E_CPU1_G1_RX_DP'<13>:
 C_SIGNAL='@t6g_mb_lib.t6g(sch_1):p5e_cpu1_g1_rx_dp(13)';
NODE_NAME     U26 W53
 '@T6G_MB_LIB.T6G(SCH_1):PAGE49_I214@PURE_QUANTA.GENOA_SP5(CHIPS)':
 'G1_RXP13': CDS_PINID='G1_RXP13';
NODE_NAME     J35 A60
 '@T6G_MB_LIB.T6G(SCH_1):PAGE341_I168@PURE_QUANTA.SCONN168_ME1016810202011(CHIPS)':
 'PERP13': CDS_PINID='PERP13';
NET_NAME
'P5E_CPU1_G1_RX_DP<14>'
 '@T6G_MB_LIB.T6G(SCH_1):P5E_CPU1_G1_RX_DP'<14>:
 C_SIGNAL='@t6g_mb_lib.t6g(sch_1):p5e_cpu1_g1_rx_dp(14)';
NODE_NAME     U26 R53
 '@T6G_MB_LIB.T6G(SCH_1):PAGE49_I214@PURE_QUANTA.GENOA_SP5(CHIPS)':
 'G1_RXP14': CDS_PINID='G1_RXP14';
NODE_NAME     J35 A63
 '@T6G_MB_LIB.T6G(SCH_1):PAGE341_I168@PURE_QUANTA.SCONN168_ME1016810202011(CHIPS)':
 'PERP14': CDS_PINID='PERP14';
NET_NAME
'P5E_CPU1_G1_RX_DP<15>'
 '@T6G_MB_LIB.T6G(SCH_1):P5E_CPU1_G1_RX_DP'<15>:
 C_SIGNAL='@t6g_mb_lib.t6g(sch_1):p5e_cpu1_g1_rx_dp(15)';
NODE_NAME     U26 U53
 '@T6G_MB_LIB.T6G(SCH_1):PAGE49_I214@PURE_QUANTA.GENOA_SP5(CHIPS)':
 'G1_RXP15': CDS_PINID='G1_RXP15';
NODE_NAME     J35 A66
 '@T6G_MB_LIB.T6G(SCH_1):PAGE341_I168@PURE_QUANTA.SCONN168_ME1016810202011(CHIPS)':
 'PERP15': CDS_PINID='PERP15';
NET_NAME
'P5E_CPU1_G1_RX_DP<1>'
 '@T6G_MB_LIB.T6G(SCH_1):P5E_CPU1_G1_RX_DP'<1>:
 C_SIGNAL='@t6g_mb_lib.t6g(sch_1):p5e_cpu1_g1_rx_dp(1)';
NODE_NAME     U26 T41
 '@T6G_MB_LIB.T6G(SCH_1):PAGE49_I214@PURE_QUANTA.GENOA_SP5(CHIPS)':
 'G1_RXP1': CDS_PINID='G1_RXP1';
NODE_NAME     J35 A21
 '@T6G_MB_LIB.T6G(SCH_1):PAGE341_I168@PURE_QUANTA.SCONN168_ME1016810202011(CHIPS)':
 'PERP1': CDS_PINID='PERP1';
NET_NAME
'P5E_CPU1_G1_RX_DP<2>'
 '@T6G_MB_LIB.T6G(SCH_1):P5E_CPU1_G1_RX_DP'<2>:
 C_SIGNAL='@t6g_mb_lib.t6g(sch_1):p5e_cpu1_g1_rx_dp(2)';
NODE_NAME     U26 P41
 '@T6G_MB_LIB.T6G(SCH_1):PAGE49_I214@PURE_QUANTA.GENOA_SP5(CHIPS)':
 'G1_RXP2': CDS_PINID='G1_RXP2';
NODE_NAME     J35 A24
 '@T6G_MB_LIB.T6G(SCH_1):PAGE341_I168@PURE_QUANTA.SCONN168_ME1016810202011(CHIPS)':
 'PERP2': CDS_PINID='PERP2';
NET_NAME
'P5E_CPU1_G1_RX_DP<3>'
 '@T6G_MB_LIB.T6G(SCH_1):P5E_CPU1_G1_RX_DP'<3>:
 C_SIGNAL='@t6g_mb_lib.t6g(sch_1):p5e_cpu1_g1_rx_dp(3)';
NODE_NAME     U26 U44
 '@T6G_MB_LIB.T6G(SCH_1):PAGE49_I214@PURE_QUANTA.GENOA_SP5(CHIPS)':
 'G1_RXP3': CDS_PINID='G1_RXP3';
NODE_NAME     J35 A27
 '@T6G_MB_LIB.T6G(SCH_1):PAGE341_I168@PURE_QUANTA.SCONN168_ME1016810202011(CHIPS)':
 'PERP3': CDS_PINID='PERP3';
NET_NAME
'P5E_CPU1_G1_RX_DP<4>'
 '@T6G_MB_LIB.T6G(SCH_1):P5E_CPU1_G1_RX_DP'<4>:
 C_SIGNAL='@t6g_mb_lib.t6g(sch_1):p5e_cpu1_g1_rx_dp(4)';
NODE_NAME     U26 N44
 '@T6G_MB_LIB.T6G(SCH_1):PAGE49_I214@PURE_QUANTA.GENOA_SP5(CHIPS)':
 'G1_RXP4': CDS_PINID='G1_RXP4';
NODE_NAME     J35 A31
 '@T6G_MB_LIB.T6G(SCH_1):PAGE341_I168@PURE_QUANTA.SCONN168_ME1016810202011(CHIPS)':
 'PERP4': CDS_PINID='PERP4';
NET_NAME
'P5E_CPU1_G1_RX_DP<5>'
 '@T6G_MB_LIB.T6G(SCH_1):P5E_CPU1_G1_RX_DP'<5>:
 C_SIGNAL='@t6g_mb_lib.t6g(sch_1):p5e_cpu1_g1_rx_dp(5)';
NODE_NAME     U26 R44
 '@T6G_MB_LIB.T6G(SCH_1):PAGE49_I214@PURE_QUANTA.GENOA_SP5(CHIPS)':
 'G1_RXP5': CDS_PINID='G1_RXP5';
NODE_NAME     J35 A34
 '@T6G_MB_LIB.T6G(SCH_1):PAGE341_I168@PURE_QUANTA.SCONN168_ME1016810202011(CHIPS)':
 'PERP5': CDS_PINID='PERP5';
NET_NAME
'P5E_CPU1_G1_RX_DP<6>'
 '@T6G_MB_LIB.T6G(SCH_1):P5E_CPU1_G1_RX_DP'<6>:
 C_SIGNAL='@t6g_mb_lib.t6g(sch_1):p5e_cpu1_g1_rx_dp(6)';
NODE_NAME     U26 U47
 '@T6G_MB_LIB.T6G(SCH_1):PAGE49_I214@PURE_QUANTA.GENOA_SP5(CHIPS)':
 'G1_RXP6': CDS_PINID='G1_RXP6';
NODE_NAME     J35 A37
 '@T6G_MB_LIB.T6G(SCH_1):PAGE341_I168@PURE_QUANTA.SCONN168_ME1016810202011(CHIPS)':
 'PERP6': CDS_PINID='PERP6';
NET_NAME
'P5E_CPU1_G1_RX_DP<7>'
 '@T6G_MB_LIB.T6G(SCH_1):P5E_CPU1_G1_RX_DP'<7>:
 C_SIGNAL='@t6g_mb_lib.t6g(sch_1):p5e_cpu1_g1_rx_dp(7)';
NODE_NAME     U26 N47
 '@T6G_MB_LIB.T6G(SCH_1):PAGE49_I214@PURE_QUANTA.GENOA_SP5(CHIPS)':
 'G1_RXP7': CDS_PINID='G1_RXP7';
NODE_NAME     J35 A40
 '@T6G_MB_LIB.T6G(SCH_1):PAGE341_I168@PURE_QUANTA.SCONN168_ME1016810202011(CHIPS)':
 'PERP7': CDS_PINID='PERP7';
NET_NAME
'P5E_CPU1_G1_RX_DP<8>'
 '@T6G_MB_LIB.T6G(SCH_1):P5E_CPU1_G1_RX_DP'<8>:
 C_SIGNAL='@t6g_mb_lib.t6g(sch_1):p5e_cpu1_g1_rx_dp(8)';
NODE_NAME     U26 R47
 '@T6G_MB_LIB.T6G(SCH_1):PAGE49_I214@PURE_QUANTA.GENOA_SP5(CHIPS)':
 'G1_RXP8': CDS_PINID='G1_RXP8';
NODE_NAME     J35 A45
 '@T6G_MB_LIB.T6G(SCH_1):PAGE341_I168@PURE_QUANTA.SCONN168_ME1016810202011(CHIPS)':
 'PERP8': CDS_PINID='PERP8';
NET_NAME
'P5E_CPU1_G1_RX_DP<9>'
 '@T6G_MB_LIB.T6G(SCH_1):P5E_CPU1_G1_RX_DP'<9>:
 C_SIGNAL='@t6g_mb_lib.t6g(sch_1):p5e_cpu1_g1_rx_dp(9)';
NODE_NAME     U26 W50
 '@T6G_MB_LIB.T6G(SCH_1):PAGE49_I214@PURE_QUANTA.GENOA_SP5(CHIPS)':
 'G1_RXP9': CDS_PINID='G1_RXP9';
NODE_NAME     J35 A48
 '@T6G_MB_LIB.T6G(SCH_1):PAGE341_I168@PURE_QUANTA.SCONN168_ME1016810202011(CHIPS)':
 'PERP9': CDS_PINID='PERP9';
NET_NAME
'P5E_CPU1_G1_TX_C_DN<0>'
 '@T6G_MB_LIB.T6G(SCH_1):P5E_CPU1_G1_TX_C_DN'<0>:
 C_SIGNAL='@t6g_mb_lib.t6g(sch_1):p5e_cpu1_g1_tx_c_dn(0)';
NODE_NAME     J35 B18
 '@T6G_MB_LIB.T6G(SCH_1):PAGE341_I168@PURE_QUANTA.SCONN168_ME1016810202011(CHIPS)':
 'PETP0': CDS_PINID='PETP0';
NODE_NAME     C708 1
 '@T6G_MB_LIB.T6G(SCH_1):PAGE355_I166@PURE_QUANTA.Q_CAP_DIFFBUS(CHIPS)':
 '1': CDS_PINID='\1\';
NET_NAME
'P5E_CPU1_G1_TX_C_DN<10>'
 '@T6G_MB_LIB.T6G(SCH_1):P5E_CPU1_G1_TX_C_DN'<10>:
 C_SIGNAL='@t6g_mb_lib.t6g(sch_1):p5e_cpu1_g1_tx_c_dn(10)';
NODE_NAME     J35 B51
 '@T6G_MB_LIB.T6G(SCH_1):PAGE341_I168@PURE_QUANTA.SCONN168_ME1016810202011(CHIPS)':
 'PETP10': CDS_PINID='PETP10';
NODE_NAME     C688 1
 '@T6G_MB_LIB.T6G(SCH_1):PAGE355_I220@PURE_QUANTA.Q_CAP_DIFFBUS(CHIPS)':
 '1': CDS_PINID='\1\';
NET_NAME
'P5E_CPU1_G1_TX_C_DN<11>'
 '@T6G_MB_LIB.T6G(SCH_1):P5E_CPU1_G1_TX_C_DN'<11>:
 C_SIGNAL='@t6g_mb_lib.t6g(sch_1):p5e_cpu1_g1_tx_c_dn(11)';
NODE_NAME     J35 B54
 '@T6G_MB_LIB.T6G(SCH_1):PAGE341_I168@PURE_QUANTA.SCONN168_ME1016810202011(CHIPS)':
 'PETP11': CDS_PINID='PETP11';
NODE_NAME     C686 1
 '@T6G_MB_LIB.T6G(SCH_1):PAGE355_I223@PURE_QUANTA.Q_CAP_DIFFBUS(CHIPS)':
 '1': CDS_PINID='\1\';
NET_NAME
'P5E_CPU1_G1_TX_C_DN<12>'
 '@T6G_MB_LIB.T6G(SCH_1):P5E_CPU1_G1_TX_C_DN'<12>:
 C_SIGNAL='@t6g_mb_lib.t6g(sch_1):p5e_cpu1_g1_tx_c_dn(12)';
NODE_NAME     J35 B57
 '@T6G_MB_LIB.T6G(SCH_1):PAGE341_I168@PURE_QUANTA.SCONN168_ME1016810202011(CHIPS)':
 'PETP12': CDS_PINID='PETP12';
NODE_NAME     C684 1
 '@T6G_MB_LIB.T6G(SCH_1):PAGE355_I225@PURE_QUANTA.Q_CAP_DIFFBUS(CHIPS)':
 '1': CDS_PINID='\1\';
NET_NAME
'P5E_CPU1_G1_TX_C_DN<13>'
 '@T6G_MB_LIB.T6G(SCH_1):P5E_CPU1_G1_TX_C_DN'<13>:
 C_SIGNAL='@t6g_mb_lib.t6g(sch_1):p5e_cpu1_g1_tx_c_dn(13)';
NODE_NAME     J35 B60
 '@T6G_MB_LIB.T6G(SCH_1):PAGE341_I168@PURE_QUANTA.SCONN168_ME1016810202011(CHIPS)':
 'PETP13': CDS_PINID='PETP13';
NODE_NAME     C682 1
 '@T6G_MB_LIB.T6G(SCH_1):PAGE355_I247@PURE_QUANTA.Q_CAP_DIFFBUS(CHIPS)':
 '1': CDS_PINID='\1\';
NET_NAME
'P5E_CPU1_G1_TX_C_DN<14>'
 '@T6G_MB_LIB.T6G(SCH_1):P5E_CPU1_G1_TX_C_DN'<14>:
 C_SIGNAL='@t6g_mb_lib.t6g(sch_1):p5e_cpu1_g1_tx_c_dn(14)';
NODE_NAME     J35 B63
 '@T6G_MB_LIB.T6G(SCH_1):PAGE341_I168@PURE_QUANTA.SCONN168_ME1016810202011(CHIPS)':
 'PETP14': CDS_PINID='PETP14';
NODE_NAME     C680 1
 '@T6G_MB_LIB.T6G(SCH_1):PAGE355_I249@PURE_QUANTA.Q_CAP_DIFFBUS(CHIPS)':
 '1': CDS_PINID='\1\';
NET_NAME
'P5E_CPU1_G1_TX_C_DN<15>'
 '@T6G_MB_LIB.T6G(SCH_1):P5E_CPU1_G1_TX_C_DN'<15>:
 C_SIGNAL='@t6g_mb_lib.t6g(sch_1):p5e_cpu1_g1_tx_c_dn(15)';
NODE_NAME     J35 B66
 '@T6G_MB_LIB.T6G(SCH_1):PAGE341_I168@PURE_QUANTA.SCONN168_ME1016810202011(CHIPS)':
 'PETP15': CDS_PINID='PETP15';
NODE_NAME     C678 1
 '@T6G_MB_LIB.T6G(SCH_1):PAGE355_I251@PURE_QUANTA.Q_CAP_DIFFBUS(CHIPS)':
 '1': CDS_PINID='\1\';
NET_NAME
'P5E_CPU1_G1_TX_C_DN<1>'
 '@T6G_MB_LIB.T6G(SCH_1):P5E_CPU1_G1_TX_C_DN'<1>:
 C_SIGNAL='@t6g_mb_lib.t6g(sch_1):p5e_cpu1_g1_tx_c_dn(1)';
NODE_NAME     J35 B21
 '@T6G_MB_LIB.T6G(SCH_1):PAGE341_I168@PURE_QUANTA.SCONN168_ME1016810202011(CHIPS)':
 'PETP1': CDS_PINID='PETP1';
NODE_NAME     C706 1
 '@T6G_MB_LIB.T6G(SCH_1):PAGE355_I167@PURE_QUANTA.Q_CAP_DIFFBUS(CHIPS)':
 '1': CDS_PINID='\1\';
NET_NAME
'P5E_CPU1_G1_TX_C_DN<2>'
 '@T6G_MB_LIB.T6G(SCH_1):P5E_CPU1_G1_TX_C_DN'<2>:
 C_SIGNAL='@t6g_mb_lib.t6g(sch_1):p5e_cpu1_g1_tx_c_dn(2)';
NODE_NAME     J35 B24
 '@T6G_MB_LIB.T6G(SCH_1):PAGE341_I168@PURE_QUANTA.SCONN168_ME1016810202011(CHIPS)':
 'PETP2': CDS_PINID='PETP2';
NODE_NAME     C704 1
 '@T6G_MB_LIB.T6G(SCH_1):PAGE355_I170@PURE_QUANTA.Q_CAP_DIFFBUS(CHIPS)':
 '1': CDS_PINID='\1\';
NET_NAME
'P5E_CPU1_G1_TX_C_DN<3>'
 '@T6G_MB_LIB.T6G(SCH_1):P5E_CPU1_G1_TX_C_DN'<3>:
 C_SIGNAL='@t6g_mb_lib.t6g(sch_1):p5e_cpu1_g1_tx_c_dn(3)';
NODE_NAME     J35 B27
 '@T6G_MB_LIB.T6G(SCH_1):PAGE341_I168@PURE_QUANTA.SCONN168_ME1016810202011(CHIPS)':
 'PETP3': CDS_PINID='PETP3';
NODE_NAME     C702 1
 '@T6G_MB_LIB.T6G(SCH_1):PAGE355_I197@PURE_QUANTA.Q_CAP_DIFFBUS(CHIPS)':
 '1': CDS_PINID='\1\';
NET_NAME
'P5E_CPU1_G1_TX_C_DN<4>'
 '@T6G_MB_LIB.T6G(SCH_1):P5E_CPU1_G1_TX_C_DN'<4>:
 C_SIGNAL='@t6g_mb_lib.t6g(sch_1):p5e_cpu1_g1_tx_c_dn(4)';
NODE_NAME     J35 B31
 '@T6G_MB_LIB.T6G(SCH_1):PAGE341_I168@PURE_QUANTA.SCONN168_ME1016810202011(CHIPS)':
 'PETP4': CDS_PINID='PETP4';
NODE_NAME     C700 1
 '@T6G_MB_LIB.T6G(SCH_1):PAGE355_I200@PURE_QUANTA.Q_CAP_DIFFBUS(CHIPS)':
 '1': CDS_PINID='\1\';
NET_NAME
'P5E_CPU1_G1_TX_C_DN<5>'
 '@T6G_MB_LIB.T6G(SCH_1):P5E_CPU1_G1_TX_C_DN'<5>:
 C_SIGNAL='@t6g_mb_lib.t6g(sch_1):p5e_cpu1_g1_tx_c_dn(5)';
NODE_NAME     J35 B34
 '@T6G_MB_LIB.T6G(SCH_1):PAGE341_I168@PURE_QUANTA.SCONN168_ME1016810202011(CHIPS)':
 'PETP5': CDS_PINID='PETP5';
NODE_NAME     C698 1
 '@T6G_MB_LIB.T6G(SCH_1):PAGE355_I201@PURE_QUANTA.Q_CAP_DIFFBUS(CHIPS)':
 '1': CDS_PINID='\1\';
NET_NAME
'P5E_CPU1_G1_TX_C_DN<6>'
 '@T6G_MB_LIB.T6G(SCH_1):P5E_CPU1_G1_TX_C_DN'<6>:
 C_SIGNAL='@t6g_mb_lib.t6g(sch_1):p5e_cpu1_g1_tx_c_dn(6)';
NODE_NAME     J35 B37
 '@T6G_MB_LIB.T6G(SCH_1):PAGE341_I168@PURE_QUANTA.SCONN168_ME1016810202011(CHIPS)':
 'PETP6': CDS_PINID='PETP6';
NODE_NAME     C696 1
 '@T6G_MB_LIB.T6G(SCH_1):PAGE355_I204@PURE_QUANTA.Q_CAP_DIFFBUS(CHIPS)':
 '1': CDS_PINID='\1\';
NET_NAME
'P5E_CPU1_G1_TX_C_DN<7>'
 '@T6G_MB_LIB.T6G(SCH_1):P5E_CPU1_G1_TX_C_DN'<7>:
 C_SIGNAL='@t6g_mb_lib.t6g(sch_1):p5e_cpu1_g1_tx_c_dn(7)';
NODE_NAME     J35 B40
 '@T6G_MB_LIB.T6G(SCH_1):PAGE341_I168@PURE_QUANTA.SCONN168_ME1016810202011(CHIPS)':
 'PETP7': CDS_PINID='PETP7';
NODE_NAME     C694 1
 '@T6G_MB_LIB.T6G(SCH_1):PAGE355_I206@PURE_QUANTA.Q_CAP_DIFFBUS(CHIPS)':
 '1': CDS_PINID='\1\';
NET_NAME
'P5E_CPU1_G1_TX_C_DN<8>'
 '@T6G_MB_LIB.T6G(SCH_1):P5E_CPU1_G1_TX_C_DN'<8>:
 C_SIGNAL='@t6g_mb_lib.t6g(sch_1):p5e_cpu1_g1_tx_c_dn(8)';
NODE_NAME     J35 B45
 '@T6G_MB_LIB.T6G(SCH_1):PAGE341_I168@PURE_QUANTA.SCONN168_ME1016810202011(CHIPS)':
 'PETP8': CDS_PINID='PETP8';
NODE_NAME     C692 1
 '@T6G_MB_LIB.T6G(SCH_1):PAGE355_I217@PURE_QUANTA.Q_CAP_DIFFBUS(CHIPS)':
 '1': CDS_PINID='\1\';
NET_NAME
'P5E_CPU1_G1_TX_C_DN<9>'
 '@T6G_MB_LIB.T6G(SCH_1):P5E_CPU1_G1_TX_C_DN'<9>:
 C_SIGNAL='@t6g_mb_lib.t6g(sch_1):p5e_cpu1_g1_tx_c_dn(9)';
NODE_NAME     J35 B48
 '@T6G_MB_LIB.T6G(SCH_1):PAGE341_I168@PURE_QUANTA.SCONN168_ME1016810202011(CHIPS)':
 'PETP9': CDS_PINID='PETP9';
NODE_NAME     C690 1
 '@T6G_MB_LIB.T6G(SCH_1):PAGE355_I219@PURE_QUANTA.Q_CAP_DIFFBUS(CHIPS)':
 '1': CDS_PINID='\1\';
NET_NAME
'P5E_CPU1_G1_TX_C_DP<0>'
 '@T6G_MB_LIB.T6G(SCH_1):P5E_CPU1_G1_TX_C_DP'<0>:
 C_SIGNAL='@t6g_mb_lib.t6g(sch_1):p5e_cpu1_g1_tx_c_dp(0)';
NODE_NAME     J35 B17
 '@T6G_MB_LIB.T6G(SCH_1):PAGE341_I168@PURE_QUANTA.SCONN168_ME1016810202011(CHIPS)':
 'PETN0': CDS_PINID='PETN0';
NODE_NAME     C709 1
 '@T6G_MB_LIB.T6G(SCH_1):PAGE355_I165@PURE_QUANTA.Q_CAP_DIFFBUS(CHIPS)':
 '1': CDS_PINID='\1\';
NET_NAME
'P5E_CPU1_G1_TX_C_DP<10>'
 '@T6G_MB_LIB.T6G(SCH_1):P5E_CPU1_G1_TX_C_DP'<10>:
 C_SIGNAL='@t6g_mb_lib.t6g(sch_1):p5e_cpu1_g1_tx_c_dp(10)';
NODE_NAME     J35 B50
 '@T6G_MB_LIB.T6G(SCH_1):PAGE341_I168@PURE_QUANTA.SCONN168_ME1016810202011(CHIPS)':
 'PETN10': CDS_PINID='PETN10';
NODE_NAME     C689 1
 '@T6G_MB_LIB.T6G(SCH_1):PAGE355_I221@PURE_QUANTA.Q_CAP_DIFFBUS(CHIPS)':
 '1': CDS_PINID='\1\';
NET_NAME
'P5E_CPU1_G1_TX_C_DP<11>'
 '@T6G_MB_LIB.T6G(SCH_1):P5E_CPU1_G1_TX_C_DP'<11>:
 C_SIGNAL='@t6g_mb_lib.t6g(sch_1):p5e_cpu1_g1_tx_c_dp(11)';
NODE_NAME     J35 B53
 '@T6G_MB_LIB.T6G(SCH_1):PAGE341_I168@PURE_QUANTA.SCONN168_ME1016810202011(CHIPS)':
 'PETN11': CDS_PINID='PETN11';
NODE_NAME     C687 1
 '@T6G_MB_LIB.T6G(SCH_1):PAGE355_I222@PURE_QUANTA.Q_CAP_DIFFBUS(CHIPS)':
 '1': CDS_PINID='\1\';
NET_NAME
'P5E_CPU1_G1_TX_C_DP<12>'
 '@T6G_MB_LIB.T6G(SCH_1):P5E_CPU1_G1_TX_C_DP'<12>:
 C_SIGNAL='@t6g_mb_lib.t6g(sch_1):p5e_cpu1_g1_tx_c_dp(12)';
NODE_NAME     J35 B56
 '@T6G_MB_LIB.T6G(SCH_1):PAGE341_I168@PURE_QUANTA.SCONN168_ME1016810202011(CHIPS)':
 'PETN12': CDS_PINID='PETN12';
NODE_NAME     C685 1
 '@T6G_MB_LIB.T6G(SCH_1):PAGE355_I224@PURE_QUANTA.Q_CAP_DIFFBUS(CHIPS)':
 '1': CDS_PINID='\1\';
NET_NAME
'P5E_CPU1_G1_TX_C_DP<13>'
 '@T6G_MB_LIB.T6G(SCH_1):P5E_CPU1_G1_TX_C_DP'<13>:
 C_SIGNAL='@t6g_mb_lib.t6g(sch_1):p5e_cpu1_g1_tx_c_dp(13)';
NODE_NAME     J35 B59
 '@T6G_MB_LIB.T6G(SCH_1):PAGE341_I168@PURE_QUANTA.SCONN168_ME1016810202011(CHIPS)':
 'PETN13': CDS_PINID='PETN13';
NODE_NAME     C683 1
 '@T6G_MB_LIB.T6G(SCH_1):PAGE355_I236@PURE_QUANTA.Q_CAP_DIFFBUS(CHIPS)':
 '1': CDS_PINID='\1\';
NET_NAME
'P5E_CPU1_G1_TX_C_DP<14>'
 '@T6G_MB_LIB.T6G(SCH_1):P5E_CPU1_G1_TX_C_DP'<14>:
 C_SIGNAL='@t6g_mb_lib.t6g(sch_1):p5e_cpu1_g1_tx_c_dp(14)';
NODE_NAME     J35 B62
 '@T6G_MB_LIB.T6G(SCH_1):PAGE341_I168@PURE_QUANTA.SCONN168_ME1016810202011(CHIPS)':
 'PETN14': CDS_PINID='PETN14';
NODE_NAME     C681 1
 '@T6G_MB_LIB.T6G(SCH_1):PAGE355_I248@PURE_QUANTA.Q_CAP_DIFFBUS(CHIPS)':
 '1': CDS_PINID='\1\';
NET_NAME
'P5E_CPU1_G1_TX_C_DP<15>'
 '@T6G_MB_LIB.T6G(SCH_1):P5E_CPU1_G1_TX_C_DP'<15>:
 C_SIGNAL='@t6g_mb_lib.t6g(sch_1):p5e_cpu1_g1_tx_c_dp(15)';
NODE_NAME     J35 B65
 '@T6G_MB_LIB.T6G(SCH_1):PAGE341_I168@PURE_QUANTA.SCONN168_ME1016810202011(CHIPS)':
 'PETN15': CDS_PINID='PETN15';
NODE_NAME     C679 1
 '@T6G_MB_LIB.T6G(SCH_1):PAGE355_I250@PURE_QUANTA.Q_CAP_DIFFBUS(CHIPS)':
 '1': CDS_PINID='\1\';
NET_NAME
'P5E_CPU1_G1_TX_C_DP<1>'
 '@T6G_MB_LIB.T6G(SCH_1):P5E_CPU1_G1_TX_C_DP'<1>:
 C_SIGNAL='@t6g_mb_lib.t6g(sch_1):p5e_cpu1_g1_tx_c_dp(1)';
NODE_NAME     J35 B20
 '@T6G_MB_LIB.T6G(SCH_1):PAGE341_I168@PURE_QUANTA.SCONN168_ME1016810202011(CHIPS)':
 'PETN1': CDS_PINID='PETN1';
NODE_NAME     C707 1
 '@T6G_MB_LIB.T6G(SCH_1):PAGE355_I168@PURE_QUANTA.Q_CAP_DIFFBUS(CHIPS)':
 '1': CDS_PINID='\1\';
NET_NAME
'P5E_CPU1_G1_TX_C_DP<2>'
 '@T6G_MB_LIB.T6G(SCH_1):P5E_CPU1_G1_TX_C_DP'<2>:
 C_SIGNAL='@t6g_mb_lib.t6g(sch_1):p5e_cpu1_g1_tx_c_dp(2)';
NODE_NAME     J35 B23
 '@T6G_MB_LIB.T6G(SCH_1):PAGE341_I168@PURE_QUANTA.SCONN168_ME1016810202011(CHIPS)':
 'PETN2': CDS_PINID='PETN2';
NODE_NAME     C705 1
 '@T6G_MB_LIB.T6G(SCH_1):PAGE355_I169@PURE_QUANTA.Q_CAP_DIFFBUS(CHIPS)':
 '1': CDS_PINID='\1\';
NET_NAME
'P5E_CPU1_G1_TX_C_DP<3>'
 '@T6G_MB_LIB.T6G(SCH_1):P5E_CPU1_G1_TX_C_DP'<3>:
 C_SIGNAL='@t6g_mb_lib.t6g(sch_1):p5e_cpu1_g1_tx_c_dp(3)';
NODE_NAME     J35 B26
 '@T6G_MB_LIB.T6G(SCH_1):PAGE341_I168@PURE_QUANTA.SCONN168_ME1016810202011(CHIPS)':
 'PETN3': CDS_PINID='PETN3';
NODE_NAME     C703 1
 '@T6G_MB_LIB.T6G(SCH_1):PAGE355_I198@PURE_QUANTA.Q_CAP_DIFFBUS(CHIPS)':
 '1': CDS_PINID='\1\';
NET_NAME
'P5E_CPU1_G1_TX_C_DP<4>'
 '@T6G_MB_LIB.T6G(SCH_1):P5E_CPU1_G1_TX_C_DP'<4>:
 C_SIGNAL='@t6g_mb_lib.t6g(sch_1):p5e_cpu1_g1_tx_c_dp(4)';
NODE_NAME     J35 B30
 '@T6G_MB_LIB.T6G(SCH_1):PAGE341_I168@PURE_QUANTA.SCONN168_ME1016810202011(CHIPS)':
 'PETN4': CDS_PINID='PETN4';
NODE_NAME     C701 1
 '@T6G_MB_LIB.T6G(SCH_1):PAGE355_I199@PURE_QUANTA.Q_CAP_DIFFBUS(CHIPS)':
 '1': CDS_PINID='\1\';
NET_NAME
'P5E_CPU1_G1_TX_C_DP<5>'
 '@T6G_MB_LIB.T6G(SCH_1):P5E_CPU1_G1_TX_C_DP'<5>:
 C_SIGNAL='@t6g_mb_lib.t6g(sch_1):p5e_cpu1_g1_tx_c_dp(5)';
NODE_NAME     J35 B33
 '@T6G_MB_LIB.T6G(SCH_1):PAGE341_I168@PURE_QUANTA.SCONN168_ME1016810202011(CHIPS)':
 'PETN5': CDS_PINID='PETN5';
NODE_NAME     C699 1
 '@T6G_MB_LIB.T6G(SCH_1):PAGE355_I202@PURE_QUANTA.Q_CAP_DIFFBUS(CHIPS)':
 '1': CDS_PINID='\1\';
NET_NAME
'P5E_CPU1_G1_TX_C_DP<6>'
 '@T6G_MB_LIB.T6G(SCH_1):P5E_CPU1_G1_TX_C_DP'<6>:
 C_SIGNAL='@t6g_mb_lib.t6g(sch_1):p5e_cpu1_g1_tx_c_dp(6)';
NODE_NAME     J35 B36
 '@T6G_MB_LIB.T6G(SCH_1):PAGE341_I168@PURE_QUANTA.SCONN168_ME1016810202011(CHIPS)':
 'PETN6': CDS_PINID='PETN6';
NODE_NAME     C697 1
 '@T6G_MB_LIB.T6G(SCH_1):PAGE355_I203@PURE_QUANTA.Q_CAP_DIFFBUS(CHIPS)':
 '1': CDS_PINID='\1\';
NET_NAME
'P5E_CPU1_G1_TX_C_DP<7>'
 '@T6G_MB_LIB.T6G(SCH_1):P5E_CPU1_G1_TX_C_DP'<7>:
 C_SIGNAL='@t6g_mb_lib.t6g(sch_1):p5e_cpu1_g1_tx_c_dp(7)';
NODE_NAME     J35 B39
 '@T6G_MB_LIB.T6G(SCH_1):PAGE341_I168@PURE_QUANTA.SCONN168_ME1016810202011(CHIPS)':
 'PETN7': CDS_PINID='PETN7';
NODE_NAME     C695 1
 '@T6G_MB_LIB.T6G(SCH_1):PAGE355_I205@PURE_QUANTA.Q_CAP_DIFFBUS(CHIPS)':
 '1': CDS_PINID='\1\';
NET_NAME
'P5E_CPU1_G1_TX_C_DP<8>'
 '@T6G_MB_LIB.T6G(SCH_1):P5E_CPU1_G1_TX_C_DP'<8>:
 C_SIGNAL='@t6g_mb_lib.t6g(sch_1):p5e_cpu1_g1_tx_c_dp(8)';
NODE_NAME     J35 B44
 '@T6G_MB_LIB.T6G(SCH_1):PAGE341_I168@PURE_QUANTA.SCONN168_ME1016810202011(CHIPS)':
 'PETN8': CDS_PINID='PETN8';
NODE_NAME     C56 1
 '@T6G_MB_LIB.T6G(SCH_1):PAGE355_I216@PURE_QUANTA.Q_CAP_DIFFBUS(CHIPS)':
 '1': CDS_PINID='\1\';
NET_NAME
'P5E_CPU1_G1_TX_C_DP<9>'
 '@T6G_MB_LIB.T6G(SCH_1):P5E_CPU1_G1_TX_C_DP'<9>:
 C_SIGNAL='@t6g_mb_lib.t6g(sch_1):p5e_cpu1_g1_tx_c_dp(9)';
NODE_NAME     J35 B47
 '@T6G_MB_LIB.T6G(SCH_1):PAGE341_I168@PURE_QUANTA.SCONN168_ME1016810202011(CHIPS)':
 'PETN9': CDS_PINID='PETN9';
NODE_NAME     C691 1
 '@T6G_MB_LIB.T6G(SCH_1):PAGE355_I218@PURE_QUANTA.Q_CAP_DIFFBUS(CHIPS)':
 '1': CDS_PINID='\1\';
NET_NAME
'P5E_CPU1_G1_TX_DN<0>'
 '@T6G_MB_LIB.T6G(SCH_1):P5E_CPU1_G1_TX_DN'<0>:
 C_SIGNAL='@t6g_mb_lib.t6g(sch_1):p5e_cpu1_g1_tx_dn(0)';
NODE_NAME     U26 AP41
 '@T6G_MB_LIB.T6G(SCH_1):PAGE49_I214@PURE_QUANTA.GENOA_SP5(CHIPS)':
 'G1_TXN0': CDS_PINID='G1_TXN0';
NODE_NAME     C708 2
 '@T6G_MB_LIB.T6G(SCH_1):PAGE355_I166@PURE_QUANTA.Q_CAP_DIFFBUS(CHIPS)':
 '2': CDS_PINID='\2\';
NET_NAME
'P5E_CPU1_G1_TX_DN<10>'
 '@T6G_MB_LIB.T6G(SCH_1):P5E_CPU1_G1_TX_DN'<10>:
 C_SIGNAL='@t6g_mb_lib.t6g(sch_1):p5e_cpu1_g1_tx_dn(10)';
NODE_NAME     U26 AN50
 '@T6G_MB_LIB.T6G(SCH_1):PAGE49_I214@PURE_QUANTA.GENOA_SP5(CHIPS)':
 'G1_TXN10': CDS_PINID='G1_TXN10';
NODE_NAME     C688 2
 '@T6G_MB_LIB.T6G(SCH_1):PAGE355_I220@PURE_QUANTA.Q_CAP_DIFFBUS(CHIPS)':
 '2': CDS_PINID='\2\';
NET_NAME
'P5E_CPU1_G1_TX_DN<11>'
 '@T6G_MB_LIB.T6G(SCH_1):P5E_CPU1_G1_TX_DN'<11>:
 C_SIGNAL='@t6g_mb_lib.t6g(sch_1):p5e_cpu1_g1_tx_dn(11)';
NODE_NAME     U26 AJ50
 '@T6G_MB_LIB.T6G(SCH_1):PAGE49_I214@PURE_QUANTA.GENOA_SP5(CHIPS)':
 'G1_TXN11': CDS_PINID='G1_TXN11';
NODE_NAME     C686 2
 '@T6G_MB_LIB.T6G(SCH_1):PAGE355_I223@PURE_QUANTA.Q_CAP_DIFFBUS(CHIPS)':
 '2': CDS_PINID='\2\';
NET_NAME
'P5E_CPU1_G1_TX_DN<12>'
 '@T6G_MB_LIB.T6G(SCH_1):P5E_CPU1_G1_TX_DN'<12>:
 C_SIGNAL='@t6g_mb_lib.t6g(sch_1):p5e_cpu1_g1_tx_dn(12)';
NODE_NAME     U26 AL50
 '@T6G_MB_LIB.T6G(SCH_1):PAGE49_I214@PURE_QUANTA.GENOA_SP5(CHIPS)':
 'G1_TXN12': CDS_PINID='G1_TXN12';
NODE_NAME     C684 2
 '@T6G_MB_LIB.T6G(SCH_1):PAGE355_I225@PURE_QUANTA.Q_CAP_DIFFBUS(CHIPS)':
 '2': CDS_PINID='\2\';
NET_NAME
'P5E_CPU1_G1_TX_DN<13>'
 '@T6G_MB_LIB.T6G(SCH_1):P5E_CPU1_G1_TX_DN'<13>:
 C_SIGNAL='@t6g_mb_lib.t6g(sch_1):p5e_cpu1_g1_tx_dn(13)';
NODE_NAME     U26 AN53
 '@T6G_MB_LIB.T6G(SCH_1):PAGE49_I214@PURE_QUANTA.GENOA_SP5(CHIPS)':
 'G1_TXN13': CDS_PINID='G1_TXN13';
NODE_NAME     C682 2
 '@T6G_MB_LIB.T6G(SCH_1):PAGE355_I247@PURE_QUANTA.Q_CAP_DIFFBUS(CHIPS)':
 '2': CDS_PINID='\2\';
NET_NAME
'P5E_CPU1_G1_TX_DN<14>'
 '@T6G_MB_LIB.T6G(SCH_1):P5E_CPU1_G1_TX_DN'<14>:
 C_SIGNAL='@t6g_mb_lib.t6g(sch_1):p5e_cpu1_g1_tx_dn(14)';
NODE_NAME     U26 AJ53
 '@T6G_MB_LIB.T6G(SCH_1):PAGE49_I214@PURE_QUANTA.GENOA_SP5(CHIPS)':
 'G1_TXN14': CDS_PINID='G1_TXN14';
NODE_NAME     C680 2
 '@T6G_MB_LIB.T6G(SCH_1):PAGE355_I249@PURE_QUANTA.Q_CAP_DIFFBUS(CHIPS)':
 '2': CDS_PINID='\2\';
NET_NAME
'P5E_CPU1_G1_TX_DN<15>'
 '@T6G_MB_LIB.T6G(SCH_1):P5E_CPU1_G1_TX_DN'<15>:
 C_SIGNAL='@t6g_mb_lib.t6g(sch_1):p5e_cpu1_g1_tx_dn(15)';
NODE_NAME     U26 AL53
 '@T6G_MB_LIB.T6G(SCH_1):PAGE49_I214@PURE_QUANTA.GENOA_SP5(CHIPS)':
 'G1_TXN15': CDS_PINID='G1_TXN15';
NODE_NAME     C678 2
 '@T6G_MB_LIB.T6G(SCH_1):PAGE355_I251@PURE_QUANTA.Q_CAP_DIFFBUS(CHIPS)':
 '2': CDS_PINID='\2\';
NET_NAME
'P5E_CPU1_G1_TX_DN<1>'
 '@T6G_MB_LIB.T6G(SCH_1):P5E_CPU1_G1_TX_DN'<1>:
 C_SIGNAL='@t6g_mb_lib.t6g(sch_1):p5e_cpu1_g1_tx_dn(1)';
NODE_NAME     U26 AM41
 '@T6G_MB_LIB.T6G(SCH_1):PAGE49_I214@PURE_QUANTA.GENOA_SP5(CHIPS)':
 'G1_TXN1': CDS_PINID='G1_TXN1';
NODE_NAME     C706 2
 '@T6G_MB_LIB.T6G(SCH_1):PAGE355_I167@PURE_QUANTA.Q_CAP_DIFFBUS(CHIPS)':
 '2': CDS_PINID='\2\';
NET_NAME
'P5E_CPU1_G1_TX_DN<2>'
 '@T6G_MB_LIB.T6G(SCH_1):P5E_CPU1_G1_TX_DN'<2>:
 C_SIGNAL='@t6g_mb_lib.t6g(sch_1):p5e_cpu1_g1_tx_dn(2)';
NODE_NAME     U26 AH41
 '@T6G_MB_LIB.T6G(SCH_1):PAGE49_I214@PURE_QUANTA.GENOA_SP5(CHIPS)':
 'G1_TXN2': CDS_PINID='G1_TXN2';
NODE_NAME     C704 2
 '@T6G_MB_LIB.T6G(SCH_1):PAGE355_I170@PURE_QUANTA.Q_CAP_DIFFBUS(CHIPS)':
 '2': CDS_PINID='\2\';
NET_NAME
'P5E_CPU1_G1_TX_DN<3>'
 '@T6G_MB_LIB.T6G(SCH_1):P5E_CPU1_G1_TX_DN'<3>:
 C_SIGNAL='@t6g_mb_lib.t6g(sch_1):p5e_cpu1_g1_tx_dn(3)';
NODE_NAME     U26 AK41
 '@T6G_MB_LIB.T6G(SCH_1):PAGE49_I214@PURE_QUANTA.GENOA_SP5(CHIPS)':
 'G1_TXN3': CDS_PINID='G1_TXN3';
NODE_NAME     C702 2
 '@T6G_MB_LIB.T6G(SCH_1):PAGE355_I197@PURE_QUANTA.Q_CAP_DIFFBUS(CHIPS)':
 '2': CDS_PINID='\2\';
NET_NAME
'P5E_CPU1_G1_TX_DN<4>'
 '@T6G_MB_LIB.T6G(SCH_1):P5E_CPU1_G1_TX_DN'<4>:
 C_SIGNAL='@t6g_mb_lib.t6g(sch_1):p5e_cpu1_g1_tx_dn(4)';
NODE_NAME     U26 AN44
 '@T6G_MB_LIB.T6G(SCH_1):PAGE49_I214@PURE_QUANTA.GENOA_SP5(CHIPS)':
 'G1_TXN4': CDS_PINID='G1_TXN4';
NODE_NAME     C700 2
 '@T6G_MB_LIB.T6G(SCH_1):PAGE355_I200@PURE_QUANTA.Q_CAP_DIFFBUS(CHIPS)':
 '2': CDS_PINID='\2\';
NET_NAME
'P5E_CPU1_G1_TX_DN<5>'
 '@T6G_MB_LIB.T6G(SCH_1):P5E_CPU1_G1_TX_DN'<5>:
 C_SIGNAL='@t6g_mb_lib.t6g(sch_1):p5e_cpu1_g1_tx_dn(5)';
NODE_NAME     U26 AJ44
 '@T6G_MB_LIB.T6G(SCH_1):PAGE49_I214@PURE_QUANTA.GENOA_SP5(CHIPS)':
 'G1_TXN5': CDS_PINID='G1_TXN5';
NODE_NAME     C698 2
 '@T6G_MB_LIB.T6G(SCH_1):PAGE355_I201@PURE_QUANTA.Q_CAP_DIFFBUS(CHIPS)':
 '2': CDS_PINID='\2\';
NET_NAME
'P5E_CPU1_G1_TX_DN<6>'
 '@T6G_MB_LIB.T6G(SCH_1):P5E_CPU1_G1_TX_DN'<6>:
 C_SIGNAL='@t6g_mb_lib.t6g(sch_1):p5e_cpu1_g1_tx_dn(6)';
NODE_NAME     U26 AL44
 '@T6G_MB_LIB.T6G(SCH_1):PAGE49_I214@PURE_QUANTA.GENOA_SP5(CHIPS)':
 'G1_TXN6': CDS_PINID='G1_TXN6';
NODE_NAME     C696 2
 '@T6G_MB_LIB.T6G(SCH_1):PAGE355_I204@PURE_QUANTA.Q_CAP_DIFFBUS(CHIPS)':
 '2': CDS_PINID='\2\';
NET_NAME
'P5E_CPU1_G1_TX_DN<7>'
 '@T6G_MB_LIB.T6G(SCH_1):P5E_CPU1_G1_TX_DN'<7>:
 C_SIGNAL='@t6g_mb_lib.t6g(sch_1):p5e_cpu1_g1_tx_dn(7)';
NODE_NAME     U26 AN47
 '@T6G_MB_LIB.T6G(SCH_1):PAGE49_I214@PURE_QUANTA.GENOA_SP5(CHIPS)':
 'G1_TXN7': CDS_PINID='G1_TXN7';
NODE_NAME     C694 2
 '@T6G_MB_LIB.T6G(SCH_1):PAGE355_I206@PURE_QUANTA.Q_CAP_DIFFBUS(CHIPS)':
 '2': CDS_PINID='\2\';
NET_NAME
'P5E_CPU1_G1_TX_DN<8>'
 '@T6G_MB_LIB.T6G(SCH_1):P5E_CPU1_G1_TX_DN'<8>:
 C_SIGNAL='@t6g_mb_lib.t6g(sch_1):p5e_cpu1_g1_tx_dn(8)';
NODE_NAME     U26 AJ47
 '@T6G_MB_LIB.T6G(SCH_1):PAGE49_I214@PURE_QUANTA.GENOA_SP5(CHIPS)':
 'G1_TXN8': CDS_PINID='G1_TXN8';
NODE_NAME     C692 2
 '@T6G_MB_LIB.T6G(SCH_1):PAGE355_I217@PURE_QUANTA.Q_CAP_DIFFBUS(CHIPS)':
 '2': CDS_PINID='\2\';
NET_NAME
'P5E_CPU1_G1_TX_DN<9>'
 '@T6G_MB_LIB.T6G(SCH_1):P5E_CPU1_G1_TX_DN'<9>:
 C_SIGNAL='@t6g_mb_lib.t6g(sch_1):p5e_cpu1_g1_tx_dn(9)';
NODE_NAME     U26 AL47
 '@T6G_MB_LIB.T6G(SCH_1):PAGE49_I214@PURE_QUANTA.GENOA_SP5(CHIPS)':
 'G1_TXN9': CDS_PINID='G1_TXN9';
NODE_NAME     C690 2
 '@T6G_MB_LIB.T6G(SCH_1):PAGE355_I219@PURE_QUANTA.Q_CAP_DIFFBUS(CHIPS)':
 '2': CDS_PINID='\2\';
NET_NAME
'P5E_CPU1_G1_TX_DP<0>'
 '@T6G_MB_LIB.T6G(SCH_1):P5E_CPU1_G1_TX_DP'<0>:
 C_SIGNAL='@t6g_mb_lib.t6g(sch_1):p5e_cpu1_g1_tx_dp(0)';
NODE_NAME     U26 AP40
 '@T6G_MB_LIB.T6G(SCH_1):PAGE49_I214@PURE_QUANTA.GENOA_SP5(CHIPS)':
 'G1_TXP0': CDS_PINID='G1_TXP0';
NODE_NAME     C709 2
 '@T6G_MB_LIB.T6G(SCH_1):PAGE355_I165@PURE_QUANTA.Q_CAP_DIFFBUS(CHIPS)':
 '2': CDS_PINID='\2\';
NET_NAME
'P5E_CPU1_G1_TX_DP<10>'
 '@T6G_MB_LIB.T6G(SCH_1):P5E_CPU1_G1_TX_DP'<10>:
 C_SIGNAL='@t6g_mb_lib.t6g(sch_1):p5e_cpu1_g1_tx_dp(10)';
NODE_NAME     U26 AN49
 '@T6G_MB_LIB.T6G(SCH_1):PAGE49_I214@PURE_QUANTA.GENOA_SP5(CHIPS)':
 'G1_TXP10': CDS_PINID='G1_TXP10';
NODE_NAME     C689 2
 '@T6G_MB_LIB.T6G(SCH_1):PAGE355_I221@PURE_QUANTA.Q_CAP_DIFFBUS(CHIPS)':
 '2': CDS_PINID='\2\';
NET_NAME
'P5E_CPU1_G1_TX_DP<11>'
 '@T6G_MB_LIB.T6G(SCH_1):P5E_CPU1_G1_TX_DP'<11>:
 C_SIGNAL='@t6g_mb_lib.t6g(sch_1):p5e_cpu1_g1_tx_dp(11)';
NODE_NAME     U26 AJ49
 '@T6G_MB_LIB.T6G(SCH_1):PAGE49_I214@PURE_QUANTA.GENOA_SP5(CHIPS)':
 'G1_TXP11': CDS_PINID='G1_TXP11';
NODE_NAME     C687 2
 '@T6G_MB_LIB.T6G(SCH_1):PAGE355_I222@PURE_QUANTA.Q_CAP_DIFFBUS(CHIPS)':
 '2': CDS_PINID='\2\';
NET_NAME
'P5E_CPU1_G1_TX_DP<12>'
 '@T6G_MB_LIB.T6G(SCH_1):P5E_CPU1_G1_TX_DP'<12>:
 C_SIGNAL='@t6g_mb_lib.t6g(sch_1):p5e_cpu1_g1_tx_dp(12)';
NODE_NAME     U26 AL49
 '@T6G_MB_LIB.T6G(SCH_1):PAGE49_I214@PURE_QUANTA.GENOA_SP5(CHIPS)':
 'G1_TXP12': CDS_PINID='G1_TXP12';
NODE_NAME     C685 2
 '@T6G_MB_LIB.T6G(SCH_1):PAGE355_I224@PURE_QUANTA.Q_CAP_DIFFBUS(CHIPS)':
 '2': CDS_PINID='\2\';
NET_NAME
'P5E_CPU1_G1_TX_DP<13>'
 '@T6G_MB_LIB.T6G(SCH_1):P5E_CPU1_G1_TX_DP'<13>:
 C_SIGNAL='@t6g_mb_lib.t6g(sch_1):p5e_cpu1_g1_tx_dp(13)';
NODE_NAME     U26 AN52
 '@T6G_MB_LIB.T6G(SCH_1):PAGE49_I214@PURE_QUANTA.GENOA_SP5(CHIPS)':
 'G1_TXP13': CDS_PINID='G1_TXP13';
NODE_NAME     C683 2
 '@T6G_MB_LIB.T6G(SCH_1):PAGE355_I236@PURE_QUANTA.Q_CAP_DIFFBUS(CHIPS)':
 '2': CDS_PINID='\2\';
NET_NAME
'P5E_CPU1_G1_TX_DP<14>'
 '@T6G_MB_LIB.T6G(SCH_1):P5E_CPU1_G1_TX_DP'<14>:
 C_SIGNAL='@t6g_mb_lib.t6g(sch_1):p5e_cpu1_g1_tx_dp(14)';
NODE_NAME     U26 AJ52
 '@T6G_MB_LIB.T6G(SCH_1):PAGE49_I214@PURE_QUANTA.GENOA_SP5(CHIPS)':
 'G1_TXP14': CDS_PINID='G1_TXP14';
NODE_NAME     C681 2
 '@T6G_MB_LIB.T6G(SCH_1):PAGE355_I248@PURE_QUANTA.Q_CAP_DIFFBUS(CHIPS)':
 '2': CDS_PINID='\2\';
NET_NAME
'P5E_CPU1_G1_TX_DP<15>'
 '@T6G_MB_LIB.T6G(SCH_1):P5E_CPU1_G1_TX_DP'<15>:
 C_SIGNAL='@t6g_mb_lib.t6g(sch_1):p5e_cpu1_g1_tx_dp(15)';
NODE_NAME     U26 AL52
 '@T6G_MB_LIB.T6G(SCH_1):PAGE49_I214@PURE_QUANTA.GENOA_SP5(CHIPS)':
 'G1_TXP15': CDS_PINID='G1_TXP15';
NODE_NAME     C679 2
 '@T6G_MB_LIB.T6G(SCH_1):PAGE355_I250@PURE_QUANTA.Q_CAP_DIFFBUS(CHIPS)':
 '2': CDS_PINID='\2\';
NET_NAME
'P5E_CPU1_G1_TX_DP<1>'
 '@T6G_MB_LIB.T6G(SCH_1):P5E_CPU1_G1_TX_DP'<1>:
 C_SIGNAL='@t6g_mb_lib.t6g(sch_1):p5e_cpu1_g1_tx_dp(1)';
NODE_NAME     U26 AM40
 '@T6G_MB_LIB.T6G(SCH_1):PAGE49_I214@PURE_QUANTA.GENOA_SP5(CHIPS)':
 'G1_TXP1': CDS_PINID='G1_TXP1';
NODE_NAME     C707 2
 '@T6G_MB_LIB.T6G(SCH_1):PAGE355_I168@PURE_QUANTA.Q_CAP_DIFFBUS(CHIPS)':
 '2': CDS_PINID='\2\';
NET_NAME
'P5E_CPU1_G1_TX_DP<2>'
 '@T6G_MB_LIB.T6G(SCH_1):P5E_CPU1_G1_TX_DP'<2>:
 C_SIGNAL='@t6g_mb_lib.t6g(sch_1):p5e_cpu1_g1_tx_dp(2)';
NODE_NAME     U26 AH40
 '@T6G_MB_LIB.T6G(SCH_1):PAGE49_I214@PURE_QUANTA.GENOA_SP5(CHIPS)':
 'G1_TXP2': CDS_PINID='G1_TXP2';
NODE_NAME     C705 2
 '@T6G_MB_LIB.T6G(SCH_1):PAGE355_I169@PURE_QUANTA.Q_CAP_DIFFBUS(CHIPS)':
 '2': CDS_PINID='\2\';
NET_NAME
'P5E_CPU1_G1_TX_DP<3>'
 '@T6G_MB_LIB.T6G(SCH_1):P5E_CPU1_G1_TX_DP'<3>:
 C_SIGNAL='@t6g_mb_lib.t6g(sch_1):p5e_cpu1_g1_tx_dp(3)';
NODE_NAME     U26 AK40
 '@T6G_MB_LIB.T6G(SCH_1):PAGE49_I214@PURE_QUANTA.GENOA_SP5(CHIPS)':
 'G1_TXP3': CDS_PINID='G1_TXP3';
NODE_NAME     C703 2
 '@T6G_MB_LIB.T6G(SCH_1):PAGE355_I198@PURE_QUANTA.Q_CAP_DIFFBUS(CHIPS)':
 '2': CDS_PINID='\2\';
NET_NAME
'P5E_CPU1_G1_TX_DP<4>'
 '@T6G_MB_LIB.T6G(SCH_1):P5E_CPU1_G1_TX_DP'<4>:
 C_SIGNAL='@t6g_mb_lib.t6g(sch_1):p5e_cpu1_g1_tx_dp(4)';
NODE_NAME     U26 AN43
 '@T6G_MB_LIB.T6G(SCH_1):PAGE49_I214@PURE_QUANTA.GENOA_SP5(CHIPS)':
 'G1_TXP4': CDS_PINID='G1_TXP4';
NODE_NAME     C701 2
 '@T6G_MB_LIB.T6G(SCH_1):PAGE355_I199@PURE_QUANTA.Q_CAP_DIFFBUS(CHIPS)':
 '2': CDS_PINID='\2\';
NET_NAME
'P5E_CPU1_G1_TX_DP<5>'
 '@T6G_MB_LIB.T6G(SCH_1):P5E_CPU1_G1_TX_DP'<5>:
 C_SIGNAL='@t6g_mb_lib.t6g(sch_1):p5e_cpu1_g1_tx_dp(5)';
NODE_NAME     U26 AJ43
 '@T6G_MB_LIB.T6G(SCH_1):PAGE49_I214@PURE_QUANTA.GENOA_SP5(CHIPS)':
 'G1_TXP5': CDS_PINID='G1_TXP5';
NODE_NAME     C699 2
 '@T6G_MB_LIB.T6G(SCH_1):PAGE355_I202@PURE_QUANTA.Q_CAP_DIFFBUS(CHIPS)':
 '2': CDS_PINID='\2\';
NET_NAME
'P5E_CPU1_G1_TX_DP<6>'
 '@T6G_MB_LIB.T6G(SCH_1):P5E_CPU1_G1_TX_DP'<6>:
 C_SIGNAL='@t6g_mb_lib.t6g(sch_1):p5e_cpu1_g1_tx_dp(6)';
NODE_NAME     U26 AL43
 '@T6G_MB_LIB.T6G(SCH_1):PAGE49_I214@PURE_QUANTA.GENOA_SP5(CHIPS)':
 'G1_TXP6': CDS_PINID='G1_TXP6';
NODE_NAME     C697 2
 '@T6G_MB_LIB.T6G(SCH_1):PAGE355_I203@PURE_QUANTA.Q_CAP_DIFFBUS(CHIPS)':
 '2': CDS_PINID='\2\';
NET_NAME
'P5E_CPU1_G1_TX_DP<7>'
 '@T6G_MB_LIB.T6G(SCH_1):P5E_CPU1_G1_TX_DP'<7>:
 C_SIGNAL='@t6g_mb_lib.t6g(sch_1):p5e_cpu1_g1_tx_dp(7)';
NODE_NAME     U26 AN46
 '@T6G_MB_LIB.T6G(SCH_1):PAGE49_I214@PURE_QUANTA.GENOA_SP5(CHIPS)':
 'G1_TXP7': CDS_PINID='G1_TXP7';
NODE_NAME     C695 2
 '@T6G_MB_LIB.T6G(SCH_1):PAGE355_I205@PURE_QUANTA.Q_CAP_DIFFBUS(CHIPS)':
 '2': CDS_PINID='\2\';
NET_NAME
'P5E_CPU1_G1_TX_DP<8>'
 '@T6G_MB_LIB.T6G(SCH_1):P5E_CPU1_G1_TX_DP'<8>:
 C_SIGNAL='@t6g_mb_lib.t6g(sch_1):p5e_cpu1_g1_tx_dp(8)';
NODE_NAME     U26 AJ46
 '@T6G_MB_LIB.T6G(SCH_1):PAGE49_I214@PURE_QUANTA.GENOA_SP5(CHIPS)':
 'G1_TXP8': CDS_PINID='G1_TXP8';
NODE_NAME     C56 2
 '@T6G_MB_LIB.T6G(SCH_1):PAGE355_I216@PURE_QUANTA.Q_CAP_DIFFBUS(CHIPS)':
 '2': CDS_PINID='\2\';
NET_NAME
'P5E_CPU1_G1_TX_DP<9>'
 '@T6G_MB_LIB.T6G(SCH_1):P5E_CPU1_G1_TX_DP'<9>:
 C_SIGNAL='@t6g_mb_lib.t6g(sch_1):p5e_cpu1_g1_tx_dp(9)';
NODE_NAME     U26 AL46
 '@T6G_MB_LIB.T6G(SCH_1):PAGE49_I214@PURE_QUANTA.GENOA_SP5(CHIPS)':
 'G1_TXP9': CDS_PINID='G1_TXP9';
NODE_NAME     C691 2
 '@T6G_MB_LIB.T6G(SCH_1):PAGE355_I218@PURE_QUANTA.Q_CAP_DIFFBUS(CHIPS)':
 '2': CDS_PINID='\2\';
NET_NAME
'P5E_CPU1_P0_RX_BUF_DN<0>'
 '@T6G_MB_LIB.T6G(SCH_1):P5E_CPU1_P0_RX_BUF_DN'<0>:
 C_SIGNAL='@t6g_mb_lib.t6g(sch_1):p5e_cpu1_p0_rx_buf_dn(0)';
NODE_NAME     U6014 EV2
 '@T6G_MB_LIB.T6G(SCH_1):PAGE402_I38@PURE_QUANTA.PT5161LRS(CHIPS)':
 'A_PERN15': CDS_PINID='A_PERN15';
NODE_NAME     J112 C1
 '@T6G_MB_LIB.T6G(SCH_1):PAGE329_I102@PURE_QUANTA.CONN160_10131762101LF(CHIPS)':
 'C1': CDS_PINID='C1';
NET_NAME
'P5E_CPU1_P0_RX_BUF_DN<10>'
 '@T6G_MB_LIB.T6G(SCH_1):P5E_CPU1_P0_RX_BUF_DN'<10>:
 C_SIGNAL='@t6g_mb_lib.t6g(sch_1):p5e_cpu1_p0_rx_buf_dn(10)';
NODE_NAME     U6014 BH2
 '@T6G_MB_LIB.T6G(SCH_1):PAGE402_I1@PURE_QUANTA.PT5161LRS(CHIPS)':
 'A_PERN5': CDS_PINID='A_PERN5';
NODE_NAME     J111 C3
 '@T6G_MB_LIB.T6G(SCH_1):PAGE328_I76@PURE_QUANTA.CONN112_10137002101LF(CHIPS)':
 'C3': CDS_PINID='C3';
NET_NAME
'P5E_CPU1_P0_RX_BUF_DN<11>'
 '@T6G_MB_LIB.T6G(SCH_1):P5E_CPU1_P0_RX_BUF_DN'<11>:
 C_SIGNAL='@t6g_mb_lib.t6g(sch_1):p5e_cpu1_p0_rx_buf_dn(11)';
NODE_NAME     U6014 BA2
 '@T6G_MB_LIB.T6G(SCH_1):PAGE402_I1@PURE_QUANTA.PT5161LRS(CHIPS)':
 'A_PERN4': CDS_PINID='A_PERN4';
NODE_NAME     J111 B4
 '@T6G_MB_LIB.T6G(SCH_1):PAGE328_I76@PURE_QUANTA.CONN112_10137002101LF(CHIPS)':
 'B4': CDS_PINID='B4';
NET_NAME
'P5E_CPU1_P0_RX_BUF_DN<12>'
 '@T6G_MB_LIB.T6G(SCH_1):P5E_CPU1_P0_RX_BUF_DN'<12>:
 C_SIGNAL='@t6g_mb_lib.t6g(sch_1):p5e_cpu1_p0_rx_buf_dn(12)';
NODE_NAME     U6014 AP2
 '@T6G_MB_LIB.T6G(SCH_1):PAGE402_I1@PURE_QUANTA.PT5161LRS(CHIPS)':
 'A_PERN3': CDS_PINID='A_PERN3';
NODE_NAME     J111 C5
 '@T6G_MB_LIB.T6G(SCH_1):PAGE328_I38@PURE_QUANTA.CONN112_10137002101LF(CHIPS)':
 'C5': CDS_PINID='C5';
NET_NAME
'P5E_CPU1_P0_RX_BUF_DN<13>'
 '@T6G_MB_LIB.T6G(SCH_1):P5E_CPU1_P0_RX_BUF_DN'<13>:
 C_SIGNAL='@t6g_mb_lib.t6g(sch_1):p5e_cpu1_p0_rx_buf_dn(13)';
NODE_NAME     U6014 AG2
 '@T6G_MB_LIB.T6G(SCH_1):PAGE402_I1@PURE_QUANTA.PT5161LRS(CHIPS)':
 'A_PERN2': CDS_PINID='A_PERN2';
NODE_NAME     J111 B6
 '@T6G_MB_LIB.T6G(SCH_1):PAGE328_I38@PURE_QUANTA.CONN112_10137002101LF(CHIPS)':
 'B6': CDS_PINID='B6';
NET_NAME
'P5E_CPU1_P0_RX_BUF_DN<14>'
 '@T6G_MB_LIB.T6G(SCH_1):P5E_CPU1_P0_RX_BUF_DN'<14>:
 C_SIGNAL='@t6g_mb_lib.t6g(sch_1):p5e_cpu1_p0_rx_buf_dn(14)';
NODE_NAME     U6014 Y2
 '@T6G_MB_LIB.T6G(SCH_1):PAGE402_I1@PURE_QUANTA.PT5161LRS(CHIPS)':
 'A_PERN1': CDS_PINID='A_PERN1';
NODE_NAME     J111 C7
 '@T6G_MB_LIB.T6G(SCH_1):PAGE328_I38@PURE_QUANTA.CONN112_10137002101LF(CHIPS)':
 'C7': CDS_PINID='C7';
NET_NAME
'P5E_CPU1_P0_RX_BUF_DN<15>'
 '@T6G_MB_LIB.T6G(SCH_1):P5E_CPU1_P0_RX_BUF_DN'<15>:
 C_SIGNAL='@t6g_mb_lib.t6g(sch_1):p5e_cpu1_p0_rx_buf_dn(15)';
NODE_NAME     U6014 N2
 '@T6G_MB_LIB.T6G(SCH_1):PAGE402_I1@PURE_QUANTA.PT5161LRS(CHIPS)':
 'A_PERN0': CDS_PINID='A_PERN0';
NODE_NAME     J111 B8
 '@T6G_MB_LIB.T6G(SCH_1):PAGE328_I38@PURE_QUANTA.CONN112_10137002101LF(CHIPS)':
 'B8': CDS_PINID='B8';
NET_NAME
'P5E_CPU1_P0_RX_BUF_DN<1>'
 '@T6G_MB_LIB.T6G(SCH_1):P5E_CPU1_P0_RX_BUF_DN'<1>:
 C_SIGNAL='@t6g_mb_lib.t6g(sch_1):p5e_cpu1_p0_rx_buf_dn(1)';
NODE_NAME     U6014 EL2
 '@T6G_MB_LIB.T6G(SCH_1):PAGE402_I38@PURE_QUANTA.PT5161LRS(CHIPS)':
 'A_PERN14': CDS_PINID='A_PERN14';
NODE_NAME     J112 B2
 '@T6G_MB_LIB.T6G(SCH_1):PAGE329_I102@PURE_QUANTA.CONN160_10131762101LF(CHIPS)':
 'B2': CDS_PINID='B2';
NET_NAME
'P5E_CPU1_P0_RX_BUF_DN<2>'
 '@T6G_MB_LIB.T6G(SCH_1):P5E_CPU1_P0_RX_BUF_DN'<2>:
 C_SIGNAL='@t6g_mb_lib.t6g(sch_1):p5e_cpu1_p0_rx_buf_dn(2)';
NODE_NAME     U6014 ED2
 '@T6G_MB_LIB.T6G(SCH_1):PAGE402_I38@PURE_QUANTA.PT5161LRS(CHIPS)':
 'A_PERN13': CDS_PINID='A_PERN13';
NODE_NAME     J112 C3
 '@T6G_MB_LIB.T6G(SCH_1):PAGE329_I102@PURE_QUANTA.CONN160_10131762101LF(CHIPS)':
 'C3': CDS_PINID='C3';
NET_NAME
'P5E_CPU1_P0_RX_BUF_DN<3>'
 '@T6G_MB_LIB.T6G(SCH_1):P5E_CPU1_P0_RX_BUF_DN'<3>:
 C_SIGNAL='@t6g_mb_lib.t6g(sch_1):p5e_cpu1_p0_rx_buf_dn(3)';
NODE_NAME     U6014 DU2
 '@T6G_MB_LIB.T6G(SCH_1):PAGE402_I38@PURE_QUANTA.PT5161LRS(CHIPS)':
 'A_PERN12': CDS_PINID='A_PERN12';
NODE_NAME     J112 B4
 '@T6G_MB_LIB.T6G(SCH_1):PAGE329_I102@PURE_QUANTA.CONN160_10131762101LF(CHIPS)':
 'B4': CDS_PINID='B4';
NET_NAME
'P5E_CPU1_P0_RX_BUF_DN<4>'
 '@T6G_MB_LIB.T6G(SCH_1):P5E_CPU1_P0_RX_BUF_DN'<4>:
 C_SIGNAL='@t6g_mb_lib.t6g(sch_1):p5e_cpu1_p0_rx_buf_dn(4)';
NODE_NAME     U6014 DK2
 '@T6G_MB_LIB.T6G(SCH_1):PAGE402_I38@PURE_QUANTA.PT5161LRS(CHIPS)':
 'A_PERN11': CDS_PINID='A_PERN11';
NODE_NAME     J112 C5
 '@T6G_MB_LIB.T6G(SCH_1):PAGE329_I7@PURE_QUANTA.CONN160_10131762101LF(CHIPS)':
 'C5': CDS_PINID='C5';
NET_NAME
'P5E_CPU1_P0_RX_BUF_DN<5>'
 '@T6G_MB_LIB.T6G(SCH_1):P5E_CPU1_P0_RX_BUF_DN'<5>:
 C_SIGNAL='@t6g_mb_lib.t6g(sch_1):p5e_cpu1_p0_rx_buf_dn(5)';
NODE_NAME     U6014 DC2
 '@T6G_MB_LIB.T6G(SCH_1):PAGE402_I38@PURE_QUANTA.PT5161LRS(CHIPS)':
 'A_PERN10': CDS_PINID='A_PERN10';
NODE_NAME     J112 B6
 '@T6G_MB_LIB.T6G(SCH_1):PAGE329_I7@PURE_QUANTA.CONN160_10131762101LF(CHIPS)':
 'B6': CDS_PINID='B6';
NET_NAME
'P5E_CPU1_P0_RX_BUF_DN<6>'
 '@T6G_MB_LIB.T6G(SCH_1):P5E_CPU1_P0_RX_BUF_DN'<6>:
 C_SIGNAL='@t6g_mb_lib.t6g(sch_1):p5e_cpu1_p0_rx_buf_dn(6)';
NODE_NAME     U6014 CT2
 '@T6G_MB_LIB.T6G(SCH_1):PAGE402_I38@PURE_QUANTA.PT5161LRS(CHIPS)':
 'A_PERN9': CDS_PINID='A_PERN9';
NODE_NAME     J112 C7
 '@T6G_MB_LIB.T6G(SCH_1):PAGE329_I7@PURE_QUANTA.CONN160_10131762101LF(CHIPS)':
 'C7': CDS_PINID='C7';
NET_NAME
'P5E_CPU1_P0_RX_BUF_DN<7>'
 '@T6G_MB_LIB.T6G(SCH_1):P5E_CPU1_P0_RX_BUF_DN'<7>:
 C_SIGNAL='@t6g_mb_lib.t6g(sch_1):p5e_cpu1_p0_rx_buf_dn(7)';
NODE_NAME     U6014 CJ2
 '@T6G_MB_LIB.T6G(SCH_1):PAGE402_I38@PURE_QUANTA.PT5161LRS(CHIPS)':
 'A_PERN8': CDS_PINID='A_PERN8';
NODE_NAME     J112 B8
 '@T6G_MB_LIB.T6G(SCH_1):PAGE329_I7@PURE_QUANTA.CONN160_10131762101LF(CHIPS)':
 'B8': CDS_PINID='B8';
NET_NAME
'P5E_CPU1_P0_RX_BUF_DN<8>'
 '@T6G_MB_LIB.T6G(SCH_1):P5E_CPU1_P0_RX_BUF_DN'<8>:
 C_SIGNAL='@t6g_mb_lib.t6g(sch_1):p5e_cpu1_p0_rx_buf_dn(8)';
NODE_NAME     U6014 CB2
 '@T6G_MB_LIB.T6G(SCH_1):PAGE402_I1@PURE_QUANTA.PT5161LRS(CHIPS)':
 'A_PERN7': CDS_PINID='A_PERN7';
NODE_NAME     J111 C1
 '@T6G_MB_LIB.T6G(SCH_1):PAGE328_I76@PURE_QUANTA.CONN112_10137002101LF(CHIPS)':
 'C1': CDS_PINID='C1';
NET_NAME
'P5E_CPU1_P0_RX_BUF_DN<9>'
 '@T6G_MB_LIB.T6G(SCH_1):P5E_CPU1_P0_RX_BUF_DN'<9>:
 C_SIGNAL='@t6g_mb_lib.t6g(sch_1):p5e_cpu1_p0_rx_buf_dn(9)';
NODE_NAME     U6014 BR2
 '@T6G_MB_LIB.T6G(SCH_1):PAGE402_I1@PURE_QUANTA.PT5161LRS(CHIPS)':
 'A_PERN6': CDS_PINID='A_PERN6';
NODE_NAME     J111 B2
 '@T6G_MB_LIB.T6G(SCH_1):PAGE328_I76@PURE_QUANTA.CONN112_10137002101LF(CHIPS)':
 'B2': CDS_PINID='B2';
NET_NAME
'P5E_CPU1_P0_RX_BUF_DP<0>'
 '@T6G_MB_LIB.T6G(SCH_1):P5E_CPU1_P0_RX_BUF_DP'<0>:
 C_SIGNAL='@t6g_mb_lib.t6g(sch_1):p5e_cpu1_p0_rx_buf_dp(0)';
NODE_NAME     U6014 EY1
 '@T6G_MB_LIB.T6G(SCH_1):PAGE402_I38@PURE_QUANTA.PT5161LRS(CHIPS)':
 'A_PERP15': CDS_PINID='A_PERP15';
NODE_NAME     J112 D1
 '@T6G_MB_LIB.T6G(SCH_1):PAGE329_I102@PURE_QUANTA.CONN160_10131762101LF(CHIPS)':
 'D1': CDS_PINID='D1';
NET_NAME
'P5E_CPU1_P0_RX_BUF_DP<10>'
 '@T6G_MB_LIB.T6G(SCH_1):P5E_CPU1_P0_RX_BUF_DP'<10>:
 C_SIGNAL='@t6g_mb_lib.t6g(sch_1):p5e_cpu1_p0_rx_buf_dp(10)';
NODE_NAME     U6014 BK1
 '@T6G_MB_LIB.T6G(SCH_1):PAGE402_I1@PURE_QUANTA.PT5161LRS(CHIPS)':
 'A_PERP5': CDS_PINID='A_PERP5';
NODE_NAME     J111 D3
 '@T6G_MB_LIB.T6G(SCH_1):PAGE328_I76@PURE_QUANTA.CONN112_10137002101LF(CHIPS)':
 'D3': CDS_PINID='D3';
NET_NAME
'P5E_CPU1_P0_RX_BUF_DP<11>'
 '@T6G_MB_LIB.T6G(SCH_1):P5E_CPU1_P0_RX_BUF_DP'<11>:
 C_SIGNAL='@t6g_mb_lib.t6g(sch_1):p5e_cpu1_p0_rx_buf_dp(11)';
NODE_NAME     U6014 BC1
 '@T6G_MB_LIB.T6G(SCH_1):PAGE402_I1@PURE_QUANTA.PT5161LRS(CHIPS)':
 'A_PERP4': CDS_PINID='A_PERP4';
NODE_NAME     J111 C4
 '@T6G_MB_LIB.T6G(SCH_1):PAGE328_I76@PURE_QUANTA.CONN112_10137002101LF(CHIPS)':
 'C4': CDS_PINID='C4';
NET_NAME
'P5E_CPU1_P0_RX_BUF_DP<12>'
 '@T6G_MB_LIB.T6G(SCH_1):P5E_CPU1_P0_RX_BUF_DP'<12>:
 C_SIGNAL='@t6g_mb_lib.t6g(sch_1):p5e_cpu1_p0_rx_buf_dp(12)';
NODE_NAME     U6014 AT1
 '@T6G_MB_LIB.T6G(SCH_1):PAGE402_I1@PURE_QUANTA.PT5161LRS(CHIPS)':
 'A_PERP3': CDS_PINID='A_PERP3';
NODE_NAME     J111 D5
 '@T6G_MB_LIB.T6G(SCH_1):PAGE328_I38@PURE_QUANTA.CONN112_10137002101LF(CHIPS)':
 'D5': CDS_PINID='D5';
NET_NAME
'P5E_CPU1_P0_RX_BUF_DP<13>'
 '@T6G_MB_LIB.T6G(SCH_1):P5E_CPU1_P0_RX_BUF_DP'<13>:
 C_SIGNAL='@t6g_mb_lib.t6g(sch_1):p5e_cpu1_p0_rx_buf_dp(13)';
NODE_NAME     U6014 AJ1
 '@T6G_MB_LIB.T6G(SCH_1):PAGE402_I1@PURE_QUANTA.PT5161LRS(CHIPS)':
 'A_PERP2': CDS_PINID='A_PERP2';
NODE_NAME     J111 C6
 '@T6G_MB_LIB.T6G(SCH_1):PAGE328_I38@PURE_QUANTA.CONN112_10137002101LF(CHIPS)':
 'C6': CDS_PINID='C6';
NET_NAME
'P5E_CPU1_P0_RX_BUF_DP<14>'
 '@T6G_MB_LIB.T6G(SCH_1):P5E_CPU1_P0_RX_BUF_DP'<14>:
 C_SIGNAL='@t6g_mb_lib.t6g(sch_1):p5e_cpu1_p0_rx_buf_dp(14)';
NODE_NAME     U6014 AB1
 '@T6G_MB_LIB.T6G(SCH_1):PAGE402_I1@PURE_QUANTA.PT5161LRS(CHIPS)':
 'A_PERP1': CDS_PINID='A_PERP1';
NODE_NAME     J111 D7
 '@T6G_MB_LIB.T6G(SCH_1):PAGE328_I38@PURE_QUANTA.CONN112_10137002101LF(CHIPS)':
 'D7': CDS_PINID='D7';
NET_NAME
'P5E_CPU1_P0_RX_BUF_DP<15>'
 '@T6G_MB_LIB.T6G(SCH_1):P5E_CPU1_P0_RX_BUF_DP'<15>:
 C_SIGNAL='@t6g_mb_lib.t6g(sch_1):p5e_cpu1_p0_rx_buf_dp(15)';
NODE_NAME     U6014 R1
 '@T6G_MB_LIB.T6G(SCH_1):PAGE402_I1@PURE_QUANTA.PT5161LRS(CHIPS)':
 'A_PERP0': CDS_PINID='A_PERP0';
NODE_NAME     J111 C8
 '@T6G_MB_LIB.T6G(SCH_1):PAGE328_I38@PURE_QUANTA.CONN112_10137002101LF(CHIPS)':
 'C8': CDS_PINID='C8';
NET_NAME
'P5E_CPU1_P0_RX_BUF_DP<1>'
 '@T6G_MB_LIB.T6G(SCH_1):P5E_CPU1_P0_RX_BUF_DP'<1>:
 C_SIGNAL='@t6g_mb_lib.t6g(sch_1):p5e_cpu1_p0_rx_buf_dp(1)';
NODE_NAME     U6014 EN1
 '@T6G_MB_LIB.T6G(SCH_1):PAGE402_I38@PURE_QUANTA.PT5161LRS(CHIPS)':
 'A_PERP14': CDS_PINID='A_PERP14';
NODE_NAME     J112 C2
 '@T6G_MB_LIB.T6G(SCH_1):PAGE329_I102@PURE_QUANTA.CONN160_10131762101LF(CHIPS)':
 'C2': CDS_PINID='C2';
NET_NAME
'P5E_CPU1_P0_RX_BUF_DP<2>'
 '@T6G_MB_LIB.T6G(SCH_1):P5E_CPU1_P0_RX_BUF_DP'<2>:
 C_SIGNAL='@t6g_mb_lib.t6g(sch_1):p5e_cpu1_p0_rx_buf_dp(2)';
NODE_NAME     U6014 EF1
 '@T6G_MB_LIB.T6G(SCH_1):PAGE402_I38@PURE_QUANTA.PT5161LRS(CHIPS)':
 'A_PERP13': CDS_PINID='A_PERP13';
NODE_NAME     J112 D3
 '@T6G_MB_LIB.T6G(SCH_1):PAGE329_I102@PURE_QUANTA.CONN160_10131762101LF(CHIPS)':
 'D3': CDS_PINID='D3';
NET_NAME
'P5E_CPU1_P0_RX_BUF_DP<3>'
 '@T6G_MB_LIB.T6G(SCH_1):P5E_CPU1_P0_RX_BUF_DP'<3>:
 C_SIGNAL='@t6g_mb_lib.t6g(sch_1):p5e_cpu1_p0_rx_buf_dp(3)';
NODE_NAME     U6014 DW1
 '@T6G_MB_LIB.T6G(SCH_1):PAGE402_I38@PURE_QUANTA.PT5161LRS(CHIPS)':
 'A_PERP12': CDS_PINID='A_PERP12';
NODE_NAME     J112 C4
 '@T6G_MB_LIB.T6G(SCH_1):PAGE329_I102@PURE_QUANTA.CONN160_10131762101LF(CHIPS)':
 'C4': CDS_PINID='C4';
NET_NAME
'P5E_CPU1_P0_RX_BUF_DP<4>'
 '@T6G_MB_LIB.T6G(SCH_1):P5E_CPU1_P0_RX_BUF_DP'<4>:
 C_SIGNAL='@t6g_mb_lib.t6g(sch_1):p5e_cpu1_p0_rx_buf_dp(4)';
NODE_NAME     U6014 DM1
 '@T6G_MB_LIB.T6G(SCH_1):PAGE402_I38@PURE_QUANTA.PT5161LRS(CHIPS)':
 'A_PERP11': CDS_PINID='A_PERP11';
NODE_NAME     J112 D5
 '@T6G_MB_LIB.T6G(SCH_1):PAGE329_I7@PURE_QUANTA.CONN160_10131762101LF(CHIPS)':
 'D5': CDS_PINID='D5';
NET_NAME
'P5E_CPU1_P0_RX_BUF_DP<5>'
 '@T6G_MB_LIB.T6G(SCH_1):P5E_CPU1_P0_RX_BUF_DP'<5>:
 C_SIGNAL='@t6g_mb_lib.t6g(sch_1):p5e_cpu1_p0_rx_buf_dp(5)';
NODE_NAME     U6014 DE1
 '@T6G_MB_LIB.T6G(SCH_1):PAGE402_I38@PURE_QUANTA.PT5161LRS(CHIPS)':
 'A_PERP10': CDS_PINID='A_PERP10';
NODE_NAME     J112 C6
 '@T6G_MB_LIB.T6G(SCH_1):PAGE329_I7@PURE_QUANTA.CONN160_10131762101LF(CHIPS)':
 'C6': CDS_PINID='C6';
NET_NAME
'P5E_CPU1_P0_RX_BUF_DP<6>'
 '@T6G_MB_LIB.T6G(SCH_1):P5E_CPU1_P0_RX_BUF_DP'<6>:
 C_SIGNAL='@t6g_mb_lib.t6g(sch_1):p5e_cpu1_p0_rx_buf_dp(6)';
NODE_NAME     U6014 CV1
 '@T6G_MB_LIB.T6G(SCH_1):PAGE402_I38@PURE_QUANTA.PT5161LRS(CHIPS)':
 'A_PERP9': CDS_PINID='A_PERP9';
NODE_NAME     J112 D7
 '@T6G_MB_LIB.T6G(SCH_1):PAGE329_I7@PURE_QUANTA.CONN160_10131762101LF(CHIPS)':
 'D7': CDS_PINID='D7';
NET_NAME
'P5E_CPU1_P0_RX_BUF_DP<7>'
 '@T6G_MB_LIB.T6G(SCH_1):P5E_CPU1_P0_RX_BUF_DP'<7>:
 C_SIGNAL='@t6g_mb_lib.t6g(sch_1):p5e_cpu1_p0_rx_buf_dp(7)';
NODE_NAME     U6014 CL1
 '@T6G_MB_LIB.T6G(SCH_1):PAGE402_I38@PURE_QUANTA.PT5161LRS(CHIPS)':
 'A_PERP8': CDS_PINID='A_PERP8';
NODE_NAME     J112 C8
 '@T6G_MB_LIB.T6G(SCH_1):PAGE329_I7@PURE_QUANTA.CONN160_10131762101LF(CHIPS)':
 'C8': CDS_PINID='C8';
NET_NAME
'P5E_CPU1_P0_RX_BUF_DP<8>'
 '@T6G_MB_LIB.T6G(SCH_1):P5E_CPU1_P0_RX_BUF_DP'<8>:
 C_SIGNAL='@t6g_mb_lib.t6g(sch_1):p5e_cpu1_p0_rx_buf_dp(8)';
NODE_NAME     U6014 CD1
 '@T6G_MB_LIB.T6G(SCH_1):PAGE402_I1@PURE_QUANTA.PT5161LRS(CHIPS)':
 'A_PERP7': CDS_PINID='A_PERP7';
NODE_NAME     J111 D1
 '@T6G_MB_LIB.T6G(SCH_1):PAGE328_I76@PURE_QUANTA.CONN112_10137002101LF(CHIPS)':
 'D1': CDS_PINID='D1';
NET_NAME
'P5E_CPU1_P0_RX_BUF_DP<9>'
 '@T6G_MB_LIB.T6G(SCH_1):P5E_CPU1_P0_RX_BUF_DP'<9>:
 C_SIGNAL='@t6g_mb_lib.t6g(sch_1):p5e_cpu1_p0_rx_buf_dp(9)';
NODE_NAME     U6014 BU1
 '@T6G_MB_LIB.T6G(SCH_1):PAGE402_I1@PURE_QUANTA.PT5161LRS(CHIPS)':
 'A_PERP6': CDS_PINID='A_PERP6';
NODE_NAME     J111 C2
 '@T6G_MB_LIB.T6G(SCH_1):PAGE328_I76@PURE_QUANTA.CONN112_10137002101LF(CHIPS)':
 'C2': CDS_PINID='C2';
NET_NAME
'P5E_CPU1_P0_RX_DN<0>'
 '@T6G_MB_LIB.T6G(SCH_1):P5E_CPU1_P0_RX_DN'<0>:
 C_SIGNAL='@t6g_mb_lib.t6g(sch_1):p5e_cpu1_p0_rx_dn(0)';
NODE_NAME     U26 BW53
 '@T6G_MB_LIB.T6G(SCH_1):PAGE51_I147@PURE_QUANTA.GENOA_SP5(CHIPS)':
 'P0_RXN0||SATA00_RXN': CDS_PINID='\p0_rxn0||sata00_rxn\';
NODE_NAME     U6014 EW29
 '@T6G_MB_LIB.T6G(SCH_1):PAGE438_I38@PURE_QUANTA.PT5161LRS(CHIPS)':
 'A_PETN15': CDS_PINID='A_PETN15';
NET_NAME
'P5E_CPU1_P0_RX_DN<10>'
 '@T6G_MB_LIB.T6G(SCH_1):P5E_CPU1_P0_RX_DN'<10>:
 C_SIGNAL='@t6g_mb_lib.t6g(sch_1):p5e_cpu1_p0_rx_dn(10)';
NODE_NAME     U26 CA44
 '@T6G_MB_LIB.T6G(SCH_1):PAGE51_I147@PURE_QUANTA.GENOA_SP5(CHIPS)':
 'P0_RXN10||SATA12_RXN': CDS_PINID='\p0_rxn10||sata12_rxn\';
NODE_NAME     U6014 BJ29
 '@T6G_MB_LIB.T6G(SCH_1):PAGE438_I1@PURE_QUANTA.PT5161LRS(CHIPS)':
 'A_PETN5': CDS_PINID='A_PETN5';
NET_NAME
'P5E_CPU1_P0_RX_DN<11>'
 '@T6G_MB_LIB.T6G(SCH_1):P5E_CPU1_P0_RX_DN'<11>:
 C_SIGNAL='@t6g_mb_lib.t6g(sch_1):p5e_cpu1_p0_rx_dn(11)';
NODE_NAME     U26 BU44
 '@T6G_MB_LIB.T6G(SCH_1):PAGE51_I147@PURE_QUANTA.GENOA_SP5(CHIPS)':
 'P0_RXN11||SATA13_RXN': CDS_PINID='\p0_rxn11||sata13_rxn\';
NODE_NAME     U6014 BB29
 '@T6G_MB_LIB.T6G(SCH_1):PAGE438_I1@PURE_QUANTA.PT5161LRS(CHIPS)':
 'A_PETN4': CDS_PINID='A_PETN4';
NET_NAME
'P5E_CPU1_P0_RX_DN<12>'
 '@T6G_MB_LIB.T6G(SCH_1):P5E_CPU1_P0_RX_DN'<12>:
 C_SIGNAL='@t6g_mb_lib.t6g(sch_1):p5e_cpu1_p0_rx_dn(12)';
NODE_NAME     U26 BY41
 '@T6G_MB_LIB.T6G(SCH_1):PAGE51_I147@PURE_QUANTA.GENOA_SP5(CHIPS)':
 'P0_RXN12||SATA14_RXN': CDS_PINID='\p0_rxn12||sata14_rxn\';
NODE_NAME     U6014 AR29
 '@T6G_MB_LIB.T6G(SCH_1):PAGE438_I1@PURE_QUANTA.PT5161LRS(CHIPS)':
 'A_PETN3': CDS_PINID='A_PETN3';
NET_NAME
'P5E_CPU1_P0_RX_DN<13>'
 '@T6G_MB_LIB.T6G(SCH_1):P5E_CPU1_P0_RX_DN'<13>:
 C_SIGNAL='@t6g_mb_lib.t6g(sch_1):p5e_cpu1_p0_rx_dn(13)';
NODE_NAME     U26 CB41
 '@T6G_MB_LIB.T6G(SCH_1):PAGE51_I147@PURE_QUANTA.GENOA_SP5(CHIPS)':
 'P0_RXN13||SATA15_RXN': CDS_PINID='\p0_rxn13||sata15_rxn\';
NODE_NAME     U6014 AH29
 '@T6G_MB_LIB.T6G(SCH_1):PAGE438_I1@PURE_QUANTA.PT5161LRS(CHIPS)':
 'A_PETN2': CDS_PINID='A_PETN2';
NET_NAME
'P5E_CPU1_P0_RX_DN<14>'
 '@T6G_MB_LIB.T6G(SCH_1):P5E_CPU1_P0_RX_DN'<14>:
 C_SIGNAL='@t6g_mb_lib.t6g(sch_1):p5e_cpu1_p0_rx_dn(14)';
NODE_NAME     U26 BV41
 '@T6G_MB_LIB.T6G(SCH_1):PAGE51_I147@PURE_QUANTA.GENOA_SP5(CHIPS)':
 'P0_RXN14||SATA16_RXN': CDS_PINID='\p0_rxn14||sata16_rxn\';
NODE_NAME     U6014 AA29
 '@T6G_MB_LIB.T6G(SCH_1):PAGE438_I1@PURE_QUANTA.PT5161LRS(CHIPS)':
 'A_PETN1': CDS_PINID='A_PETN1';
NET_NAME
'P5E_CPU1_P0_RX_DN<15>'
 '@T6G_MB_LIB.T6G(SCH_1):P5E_CPU1_P0_RX_DN'<15>:
 C_SIGNAL='@t6g_mb_lib.t6g(sch_1):p5e_cpu1_p0_rx_dn(15)';
NODE_NAME     U26 BT41
 '@T6G_MB_LIB.T6G(SCH_1):PAGE51_I147@PURE_QUANTA.GENOA_SP5(CHIPS)':
 'P0_RXN15||SATA17_RXN': CDS_PINID='\p0_rxn15||sata17_rxn\';
NODE_NAME     U6014 P29
 '@T6G_MB_LIB.T6G(SCH_1):PAGE438_I1@PURE_QUANTA.PT5161LRS(CHIPS)':
 'A_PETN0': CDS_PINID='A_PETN0';
NET_NAME
'P5E_CPU1_P0_RX_DN<1>'
 '@T6G_MB_LIB.T6G(SCH_1):P5E_CPU1_P0_RX_DN'<1>:
 C_SIGNAL='@t6g_mb_lib.t6g(sch_1):p5e_cpu1_p0_rx_dn(1)';
NODE_NAME     U26 CA53
 '@T6G_MB_LIB.T6G(SCH_1):PAGE51_I147@PURE_QUANTA.GENOA_SP5(CHIPS)':
 'P0_RXN1||SATA01_RXN': CDS_PINID='\p0_rxn1||sata01_rxn\';
NODE_NAME     U6014 EM29
 '@T6G_MB_LIB.T6G(SCH_1):PAGE438_I38@PURE_QUANTA.PT5161LRS(CHIPS)':
 'A_PETN14': CDS_PINID='A_PETN14';
NET_NAME
'P5E_CPU1_P0_RX_DN<2>'
 '@T6G_MB_LIB.T6G(SCH_1):P5E_CPU1_P0_RX_DN'<2>:
 C_SIGNAL='@t6g_mb_lib.t6g(sch_1):p5e_cpu1_p0_rx_dn(2)';
NODE_NAME     U26 BU53
 '@T6G_MB_LIB.T6G(SCH_1):PAGE51_I147@PURE_QUANTA.GENOA_SP5(CHIPS)':
 'P0_RXN2||SATA02_RXN': CDS_PINID='\p0_rxn2||sata02_rxn\';
NODE_NAME     U6014 EE29
 '@T6G_MB_LIB.T6G(SCH_1):PAGE438_I38@PURE_QUANTA.PT5161LRS(CHIPS)':
 'A_PETN13': CDS_PINID='A_PETN13';
NET_NAME
'P5E_CPU1_P0_RX_DN<3>'
 '@T6G_MB_LIB.T6G(SCH_1):P5E_CPU1_P0_RX_DN'<3>:
 C_SIGNAL='@t6g_mb_lib.t6g(sch_1):p5e_cpu1_p0_rx_dn(3)';
NODE_NAME     U26 BW50
 '@T6G_MB_LIB.T6G(SCH_1):PAGE51_I147@PURE_QUANTA.GENOA_SP5(CHIPS)':
 'P0_RXN3||SATA03_RXN': CDS_PINID='\p0_rxn3||sata03_rxn\';
NODE_NAME     U6014 DV29
 '@T6G_MB_LIB.T6G(SCH_1):PAGE438_I38@PURE_QUANTA.PT5161LRS(CHIPS)':
 'A_PETN12': CDS_PINID='A_PETN12';
NET_NAME
'P5E_CPU1_P0_RX_DN<4>'
 '@T6G_MB_LIB.T6G(SCH_1):P5E_CPU1_P0_RX_DN'<4>:
 C_SIGNAL='@t6g_mb_lib.t6g(sch_1):p5e_cpu1_p0_rx_dn(4)';
NODE_NAME     U26 CA50
 '@T6G_MB_LIB.T6G(SCH_1):PAGE51_I147@PURE_QUANTA.GENOA_SP5(CHIPS)':
 'P0_RXN4||SATA04_RXN': CDS_PINID='\p0_rxn4||sata04_rxn\';
NODE_NAME     U6014 DL29
 '@T6G_MB_LIB.T6G(SCH_1):PAGE438_I38@PURE_QUANTA.PT5161LRS(CHIPS)':
 'A_PETN11': CDS_PINID='A_PETN11';
NET_NAME
'P5E_CPU1_P0_RX_DN<5>'
 '@T6G_MB_LIB.T6G(SCH_1):P5E_CPU1_P0_RX_DN'<5>:
 C_SIGNAL='@t6g_mb_lib.t6g(sch_1):p5e_cpu1_p0_rx_dn(5)';
NODE_NAME     U26 BU50
 '@T6G_MB_LIB.T6G(SCH_1):PAGE51_I147@PURE_QUANTA.GENOA_SP5(CHIPS)':
 'P0_RXN5||SATA05_RXN': CDS_PINID='\p0_rxn5||sata05_rxn\';
NODE_NAME     U6014 DD29
 '@T6G_MB_LIB.T6G(SCH_1):PAGE438_I38@PURE_QUANTA.PT5161LRS(CHIPS)':
 'A_PETN10': CDS_PINID='A_PETN10';
NET_NAME
'P5E_CPU1_P0_RX_DN<6>'
 '@T6G_MB_LIB.T6G(SCH_1):P5E_CPU1_P0_RX_DN'<6>:
 C_SIGNAL='@t6g_mb_lib.t6g(sch_1):p5e_cpu1_p0_rx_dn(6)';
NODE_NAME     U26 BW47
 '@T6G_MB_LIB.T6G(SCH_1):PAGE51_I147@PURE_QUANTA.GENOA_SP5(CHIPS)':
 'P0_RXN6||SATA06_RXN': CDS_PINID='\p0_rxn6||sata06_rxn\';
NODE_NAME     U6014 CU29
 '@T6G_MB_LIB.T6G(SCH_1):PAGE438_I38@PURE_QUANTA.PT5161LRS(CHIPS)':
 'A_PETN9': CDS_PINID='A_PETN9';
NET_NAME
'P5E_CPU1_P0_RX_DN<7>'
 '@T6G_MB_LIB.T6G(SCH_1):P5E_CPU1_P0_RX_DN'<7>:
 C_SIGNAL='@t6g_mb_lib.t6g(sch_1):p5e_cpu1_p0_rx_dn(7)';
NODE_NAME     U26 CA47
 '@T6G_MB_LIB.T6G(SCH_1):PAGE51_I147@PURE_QUANTA.GENOA_SP5(CHIPS)':
 'P0_RXN7||SATA07_RXN': CDS_PINID='\p0_rxn7||sata07_rxn\';
NODE_NAME     U6014 CK29
 '@T6G_MB_LIB.T6G(SCH_1):PAGE438_I38@PURE_QUANTA.PT5161LRS(CHIPS)':
 'A_PETN8': CDS_PINID='A_PETN8';
NET_NAME
'P5E_CPU1_P0_RX_DN<8>'
 '@T6G_MB_LIB.T6G(SCH_1):P5E_CPU1_P0_RX_DN'<8>:
 C_SIGNAL='@t6g_mb_lib.t6g(sch_1):p5e_cpu1_p0_rx_dn(8)';
NODE_NAME     U26 BU47
 '@T6G_MB_LIB.T6G(SCH_1):PAGE51_I147@PURE_QUANTA.GENOA_SP5(CHIPS)':
 'P0_RXN8||SATA10_RXN': CDS_PINID='\p0_rxn8||sata10_rxn\';
NODE_NAME     U6014 CC29
 '@T6G_MB_LIB.T6G(SCH_1):PAGE438_I1@PURE_QUANTA.PT5161LRS(CHIPS)':
 'A_PETN7': CDS_PINID='A_PETN7';
NET_NAME
'P5E_CPU1_P0_RX_DN<9>'
 '@T6G_MB_LIB.T6G(SCH_1):P5E_CPU1_P0_RX_DN'<9>:
 C_SIGNAL='@t6g_mb_lib.t6g(sch_1):p5e_cpu1_p0_rx_dn(9)';
NODE_NAME     U26 BW44
 '@T6G_MB_LIB.T6G(SCH_1):PAGE51_I147@PURE_QUANTA.GENOA_SP5(CHIPS)':
 'P0_RXN9||SATA11_RXN': CDS_PINID='\p0_rxn9||sata11_rxn\';
NODE_NAME     U6014 BT29
 '@T6G_MB_LIB.T6G(SCH_1):PAGE438_I1@PURE_QUANTA.PT5161LRS(CHIPS)':
 'A_PETN6': CDS_PINID='A_PETN6';
NET_NAME
'P5E_CPU1_P0_RX_DP<0>'
 '@T6G_MB_LIB.T6G(SCH_1):P5E_CPU1_P0_RX_DP'<0>:
 C_SIGNAL='@t6g_mb_lib.t6g(sch_1):p5e_cpu1_p0_rx_dp(0)';
NODE_NAME     U26 BW52
 '@T6G_MB_LIB.T6G(SCH_1):PAGE51_I147@PURE_QUANTA.GENOA_SP5(CHIPS)':
 'P0_RXP0||SATA00_RXP': CDS_PINID='\p0_rxp0||sata00_rxp\';
NODE_NAME     U6014 EU26
 '@T6G_MB_LIB.T6G(SCH_1):PAGE438_I38@PURE_QUANTA.PT5161LRS(CHIPS)':
 'A_PETP15': CDS_PINID='A_PETP15';
NET_NAME
'P5E_CPU1_P0_RX_DP<10>'
 '@T6G_MB_LIB.T6G(SCH_1):P5E_CPU1_P0_RX_DP'<10>:
 C_SIGNAL='@t6g_mb_lib.t6g(sch_1):p5e_cpu1_p0_rx_dp(10)';
NODE_NAME     U26 CA43
 '@T6G_MB_LIB.T6G(SCH_1):PAGE51_I147@PURE_QUANTA.GENOA_SP5(CHIPS)':
 'P0_RXP10||SATA12_RXP': CDS_PINID='\p0_rxp10||sata12_rxp\';
NODE_NAME     U6014 BG26
 '@T6G_MB_LIB.T6G(SCH_1):PAGE438_I1@PURE_QUANTA.PT5161LRS(CHIPS)':
 'A_PETP5': CDS_PINID='A_PETP5';
NET_NAME
'P5E_CPU1_P0_RX_DP<11>'
 '@T6G_MB_LIB.T6G(SCH_1):P5E_CPU1_P0_RX_DP'<11>:
 C_SIGNAL='@t6g_mb_lib.t6g(sch_1):p5e_cpu1_p0_rx_dp(11)';
NODE_NAME     U26 BU43
 '@T6G_MB_LIB.T6G(SCH_1):PAGE51_I147@PURE_QUANTA.GENOA_SP5(CHIPS)':
 'P0_RXP11||SATA13_RXP': CDS_PINID='\p0_rxp11||sata13_rxp\';
NODE_NAME     U6014 AY26
 '@T6G_MB_LIB.T6G(SCH_1):PAGE438_I1@PURE_QUANTA.PT5161LRS(CHIPS)':
 'A_PETP4': CDS_PINID='A_PETP4';
NET_NAME
'P5E_CPU1_P0_RX_DP<12>'
 '@T6G_MB_LIB.T6G(SCH_1):P5E_CPU1_P0_RX_DP'<12>:
 C_SIGNAL='@t6g_mb_lib.t6g(sch_1):p5e_cpu1_p0_rx_dp(12)';
NODE_NAME     U26 BY40
 '@T6G_MB_LIB.T6G(SCH_1):PAGE51_I147@PURE_QUANTA.GENOA_SP5(CHIPS)':
 'P0_RXP12||SATA14_RXP': CDS_PINID='\p0_rxp12||sata14_rxp\';
NODE_NAME     U6014 AN26
 '@T6G_MB_LIB.T6G(SCH_1):PAGE438_I1@PURE_QUANTA.PT5161LRS(CHIPS)':
 'A_PETP3': CDS_PINID='A_PETP3';
NET_NAME
'P5E_CPU1_P0_RX_DP<13>'
 '@T6G_MB_LIB.T6G(SCH_1):P5E_CPU1_P0_RX_DP'<13>:
 C_SIGNAL='@t6g_mb_lib.t6g(sch_1):p5e_cpu1_p0_rx_dp(13)';
NODE_NAME     U26 CB40
 '@T6G_MB_LIB.T6G(SCH_1):PAGE51_I147@PURE_QUANTA.GENOA_SP5(CHIPS)':
 'P0_RXP13||SATA15_RXP': CDS_PINID='\p0_rxp13||sata15_rxp\';
NODE_NAME     U6014 AF26
 '@T6G_MB_LIB.T6G(SCH_1):PAGE438_I1@PURE_QUANTA.PT5161LRS(CHIPS)':
 'A_PETP2': CDS_PINID='A_PETP2';
NET_NAME
'P5E_CPU1_P0_RX_DP<14>'
 '@T6G_MB_LIB.T6G(SCH_1):P5E_CPU1_P0_RX_DP'<14>:
 C_SIGNAL='@t6g_mb_lib.t6g(sch_1):p5e_cpu1_p0_rx_dp(14)';
NODE_NAME     U26 BV40
 '@T6G_MB_LIB.T6G(SCH_1):PAGE51_I147@PURE_QUANTA.GENOA_SP5(CHIPS)':
 'P0_RXP14||SATA16_RXP': CDS_PINID='\p0_rxp14||sata16_rxp\';
NODE_NAME     U6014 W26
 '@T6G_MB_LIB.T6G(SCH_1):PAGE438_I1@PURE_QUANTA.PT5161LRS(CHIPS)':
 'A_PETP1': CDS_PINID='A_PETP1';
NET_NAME
'P5E_CPU1_P0_RX_DP<15>'
 '@T6G_MB_LIB.T6G(SCH_1):P5E_CPU1_P0_RX_DP'<15>:
 C_SIGNAL='@t6g_mb_lib.t6g(sch_1):p5e_cpu1_p0_rx_dp(15)';
NODE_NAME     U26 BT40
 '@T6G_MB_LIB.T6G(SCH_1):PAGE51_I147@PURE_QUANTA.GENOA_SP5(CHIPS)':
 'P0_RXP15||SATA17_RXP': CDS_PINID='\p0_rxp15||sata17_rxp\';
NODE_NAME     U6014 M26
 '@T6G_MB_LIB.T6G(SCH_1):PAGE438_I1@PURE_QUANTA.PT5161LRS(CHIPS)':
 'A_PETP0': CDS_PINID='A_PETP0';
NET_NAME
'P5E_CPU1_P0_RX_DP<1>'
 '@T6G_MB_LIB.T6G(SCH_1):P5E_CPU1_P0_RX_DP'<1>:
 C_SIGNAL='@t6g_mb_lib.t6g(sch_1):p5e_cpu1_p0_rx_dp(1)';
NODE_NAME     U26 CA52
 '@T6G_MB_LIB.T6G(SCH_1):PAGE51_I147@PURE_QUANTA.GENOA_SP5(CHIPS)':
 'P0_RXP1||SATA01_RXP': CDS_PINID='\p0_rxp1||sata01_rxp\';
NODE_NAME     U6014 EK26
 '@T6G_MB_LIB.T6G(SCH_1):PAGE438_I38@PURE_QUANTA.PT5161LRS(CHIPS)':
 'A_PETP14': CDS_PINID='A_PETP14';
NET_NAME
'P5E_CPU1_P0_RX_DP<2>'
 '@T6G_MB_LIB.T6G(SCH_1):P5E_CPU1_P0_RX_DP'<2>:
 C_SIGNAL='@t6g_mb_lib.t6g(sch_1):p5e_cpu1_p0_rx_dp(2)';
NODE_NAME     U26 BU52
 '@T6G_MB_LIB.T6G(SCH_1):PAGE51_I147@PURE_QUANTA.GENOA_SP5(CHIPS)':
 'P0_RXP2||SATA02_RXP': CDS_PINID='\p0_rxp2||sata02_rxp\';
NODE_NAME     U6014 EC26
 '@T6G_MB_LIB.T6G(SCH_1):PAGE438_I38@PURE_QUANTA.PT5161LRS(CHIPS)':
 'A_PETP13': CDS_PINID='A_PETP13';
NET_NAME
'P5E_CPU1_P0_RX_DP<3>'
 '@T6G_MB_LIB.T6G(SCH_1):P5E_CPU1_P0_RX_DP'<3>:
 C_SIGNAL='@t6g_mb_lib.t6g(sch_1):p5e_cpu1_p0_rx_dp(3)';
NODE_NAME     U26 BW49
 '@T6G_MB_LIB.T6G(SCH_1):PAGE51_I147@PURE_QUANTA.GENOA_SP5(CHIPS)':
 'P0_RXP3||SATA03_RXP': CDS_PINID='\p0_rxp3||sata03_rxp\';
NODE_NAME     U6014 DT26
 '@T6G_MB_LIB.T6G(SCH_1):PAGE438_I38@PURE_QUANTA.PT5161LRS(CHIPS)':
 'A_PETP12': CDS_PINID='A_PETP12';
NET_NAME
'P5E_CPU1_P0_RX_DP<4>'
 '@T6G_MB_LIB.T6G(SCH_1):P5E_CPU1_P0_RX_DP'<4>:
 C_SIGNAL='@t6g_mb_lib.t6g(sch_1):p5e_cpu1_p0_rx_dp(4)';
NODE_NAME     U26 CA49
 '@T6G_MB_LIB.T6G(SCH_1):PAGE51_I147@PURE_QUANTA.GENOA_SP5(CHIPS)':
 'P0_RXP4||SATA04_RXP': CDS_PINID='\p0_rxp4||sata04_rxp\';
NODE_NAME     U6014 DJ26
 '@T6G_MB_LIB.T6G(SCH_1):PAGE438_I38@PURE_QUANTA.PT5161LRS(CHIPS)':
 'A_PETP11': CDS_PINID='A_PETP11';
NET_NAME
'P5E_CPU1_P0_RX_DP<5>'
 '@T6G_MB_LIB.T6G(SCH_1):P5E_CPU1_P0_RX_DP'<5>:
 C_SIGNAL='@t6g_mb_lib.t6g(sch_1):p5e_cpu1_p0_rx_dp(5)';
NODE_NAME     U26 BU49
 '@T6G_MB_LIB.T6G(SCH_1):PAGE51_I147@PURE_QUANTA.GENOA_SP5(CHIPS)':
 'P0_RXP5||SATA05_RXP': CDS_PINID='\p0_rxp5||sata05_rxp\';
NODE_NAME     U6014 DB26
 '@T6G_MB_LIB.T6G(SCH_1):PAGE438_I38@PURE_QUANTA.PT5161LRS(CHIPS)':
 'A_PETP10': CDS_PINID='A_PETP10';
NET_NAME
'P5E_CPU1_P0_RX_DP<6>'
 '@T6G_MB_LIB.T6G(SCH_1):P5E_CPU1_P0_RX_DP'<6>:
 C_SIGNAL='@t6g_mb_lib.t6g(sch_1):p5e_cpu1_p0_rx_dp(6)';
NODE_NAME     U26 BW46
 '@T6G_MB_LIB.T6G(SCH_1):PAGE51_I147@PURE_QUANTA.GENOA_SP5(CHIPS)':
 'P0_RXP6||SATA06_RXP': CDS_PINID='\p0_rxp6||sata06_rxp\';
NODE_NAME     U6014 CR26
 '@T6G_MB_LIB.T6G(SCH_1):PAGE438_I38@PURE_QUANTA.PT5161LRS(CHIPS)':
 'A_PETP9': CDS_PINID='A_PETP9';
NET_NAME
'P5E_CPU1_P0_RX_DP<7>'
 '@T6G_MB_LIB.T6G(SCH_1):P5E_CPU1_P0_RX_DP'<7>:
 C_SIGNAL='@t6g_mb_lib.t6g(sch_1):p5e_cpu1_p0_rx_dp(7)';
NODE_NAME     U26 CA46
 '@T6G_MB_LIB.T6G(SCH_1):PAGE51_I147@PURE_QUANTA.GENOA_SP5(CHIPS)':
 'P0_RXP7||SATA07_RXP': CDS_PINID='\p0_rxp7||sata07_rxp\';
NODE_NAME     U6014 CH26
 '@T6G_MB_LIB.T6G(SCH_1):PAGE438_I38@PURE_QUANTA.PT5161LRS(CHIPS)':
 'A_PETP8': CDS_PINID='A_PETP8';
NET_NAME
'P5E_CPU1_P0_RX_DP<8>'
 '@T6G_MB_LIB.T6G(SCH_1):P5E_CPU1_P0_RX_DP'<8>:
 C_SIGNAL='@t6g_mb_lib.t6g(sch_1):p5e_cpu1_p0_rx_dp(8)';
NODE_NAME     U26 BU46
 '@T6G_MB_LIB.T6G(SCH_1):PAGE51_I147@PURE_QUANTA.GENOA_SP5(CHIPS)':
 'P0_RXP8||SATA10_RXP': CDS_PINID='\p0_rxp8||sata10_rxp\';
NODE_NAME     U6014 CA26
 '@T6G_MB_LIB.T6G(SCH_1):PAGE438_I1@PURE_QUANTA.PT5161LRS(CHIPS)':
 'A_PETP7': CDS_PINID='A_PETP7';
NET_NAME
'P5E_CPU1_P0_RX_DP<9>'
 '@T6G_MB_LIB.T6G(SCH_1):P5E_CPU1_P0_RX_DP'<9>:
 C_SIGNAL='@t6g_mb_lib.t6g(sch_1):p5e_cpu1_p0_rx_dp(9)';
NODE_NAME     U26 BW43
 '@T6G_MB_LIB.T6G(SCH_1):PAGE51_I147@PURE_QUANTA.GENOA_SP5(CHIPS)':
 'P0_RXP9||SATA11_RXP': CDS_PINID='\p0_rxp9||sata11_rxp\';
NODE_NAME     U6014 BP26
 '@T6G_MB_LIB.T6G(SCH_1):PAGE438_I1@PURE_QUANTA.PT5161LRS(CHIPS)':
 'A_PETP6': CDS_PINID='A_PETP6';
NET_NAME
'P5E_CPU1_P0_TX_BUF_C_DN<0>'
 '@T6G_MB_LIB.T6G(SCH_1):P5E_CPU1_P0_TX_BUF_C_DN'<0>:
 C_SIGNAL='@t6g_mb_lib.t6g(sch_1):p5e_cpu1_p0_tx_buf_c_dn(0)';
NODE_NAME     C6630 1
 '@T6G_MB_LIB.T6G(SCH_1):PAGE439_I47@PURE_QUANTA.Q_CAP_DIFFBUS(CHIPS)':
 '1': CDS_PINID='\1\';
NODE_NAME     J112 I1
 '@T6G_MB_LIB.T6G(SCH_1):PAGE329_I102@PURE_QUANTA.CONN160_10131762101LF(CHIPS)':
 'I1': CDS_PINID='I1';
NET_NAME
'P5E_CPU1_P0_TX_BUF_C_DN<10>'
 '@T6G_MB_LIB.T6G(SCH_1):P5E_CPU1_P0_TX_BUF_C_DN'<10>:
 C_SIGNAL='@t6g_mb_lib.t6g(sch_1):p5e_cpu1_p0_tx_buf_c_dn(10)';
NODE_NAME     C6650 1
 '@T6G_MB_LIB.T6G(SCH_1):PAGE439_I97@PURE_QUANTA.Q_CAP_DIFFBUS(CHIPS)':
 '1': CDS_PINID='\1\';
NODE_NAME     J111 I3
 '@T6G_MB_LIB.T6G(SCH_1):PAGE328_I76@PURE_QUANTA.CONN112_10137002101LF(CHIPS)':
 'I3': CDS_PINID='I3';
NET_NAME
'P5E_CPU1_P0_TX_BUF_C_DN<11>'
 '@T6G_MB_LIB.T6G(SCH_1):P5E_CPU1_P0_TX_BUF_C_DN'<11>:
 C_SIGNAL='@t6g_mb_lib.t6g(sch_1):p5e_cpu1_p0_tx_buf_c_dn(11)';
NODE_NAME     C6652 1
 '@T6G_MB_LIB.T6G(SCH_1):PAGE439_I94@PURE_QUANTA.Q_CAP_DIFFBUS(CHIPS)':
 '1': CDS_PINID='\1\';
NODE_NAME     J111 H4
 '@T6G_MB_LIB.T6G(SCH_1):PAGE328_I76@PURE_QUANTA.CONN112_10137002101LF(CHIPS)':
 'H4': CDS_PINID='H4';
NET_NAME
'P5E_CPU1_P0_TX_BUF_C_DN<12>'
 '@T6G_MB_LIB.T6G(SCH_1):P5E_CPU1_P0_TX_BUF_C_DN'<12>:
 C_SIGNAL='@t6g_mb_lib.t6g(sch_1):p5e_cpu1_p0_tx_buf_c_dn(12)';
NODE_NAME     C6654 1
 '@T6G_MB_LIB.T6G(SCH_1):PAGE439_I92@PURE_QUANTA.Q_CAP_DIFFBUS(CHIPS)':
 '1': CDS_PINID='\1\';
NODE_NAME     J111 I5
 '@T6G_MB_LIB.T6G(SCH_1):PAGE328_I38@PURE_QUANTA.CONN112_10137002101LF(CHIPS)':
 'I5': CDS_PINID='I5';
NET_NAME
'P5E_CPU1_P0_TX_BUF_C_DN<13>'
 '@T6G_MB_LIB.T6G(SCH_1):P5E_CPU1_P0_TX_BUF_C_DN'<13>:
 C_SIGNAL='@t6g_mb_lib.t6g(sch_1):p5e_cpu1_p0_tx_buf_c_dn(13)';
NODE_NAME     C6656 1
 '@T6G_MB_LIB.T6G(SCH_1):PAGE439_I90@PURE_QUANTA.Q_CAP_DIFFBUS(CHIPS)':
 '1': CDS_PINID='\1\';
NODE_NAME     J111 H6
 '@T6G_MB_LIB.T6G(SCH_1):PAGE328_I38@PURE_QUANTA.CONN112_10137002101LF(CHIPS)':
 'H6': CDS_PINID='H6';
NET_NAME
'P5E_CPU1_P0_TX_BUF_C_DN<14>'
 '@T6G_MB_LIB.T6G(SCH_1):P5E_CPU1_P0_TX_BUF_C_DN'<14>:
 C_SIGNAL='@t6g_mb_lib.t6g(sch_1):p5e_cpu1_p0_tx_buf_c_dn(14)';
NODE_NAME     C6658 1
 '@T6G_MB_LIB.T6G(SCH_1):PAGE439_I88@PURE_QUANTA.Q_CAP_DIFFBUS(CHIPS)':
 '1': CDS_PINID='\1\';
NODE_NAME     J111 I7
 '@T6G_MB_LIB.T6G(SCH_1):PAGE328_I38@PURE_QUANTA.CONN112_10137002101LF(CHIPS)':
 'I7': CDS_PINID='I7';
NET_NAME
'P5E_CPU1_P0_TX_BUF_C_DN<15>'
 '@T6G_MB_LIB.T6G(SCH_1):P5E_CPU1_P0_TX_BUF_C_DN'<15>:
 C_SIGNAL='@t6g_mb_lib.t6g(sch_1):p5e_cpu1_p0_tx_buf_c_dn(15)';
NODE_NAME     C6660 1
 '@T6G_MB_LIB.T6G(SCH_1):PAGE439_I86@PURE_QUANTA.Q_CAP_DIFFBUS(CHIPS)':
 '1': CDS_PINID='\1\';
NODE_NAME     J111 H8
 '@T6G_MB_LIB.T6G(SCH_1):PAGE328_I38@PURE_QUANTA.CONN112_10137002101LF(CHIPS)':
 'H8': CDS_PINID='H8';
NET_NAME
'P5E_CPU1_P0_TX_BUF_C_DN<1>'
 '@T6G_MB_LIB.T6G(SCH_1):P5E_CPU1_P0_TX_BUF_C_DN'<1>:
 C_SIGNAL='@t6g_mb_lib.t6g(sch_1):p5e_cpu1_p0_tx_buf_c_dn(1)';
NODE_NAME     C6632 1
 '@T6G_MB_LIB.T6G(SCH_1):PAGE439_I44@PURE_QUANTA.Q_CAP_DIFFBUS(CHIPS)':
 '1': CDS_PINID='\1\';
NODE_NAME     J112 H2
 '@T6G_MB_LIB.T6G(SCH_1):PAGE329_I102@PURE_QUANTA.CONN160_10131762101LF(CHIPS)':
 'H2': CDS_PINID='H2';
NET_NAME
'P5E_CPU1_P0_TX_BUF_C_DN<2>'
 '@T6G_MB_LIB.T6G(SCH_1):P5E_CPU1_P0_TX_BUF_C_DN'<2>:
 C_SIGNAL='@t6g_mb_lib.t6g(sch_1):p5e_cpu1_p0_tx_buf_c_dn(2)';
NODE_NAME     C6634 1
 '@T6G_MB_LIB.T6G(SCH_1):PAGE439_I26@PURE_QUANTA.Q_CAP_DIFFBUS(CHIPS)':
 '1': CDS_PINID='\1\';
NODE_NAME     J112 I3
 '@T6G_MB_LIB.T6G(SCH_1):PAGE329_I102@PURE_QUANTA.CONN160_10131762101LF(CHIPS)':
 'I3': CDS_PINID='I3';
NET_NAME
'P5E_CPU1_P0_TX_BUF_C_DN<3>'
 '@T6G_MB_LIB.T6G(SCH_1):P5E_CPU1_P0_TX_BUF_C_DN'<3>:
 C_SIGNAL='@t6g_mb_lib.t6g(sch_1):p5e_cpu1_p0_tx_buf_c_dn(3)';
NODE_NAME     C6636 1
 '@T6G_MB_LIB.T6G(SCH_1):PAGE439_I24@PURE_QUANTA.Q_CAP_DIFFBUS(CHIPS)':
 '1': CDS_PINID='\1\';
NODE_NAME     J112 H4
 '@T6G_MB_LIB.T6G(SCH_1):PAGE329_I102@PURE_QUANTA.CONN160_10131762101LF(CHIPS)':
 'H4': CDS_PINID='H4';
NET_NAME
'P5E_CPU1_P0_TX_BUF_C_DN<4>'
 '@T6G_MB_LIB.T6G(SCH_1):P5E_CPU1_P0_TX_BUF_C_DN'<4>:
 C_SIGNAL='@t6g_mb_lib.t6g(sch_1):p5e_cpu1_p0_tx_buf_c_dn(4)';
NODE_NAME     C6638 1
 '@T6G_MB_LIB.T6G(SCH_1):PAGE439_I23@PURE_QUANTA.Q_CAP_DIFFBUS(CHIPS)':
 '1': CDS_PINID='\1\';
NODE_NAME     J112 I5
 '@T6G_MB_LIB.T6G(SCH_1):PAGE329_I7@PURE_QUANTA.CONN160_10131762101LF(CHIPS)':
 'I5': CDS_PINID='I5';
NET_NAME
'P5E_CPU1_P0_TX_BUF_C_DN<5>'
 '@T6G_MB_LIB.T6G(SCH_1):P5E_CPU1_P0_TX_BUF_C_DN'<5>:
 C_SIGNAL='@t6g_mb_lib.t6g(sch_1):p5e_cpu1_p0_tx_buf_c_dn(5)';
NODE_NAME     C6640 1
 '@T6G_MB_LIB.T6G(SCH_1):PAGE439_I21@PURE_QUANTA.Q_CAP_DIFFBUS(CHIPS)':
 '1': CDS_PINID='\1\';
NODE_NAME     J112 H6
 '@T6G_MB_LIB.T6G(SCH_1):PAGE329_I7@PURE_QUANTA.CONN160_10131762101LF(CHIPS)':
 'H6': CDS_PINID='H6';
NET_NAME
'P5E_CPU1_P0_TX_BUF_C_DN<6>'
 '@T6G_MB_LIB.T6G(SCH_1):P5E_CPU1_P0_TX_BUF_C_DN'<6>:
 C_SIGNAL='@t6g_mb_lib.t6g(sch_1):p5e_cpu1_p0_tx_buf_c_dn(6)';
NODE_NAME     C6642 1
 '@T6G_MB_LIB.T6G(SCH_1):PAGE439_I19@PURE_QUANTA.Q_CAP_DIFFBUS(CHIPS)':
 '1': CDS_PINID='\1\';
NODE_NAME     J112 I7
 '@T6G_MB_LIB.T6G(SCH_1):PAGE329_I7@PURE_QUANTA.CONN160_10131762101LF(CHIPS)':
 'I7': CDS_PINID='I7';
NET_NAME
'P5E_CPU1_P0_TX_BUF_C_DN<7>'
 '@T6G_MB_LIB.T6G(SCH_1):P5E_CPU1_P0_TX_BUF_C_DN'<7>:
 C_SIGNAL='@t6g_mb_lib.t6g(sch_1):p5e_cpu1_p0_tx_buf_c_dn(7)';
NODE_NAME     C6644 1
 '@T6G_MB_LIB.T6G(SCH_1):PAGE439_I15@PURE_QUANTA.Q_CAP_DIFFBUS(CHIPS)':
 '1': CDS_PINID='\1\';
NODE_NAME     J112 H8
 '@T6G_MB_LIB.T6G(SCH_1):PAGE329_I7@PURE_QUANTA.CONN160_10131762101LF(CHIPS)':
 'H8': CDS_PINID='H8';
NET_NAME
'P5E_CPU1_P0_TX_BUF_C_DN<8>'
 '@T6G_MB_LIB.T6G(SCH_1):P5E_CPU1_P0_TX_BUF_C_DN'<8>:
 C_SIGNAL='@t6g_mb_lib.t6g(sch_1):p5e_cpu1_p0_tx_buf_c_dn(8)';
NODE_NAME     C6646 1
 '@T6G_MB_LIB.T6G(SCH_1):PAGE439_I104@PURE_QUANTA.Q_CAP_DIFFBUS(CHIPS)':
 '1': CDS_PINID='\1\';
NODE_NAME     J111 I1
 '@T6G_MB_LIB.T6G(SCH_1):PAGE328_I76@PURE_QUANTA.CONN112_10137002101LF(CHIPS)':
 'I1': CDS_PINID='I1';
NET_NAME
'P5E_CPU1_P0_TX_BUF_C_DN<9>'
 '@T6G_MB_LIB.T6G(SCH_1):P5E_CPU1_P0_TX_BUF_C_DN'<9>:
 C_SIGNAL='@t6g_mb_lib.t6g(sch_1):p5e_cpu1_p0_tx_buf_c_dn(9)';
NODE_NAME     C6648 1
 '@T6G_MB_LIB.T6G(SCH_1):PAGE439_I103@PURE_QUANTA.Q_CAP_DIFFBUS(CHIPS)':
 '1': CDS_PINID='\1\';
NODE_NAME     J111 H2
 '@T6G_MB_LIB.T6G(SCH_1):PAGE328_I76@PURE_QUANTA.CONN112_10137002101LF(CHIPS)':
 'H2': CDS_PINID='H2';
NET_NAME
'P5E_CPU1_P0_TX_BUF_C_DP<0>'
 '@T6G_MB_LIB.T6G(SCH_1):P5E_CPU1_P0_TX_BUF_C_DP'<0>:
 C_SIGNAL='@t6g_mb_lib.t6g(sch_1):p5e_cpu1_p0_tx_buf_c_dp(0)';
NODE_NAME     C6629 1
 '@T6G_MB_LIB.T6G(SCH_1):PAGE439_I46@PURE_QUANTA.Q_CAP_DIFFBUS(CHIPS)':
 '1': CDS_PINID='\1\';
NODE_NAME     J112 J1
 '@T6G_MB_LIB.T6G(SCH_1):PAGE329_I102@PURE_QUANTA.CONN160_10131762101LF(CHIPS)':
 'J1': CDS_PINID='J1';
NET_NAME
'P5E_CPU1_P0_TX_BUF_C_DP<10>'
 '@T6G_MB_LIB.T6G(SCH_1):P5E_CPU1_P0_TX_BUF_C_DP'<10>:
 C_SIGNAL='@t6g_mb_lib.t6g(sch_1):p5e_cpu1_p0_tx_buf_c_dp(10)';
NODE_NAME     C6649 1
 '@T6G_MB_LIB.T6G(SCH_1):PAGE439_I96@PURE_QUANTA.Q_CAP_DIFFBUS(CHIPS)':
 '1': CDS_PINID='\1\';
NODE_NAME     J111 J3
 '@T6G_MB_LIB.T6G(SCH_1):PAGE328_I76@PURE_QUANTA.CONN112_10137002101LF(CHIPS)':
 'J3': CDS_PINID='J3';
NET_NAME
'P5E_CPU1_P0_TX_BUF_C_DP<11>'
 '@T6G_MB_LIB.T6G(SCH_1):P5E_CPU1_P0_TX_BUF_C_DP'<11>:
 C_SIGNAL='@t6g_mb_lib.t6g(sch_1):p5e_cpu1_p0_tx_buf_c_dp(11)';
NODE_NAME     C6651 1
 '@T6G_MB_LIB.T6G(SCH_1):PAGE439_I95@PURE_QUANTA.Q_CAP_DIFFBUS(CHIPS)':
 '1': CDS_PINID='\1\';
NODE_NAME     J111 I4
 '@T6G_MB_LIB.T6G(SCH_1):PAGE328_I76@PURE_QUANTA.CONN112_10137002101LF(CHIPS)':
 'I4': CDS_PINID='I4';
NET_NAME
'P5E_CPU1_P0_TX_BUF_C_DP<12>'
 '@T6G_MB_LIB.T6G(SCH_1):P5E_CPU1_P0_TX_BUF_C_DP'<12>:
 C_SIGNAL='@t6g_mb_lib.t6g(sch_1):p5e_cpu1_p0_tx_buf_c_dp(12)';
NODE_NAME     C6653 1
 '@T6G_MB_LIB.T6G(SCH_1):PAGE439_I93@PURE_QUANTA.Q_CAP_DIFFBUS(CHIPS)':
 '1': CDS_PINID='\1\';
NODE_NAME     J111 J5
 '@T6G_MB_LIB.T6G(SCH_1):PAGE328_I38@PURE_QUANTA.CONN112_10137002101LF(CHIPS)':
 'J5': CDS_PINID='J5';
NET_NAME
'P5E_CPU1_P0_TX_BUF_C_DP<13>'
 '@T6G_MB_LIB.T6G(SCH_1):P5E_CPU1_P0_TX_BUF_C_DP'<13>:
 C_SIGNAL='@t6g_mb_lib.t6g(sch_1):p5e_cpu1_p0_tx_buf_c_dp(13)';
NODE_NAME     C6655 1
 '@T6G_MB_LIB.T6G(SCH_1):PAGE439_I91@PURE_QUANTA.Q_CAP_DIFFBUS(CHIPS)':
 '1': CDS_PINID='\1\';
NODE_NAME     J111 I6
 '@T6G_MB_LIB.T6G(SCH_1):PAGE328_I38@PURE_QUANTA.CONN112_10137002101LF(CHIPS)':
 'I6': CDS_PINID='I6';
NET_NAME
'P5E_CPU1_P0_TX_BUF_C_DP<14>'
 '@T6G_MB_LIB.T6G(SCH_1):P5E_CPU1_P0_TX_BUF_C_DP'<14>:
 C_SIGNAL='@t6g_mb_lib.t6g(sch_1):p5e_cpu1_p0_tx_buf_c_dp(14)';
NODE_NAME     C6657 1
 '@T6G_MB_LIB.T6G(SCH_1):PAGE439_I89@PURE_QUANTA.Q_CAP_DIFFBUS(CHIPS)':
 '1': CDS_PINID='\1\';
NODE_NAME     J111 J7
 '@T6G_MB_LIB.T6G(SCH_1):PAGE328_I38@PURE_QUANTA.CONN112_10137002101LF(CHIPS)':
 'J7': CDS_PINID='J7';
NET_NAME
'P5E_CPU1_P0_TX_BUF_C_DP<15>'
 '@T6G_MB_LIB.T6G(SCH_1):P5E_CPU1_P0_TX_BUF_C_DP'<15>:
 C_SIGNAL='@t6g_mb_lib.t6g(sch_1):p5e_cpu1_p0_tx_buf_c_dp(15)';
NODE_NAME     C6659 1
 '@T6G_MB_LIB.T6G(SCH_1):PAGE439_I87@PURE_QUANTA.Q_CAP_DIFFBUS(CHIPS)':
 '1': CDS_PINID='\1\';
NODE_NAME     J111 I8
 '@T6G_MB_LIB.T6G(SCH_1):PAGE328_I38@PURE_QUANTA.CONN112_10137002101LF(CHIPS)':
 'I8': CDS_PINID='I8';
NET_NAME
'P5E_CPU1_P0_TX_BUF_C_DP<1>'
 '@T6G_MB_LIB.T6G(SCH_1):P5E_CPU1_P0_TX_BUF_C_DP'<1>:
 C_SIGNAL='@t6g_mb_lib.t6g(sch_1):p5e_cpu1_p0_tx_buf_c_dp(1)';
NODE_NAME     C6631 1
 '@T6G_MB_LIB.T6G(SCH_1):PAGE439_I45@PURE_QUANTA.Q_CAP_DIFFBUS(CHIPS)':
 '1': CDS_PINID='\1\';
NODE_NAME     J112 I2
 '@T6G_MB_LIB.T6G(SCH_1):PAGE329_I102@PURE_QUANTA.CONN160_10131762101LF(CHIPS)':
 'I2': CDS_PINID='I2';
NET_NAME
'P5E_CPU1_P0_TX_BUF_C_DP<2>'
 '@T6G_MB_LIB.T6G(SCH_1):P5E_CPU1_P0_TX_BUF_C_DP'<2>:
 C_SIGNAL='@t6g_mb_lib.t6g(sch_1):p5e_cpu1_p0_tx_buf_c_dp(2)';
NODE_NAME     C6633 1
 '@T6G_MB_LIB.T6G(SCH_1):PAGE439_I27@PURE_QUANTA.Q_CAP_DIFFBUS(CHIPS)':
 '1': CDS_PINID='\1\';
NODE_NAME     J112 J3
 '@T6G_MB_LIB.T6G(SCH_1):PAGE329_I102@PURE_QUANTA.CONN160_10131762101LF(CHIPS)':
 'J3': CDS_PINID='J3';
NET_NAME
'P5E_CPU1_P0_TX_BUF_C_DP<3>'
 '@T6G_MB_LIB.T6G(SCH_1):P5E_CPU1_P0_TX_BUF_C_DP'<3>:
 C_SIGNAL='@t6g_mb_lib.t6g(sch_1):p5e_cpu1_p0_tx_buf_c_dp(3)';
NODE_NAME     C6635 1
 '@T6G_MB_LIB.T6G(SCH_1):PAGE439_I25@PURE_QUANTA.Q_CAP_DIFFBUS(CHIPS)':
 '1': CDS_PINID='\1\';
NODE_NAME     J112 I4
 '@T6G_MB_LIB.T6G(SCH_1):PAGE329_I102@PURE_QUANTA.CONN160_10131762101LF(CHIPS)':
 'I4': CDS_PINID='I4';
NET_NAME
'P5E_CPU1_P0_TX_BUF_C_DP<4>'
 '@T6G_MB_LIB.T6G(SCH_1):P5E_CPU1_P0_TX_BUF_C_DP'<4>:
 C_SIGNAL='@t6g_mb_lib.t6g(sch_1):p5e_cpu1_p0_tx_buf_c_dp(4)';
NODE_NAME     C6637 1
 '@T6G_MB_LIB.T6G(SCH_1):PAGE439_I22@PURE_QUANTA.Q_CAP_DIFFBUS(CHIPS)':
 '1': CDS_PINID='\1\';
NODE_NAME     J112 J5
 '@T6G_MB_LIB.T6G(SCH_1):PAGE329_I7@PURE_QUANTA.CONN160_10131762101LF(CHIPS)':
 'J5': CDS_PINID='J5';
NET_NAME
'P5E_CPU1_P0_TX_BUF_C_DP<5>'
 '@T6G_MB_LIB.T6G(SCH_1):P5E_CPU1_P0_TX_BUF_C_DP'<5>:
 C_SIGNAL='@t6g_mb_lib.t6g(sch_1):p5e_cpu1_p0_tx_buf_c_dp(5)';
NODE_NAME     C6639 1
 '@T6G_MB_LIB.T6G(SCH_1):PAGE439_I20@PURE_QUANTA.Q_CAP_DIFFBUS(CHIPS)':
 '1': CDS_PINID='\1\';
NODE_NAME     J112 I6
 '@T6G_MB_LIB.T6G(SCH_1):PAGE329_I7@PURE_QUANTA.CONN160_10131762101LF(CHIPS)':
 'I6': CDS_PINID='I6';
NET_NAME
'P5E_CPU1_P0_TX_BUF_C_DP<6>'
 '@T6G_MB_LIB.T6G(SCH_1):P5E_CPU1_P0_TX_BUF_C_DP'<6>:
 C_SIGNAL='@t6g_mb_lib.t6g(sch_1):p5e_cpu1_p0_tx_buf_c_dp(6)';
NODE_NAME     C6641 1
 '@T6G_MB_LIB.T6G(SCH_1):PAGE439_I18@PURE_QUANTA.Q_CAP_DIFFBUS(CHIPS)':
 '1': CDS_PINID='\1\';
NODE_NAME     J112 J7
 '@T6G_MB_LIB.T6G(SCH_1):PAGE329_I7@PURE_QUANTA.CONN160_10131762101LF(CHIPS)':
 'J7': CDS_PINID='J7';
NET_NAME
'P5E_CPU1_P0_TX_BUF_C_DP<7>'
 '@T6G_MB_LIB.T6G(SCH_1):P5E_CPU1_P0_TX_BUF_C_DP'<7>:
 C_SIGNAL='@t6g_mb_lib.t6g(sch_1):p5e_cpu1_p0_tx_buf_c_dp(7)';
NODE_NAME     C6643 1
 '@T6G_MB_LIB.T6G(SCH_1):PAGE439_I16@PURE_QUANTA.Q_CAP_DIFFBUS(CHIPS)':
 '1': CDS_PINID='\1\';
NODE_NAME     J112 I8
 '@T6G_MB_LIB.T6G(SCH_1):PAGE329_I7@PURE_QUANTA.CONN160_10131762101LF(CHIPS)':
 'I8': CDS_PINID='I8';
NET_NAME
'P5E_CPU1_P0_TX_BUF_C_DP<8>'
 '@T6G_MB_LIB.T6G(SCH_1):P5E_CPU1_P0_TX_BUF_C_DP'<8>:
 C_SIGNAL='@t6g_mb_lib.t6g(sch_1):p5e_cpu1_p0_tx_buf_c_dp(8)';
NODE_NAME     C6645 1
 '@T6G_MB_LIB.T6G(SCH_1):PAGE439_I105@PURE_QUANTA.Q_CAP_DIFFBUS(CHIPS)':
 '1': CDS_PINID='\1\';
NODE_NAME     J111 J1
 '@T6G_MB_LIB.T6G(SCH_1):PAGE328_I76@PURE_QUANTA.CONN112_10137002101LF(CHIPS)':
 'J1': CDS_PINID='J1';
NET_NAME
'P5E_CPU1_P0_TX_BUF_C_DP<9>'
 '@T6G_MB_LIB.T6G(SCH_1):P5E_CPU1_P0_TX_BUF_C_DP'<9>:
 C_SIGNAL='@t6g_mb_lib.t6g(sch_1):p5e_cpu1_p0_tx_buf_c_dp(9)';
NODE_NAME     C6647 1
 '@T6G_MB_LIB.T6G(SCH_1):PAGE439_I102@PURE_QUANTA.Q_CAP_DIFFBUS(CHIPS)':
 '1': CDS_PINID='\1\';
NODE_NAME     J111 I2
 '@T6G_MB_LIB.T6G(SCH_1):PAGE328_I76@PURE_QUANTA.CONN112_10137002101LF(CHIPS)':
 'I2': CDS_PINID='I2';
NET_NAME
'P5E_CPU1_P0_TX_BUF_DN<0>'
 '@T6G_MB_LIB.T6G(SCH_1):P5E_CPU1_P0_TX_BUF_DN'<0>:
 C_SIGNAL='@t6g_mb_lib.t6g(sch_1):p5e_cpu1_p0_tx_buf_dn(0)';
NODE_NAME     C6630 2
 '@T6G_MB_LIB.T6G(SCH_1):PAGE439_I47@PURE_QUANTA.Q_CAP_DIFFBUS(CHIPS)':
 '2': CDS_PINID='\2\';
NODE_NAME     U6014 EW10
 '@T6G_MB_LIB.T6G(SCH_1):PAGE439_I142@PURE_QUANTA.PT5161LRS(CHIPS)':
 'B_PETN15': CDS_PINID='B_PETN15';
NET_NAME
'P5E_CPU1_P0_TX_BUF_DN<10>'
 '@T6G_MB_LIB.T6G(SCH_1):P5E_CPU1_P0_TX_BUF_DN'<10>:
 C_SIGNAL='@t6g_mb_lib.t6g(sch_1):p5e_cpu1_p0_tx_buf_dn(10)';
NODE_NAME     U6014 BJ10
 '@T6G_MB_LIB.T6G(SCH_1):PAGE439_I43@PURE_QUANTA.PT5161LRS(CHIPS)':
 'B_PETN5': CDS_PINID='B_PETN5';
NODE_NAME     C6650 2
 '@T6G_MB_LIB.T6G(SCH_1):PAGE439_I97@PURE_QUANTA.Q_CAP_DIFFBUS(CHIPS)':
 '2': CDS_PINID='\2\';
NET_NAME
'P5E_CPU1_P0_TX_BUF_DN<11>'
 '@T6G_MB_LIB.T6G(SCH_1):P5E_CPU1_P0_TX_BUF_DN'<11>:
 C_SIGNAL='@t6g_mb_lib.t6g(sch_1):p5e_cpu1_p0_tx_buf_dn(11)';
NODE_NAME     U6014 BB10
 '@T6G_MB_LIB.T6G(SCH_1):PAGE439_I43@PURE_QUANTA.PT5161LRS(CHIPS)':
 'B_PETN4': CDS_PINID='B_PETN4';
NODE_NAME     C6652 2
 '@T6G_MB_LIB.T6G(SCH_1):PAGE439_I94@PURE_QUANTA.Q_CAP_DIFFBUS(CHIPS)':
 '2': CDS_PINID='\2\';
NET_NAME
'P5E_CPU1_P0_TX_BUF_DN<12>'
 '@T6G_MB_LIB.T6G(SCH_1):P5E_CPU1_P0_TX_BUF_DN'<12>:
 C_SIGNAL='@t6g_mb_lib.t6g(sch_1):p5e_cpu1_p0_tx_buf_dn(12)';
NODE_NAME     U6014 AR10
 '@T6G_MB_LIB.T6G(SCH_1):PAGE439_I43@PURE_QUANTA.PT5161LRS(CHIPS)':
 'B_PETN3': CDS_PINID='B_PETN3';
NODE_NAME     C6654 2
 '@T6G_MB_LIB.T6G(SCH_1):PAGE439_I92@PURE_QUANTA.Q_CAP_DIFFBUS(CHIPS)':
 '2': CDS_PINID='\2\';
NET_NAME
'P5E_CPU1_P0_TX_BUF_DN<13>'
 '@T6G_MB_LIB.T6G(SCH_1):P5E_CPU1_P0_TX_BUF_DN'<13>:
 C_SIGNAL='@t6g_mb_lib.t6g(sch_1):p5e_cpu1_p0_tx_buf_dn(13)';
NODE_NAME     U6014 AH10
 '@T6G_MB_LIB.T6G(SCH_1):PAGE439_I43@PURE_QUANTA.PT5161LRS(CHIPS)':
 'B_PETN2': CDS_PINID='B_PETN2';
NODE_NAME     C6656 2
 '@T6G_MB_LIB.T6G(SCH_1):PAGE439_I90@PURE_QUANTA.Q_CAP_DIFFBUS(CHIPS)':
 '2': CDS_PINID='\2\';
NET_NAME
'P5E_CPU1_P0_TX_BUF_DN<14>'
 '@T6G_MB_LIB.T6G(SCH_1):P5E_CPU1_P0_TX_BUF_DN'<14>:
 C_SIGNAL='@t6g_mb_lib.t6g(sch_1):p5e_cpu1_p0_tx_buf_dn(14)';
NODE_NAME     U6014 AA10
 '@T6G_MB_LIB.T6G(SCH_1):PAGE439_I43@PURE_QUANTA.PT5161LRS(CHIPS)':
 'B_PETN1': CDS_PINID='B_PETN1';
NODE_NAME     C6658 2
 '@T6G_MB_LIB.T6G(SCH_1):PAGE439_I88@PURE_QUANTA.Q_CAP_DIFFBUS(CHIPS)':
 '2': CDS_PINID='\2\';
NET_NAME
'P5E_CPU1_P0_TX_BUF_DN<15>'
 '@T6G_MB_LIB.T6G(SCH_1):P5E_CPU1_P0_TX_BUF_DN'<15>:
 C_SIGNAL='@t6g_mb_lib.t6g(sch_1):p5e_cpu1_p0_tx_buf_dn(15)';
NODE_NAME     U6014 P10
 '@T6G_MB_LIB.T6G(SCH_1):PAGE439_I43@PURE_QUANTA.PT5161LRS(CHIPS)':
 'B_PETN0': CDS_PINID='B_PETN0';
NODE_NAME     C6660 2
 '@T6G_MB_LIB.T6G(SCH_1):PAGE439_I86@PURE_QUANTA.Q_CAP_DIFFBUS(CHIPS)':
 '2': CDS_PINID='\2\';
NET_NAME
'P5E_CPU1_P0_TX_BUF_DN<1>'
 '@T6G_MB_LIB.T6G(SCH_1):P5E_CPU1_P0_TX_BUF_DN'<1>:
 C_SIGNAL='@t6g_mb_lib.t6g(sch_1):p5e_cpu1_p0_tx_buf_dn(1)';
NODE_NAME     C6632 2
 '@T6G_MB_LIB.T6G(SCH_1):PAGE439_I44@PURE_QUANTA.Q_CAP_DIFFBUS(CHIPS)':
 '2': CDS_PINID='\2\';
NODE_NAME     U6014 EM10
 '@T6G_MB_LIB.T6G(SCH_1):PAGE439_I142@PURE_QUANTA.PT5161LRS(CHIPS)':
 'B_PETN14': CDS_PINID='B_PETN14';
NET_NAME
'P5E_CPU1_P0_TX_BUF_DN<2>'
 '@T6G_MB_LIB.T6G(SCH_1):P5E_CPU1_P0_TX_BUF_DN'<2>:
 C_SIGNAL='@t6g_mb_lib.t6g(sch_1):p5e_cpu1_p0_tx_buf_dn(2)';
NODE_NAME     C6634 2
 '@T6G_MB_LIB.T6G(SCH_1):PAGE439_I26@PURE_QUANTA.Q_CAP_DIFFBUS(CHIPS)':
 '2': CDS_PINID='\2\';
NODE_NAME     U6014 EE10
 '@T6G_MB_LIB.T6G(SCH_1):PAGE439_I142@PURE_QUANTA.PT5161LRS(CHIPS)':
 'B_PETN13': CDS_PINID='B_PETN13';
NET_NAME
'P5E_CPU1_P0_TX_BUF_DN<3>'
 '@T6G_MB_LIB.T6G(SCH_1):P5E_CPU1_P0_TX_BUF_DN'<3>:
 C_SIGNAL='@t6g_mb_lib.t6g(sch_1):p5e_cpu1_p0_tx_buf_dn(3)';
NODE_NAME     C6636 2
 '@T6G_MB_LIB.T6G(SCH_1):PAGE439_I24@PURE_QUANTA.Q_CAP_DIFFBUS(CHIPS)':
 '2': CDS_PINID='\2\';
NODE_NAME     U6014 DV10
 '@T6G_MB_LIB.T6G(SCH_1):PAGE439_I142@PURE_QUANTA.PT5161LRS(CHIPS)':
 'B_PETN12': CDS_PINID='B_PETN12';
NET_NAME
'P5E_CPU1_P0_TX_BUF_DN<4>'
 '@T6G_MB_LIB.T6G(SCH_1):P5E_CPU1_P0_TX_BUF_DN'<4>:
 C_SIGNAL='@t6g_mb_lib.t6g(sch_1):p5e_cpu1_p0_tx_buf_dn(4)';
NODE_NAME     C6638 2
 '@T6G_MB_LIB.T6G(SCH_1):PAGE439_I23@PURE_QUANTA.Q_CAP_DIFFBUS(CHIPS)':
 '2': CDS_PINID='\2\';
NODE_NAME     U6014 DL10
 '@T6G_MB_LIB.T6G(SCH_1):PAGE439_I142@PURE_QUANTA.PT5161LRS(CHIPS)':
 'B_PETN11': CDS_PINID='B_PETN11';
NET_NAME
'P5E_CPU1_P0_TX_BUF_DN<5>'
 '@T6G_MB_LIB.T6G(SCH_1):P5E_CPU1_P0_TX_BUF_DN'<5>:
 C_SIGNAL='@t6g_mb_lib.t6g(sch_1):p5e_cpu1_p0_tx_buf_dn(5)';
NODE_NAME     C6640 2
 '@T6G_MB_LIB.T6G(SCH_1):PAGE439_I21@PURE_QUANTA.Q_CAP_DIFFBUS(CHIPS)':
 '2': CDS_PINID='\2\';
NODE_NAME     U6014 DD10
 '@T6G_MB_LIB.T6G(SCH_1):PAGE439_I142@PURE_QUANTA.PT5161LRS(CHIPS)':
 'B_PETN10': CDS_PINID='B_PETN10';
NET_NAME
'P5E_CPU1_P0_TX_BUF_DN<6>'
 '@T6G_MB_LIB.T6G(SCH_1):P5E_CPU1_P0_TX_BUF_DN'<6>:
 C_SIGNAL='@t6g_mb_lib.t6g(sch_1):p5e_cpu1_p0_tx_buf_dn(6)';
NODE_NAME     C6642 2
 '@T6G_MB_LIB.T6G(SCH_1):PAGE439_I19@PURE_QUANTA.Q_CAP_DIFFBUS(CHIPS)':
 '2': CDS_PINID='\2\';
NODE_NAME     U6014 CU10
 '@T6G_MB_LIB.T6G(SCH_1):PAGE439_I142@PURE_QUANTA.PT5161LRS(CHIPS)':
 'B_PETN9': CDS_PINID='B_PETN9';
NET_NAME
'P5E_CPU1_P0_TX_BUF_DN<7>'
 '@T6G_MB_LIB.T6G(SCH_1):P5E_CPU1_P0_TX_BUF_DN'<7>:
 C_SIGNAL='@t6g_mb_lib.t6g(sch_1):p5e_cpu1_p0_tx_buf_dn(7)';
NODE_NAME     C6644 2
 '@T6G_MB_LIB.T6G(SCH_1):PAGE439_I15@PURE_QUANTA.Q_CAP_DIFFBUS(CHIPS)':
 '2': CDS_PINID='\2\';
NODE_NAME     U6014 CK10
 '@T6G_MB_LIB.T6G(SCH_1):PAGE439_I142@PURE_QUANTA.PT5161LRS(CHIPS)':
 'B_PETN8': CDS_PINID='B_PETN8';
NET_NAME
'P5E_CPU1_P0_TX_BUF_DN<8>'
 '@T6G_MB_LIB.T6G(SCH_1):P5E_CPU1_P0_TX_BUF_DN'<8>:
 C_SIGNAL='@t6g_mb_lib.t6g(sch_1):p5e_cpu1_p0_tx_buf_dn(8)';
NODE_NAME     U6014 CC10
 '@T6G_MB_LIB.T6G(SCH_1):PAGE439_I43@PURE_QUANTA.PT5161LRS(CHIPS)':
 'B_PETN7': CDS_PINID='B_PETN7';
NODE_NAME     C6646 2
 '@T6G_MB_LIB.T6G(SCH_1):PAGE439_I104@PURE_QUANTA.Q_CAP_DIFFBUS(CHIPS)':
 '2': CDS_PINID='\2\';
NET_NAME
'P5E_CPU1_P0_TX_BUF_DN<9>'
 '@T6G_MB_LIB.T6G(SCH_1):P5E_CPU1_P0_TX_BUF_DN'<9>:
 C_SIGNAL='@t6g_mb_lib.t6g(sch_1):p5e_cpu1_p0_tx_buf_dn(9)';
NODE_NAME     U6014 BT10
 '@T6G_MB_LIB.T6G(SCH_1):PAGE439_I43@PURE_QUANTA.PT5161LRS(CHIPS)':
 'B_PETN6': CDS_PINID='B_PETN6';
NODE_NAME     C6648 2
 '@T6G_MB_LIB.T6G(SCH_1):PAGE439_I103@PURE_QUANTA.Q_CAP_DIFFBUS(CHIPS)':
 '2': CDS_PINID='\2\';
NET_NAME
'P5E_CPU1_P0_TX_BUF_DP<0>'
 '@T6G_MB_LIB.T6G(SCH_1):P5E_CPU1_P0_TX_BUF_DP'<0>:
 C_SIGNAL='@t6g_mb_lib.t6g(sch_1):p5e_cpu1_p0_tx_buf_dp(0)';
NODE_NAME     C6629 2
 '@T6G_MB_LIB.T6G(SCH_1):PAGE439_I46@PURE_QUANTA.Q_CAP_DIFFBUS(CHIPS)':
 '2': CDS_PINID='\2\';
NODE_NAME     U6014 EU7
 '@T6G_MB_LIB.T6G(SCH_1):PAGE439_I142@PURE_QUANTA.PT5161LRS(CHIPS)':
 'B_PETP15': CDS_PINID='B_PETP15';
NET_NAME
'P5E_CPU1_P0_TX_BUF_DP<10>'
 '@T6G_MB_LIB.T6G(SCH_1):P5E_CPU1_P0_TX_BUF_DP'<10>:
 C_SIGNAL='@t6g_mb_lib.t6g(sch_1):p5e_cpu1_p0_tx_buf_dp(10)';
NODE_NAME     U6014 BG7
 '@T6G_MB_LIB.T6G(SCH_1):PAGE439_I43@PURE_QUANTA.PT5161LRS(CHIPS)':
 'B_PETP5': CDS_PINID='B_PETP5';
NODE_NAME     C6649 2
 '@T6G_MB_LIB.T6G(SCH_1):PAGE439_I96@PURE_QUANTA.Q_CAP_DIFFBUS(CHIPS)':
 '2': CDS_PINID='\2\';
NET_NAME
'P5E_CPU1_P0_TX_BUF_DP<11>'
 '@T6G_MB_LIB.T6G(SCH_1):P5E_CPU1_P0_TX_BUF_DP'<11>:
 C_SIGNAL='@t6g_mb_lib.t6g(sch_1):p5e_cpu1_p0_tx_buf_dp(11)';
NODE_NAME     U6014 AY7
 '@T6G_MB_LIB.T6G(SCH_1):PAGE439_I43@PURE_QUANTA.PT5161LRS(CHIPS)':
 'B_PETP4': CDS_PINID='B_PETP4';
NODE_NAME     C6651 2
 '@T6G_MB_LIB.T6G(SCH_1):PAGE439_I95@PURE_QUANTA.Q_CAP_DIFFBUS(CHIPS)':
 '2': CDS_PINID='\2\';
NET_NAME
'P5E_CPU1_P0_TX_BUF_DP<12>'
 '@T6G_MB_LIB.T6G(SCH_1):P5E_CPU1_P0_TX_BUF_DP'<12>:
 C_SIGNAL='@t6g_mb_lib.t6g(sch_1):p5e_cpu1_p0_tx_buf_dp(12)';
NODE_NAME     U6014 AN7
 '@T6G_MB_LIB.T6G(SCH_1):PAGE439_I43@PURE_QUANTA.PT5161LRS(CHIPS)':
 'B_PETP3': CDS_PINID='B_PETP3';
NODE_NAME     C6653 2
 '@T6G_MB_LIB.T6G(SCH_1):PAGE439_I93@PURE_QUANTA.Q_CAP_DIFFBUS(CHIPS)':
 '2': CDS_PINID='\2\';
NET_NAME
'P5E_CPU1_P0_TX_BUF_DP<13>'
 '@T6G_MB_LIB.T6G(SCH_1):P5E_CPU1_P0_TX_BUF_DP'<13>:
 C_SIGNAL='@t6g_mb_lib.t6g(sch_1):p5e_cpu1_p0_tx_buf_dp(13)';
NODE_NAME     U6014 AF7
 '@T6G_MB_LIB.T6G(SCH_1):PAGE439_I43@PURE_QUANTA.PT5161LRS(CHIPS)':
 'B_PETP2': CDS_PINID='B_PETP2';
NODE_NAME     C6655 2
 '@T6G_MB_LIB.T6G(SCH_1):PAGE439_I91@PURE_QUANTA.Q_CAP_DIFFBUS(CHIPS)':
 '2': CDS_PINID='\2\';
NET_NAME
'P5E_CPU1_P0_TX_BUF_DP<14>'
 '@T6G_MB_LIB.T6G(SCH_1):P5E_CPU1_P0_TX_BUF_DP'<14>:
 C_SIGNAL='@t6g_mb_lib.t6g(sch_1):p5e_cpu1_p0_tx_buf_dp(14)';
NODE_NAME     U6014 W7
 '@T6G_MB_LIB.T6G(SCH_1):PAGE439_I43@PURE_QUANTA.PT5161LRS(CHIPS)':
 'B_PETP1': CDS_PINID='B_PETP1';
NODE_NAME     C6657 2
 '@T6G_MB_LIB.T6G(SCH_1):PAGE439_I89@PURE_QUANTA.Q_CAP_DIFFBUS(CHIPS)':
 '2': CDS_PINID='\2\';
NET_NAME
'P5E_CPU1_P0_TX_BUF_DP<15>'
 '@T6G_MB_LIB.T6G(SCH_1):P5E_CPU1_P0_TX_BUF_DP'<15>:
 C_SIGNAL='@t6g_mb_lib.t6g(sch_1):p5e_cpu1_p0_tx_buf_dp(15)';
NODE_NAME     U6014 M7
 '@T6G_MB_LIB.T6G(SCH_1):PAGE439_I43@PURE_QUANTA.PT5161LRS(CHIPS)':
 'B_PETP0': CDS_PINID='B_PETP0';
NODE_NAME     C6659 2
 '@T6G_MB_LIB.T6G(SCH_1):PAGE439_I87@PURE_QUANTA.Q_CAP_DIFFBUS(CHIPS)':
 '2': CDS_PINID='\2\';
NET_NAME
'P5E_CPU1_P0_TX_BUF_DP<1>'
 '@T6G_MB_LIB.T6G(SCH_1):P5E_CPU1_P0_TX_BUF_DP'<1>:
 C_SIGNAL='@t6g_mb_lib.t6g(sch_1):p5e_cpu1_p0_tx_buf_dp(1)';
NODE_NAME     C6631 2
 '@T6G_MB_LIB.T6G(SCH_1):PAGE439_I45@PURE_QUANTA.Q_CAP_DIFFBUS(CHIPS)':
 '2': CDS_PINID='\2\';
NODE_NAME     U6014 EK7
 '@T6G_MB_LIB.T6G(SCH_1):PAGE439_I142@PURE_QUANTA.PT5161LRS(CHIPS)':
 'B_PETP14': CDS_PINID='B_PETP14';
NET_NAME
'P5E_CPU1_P0_TX_BUF_DP<2>'
 '@T6G_MB_LIB.T6G(SCH_1):P5E_CPU1_P0_TX_BUF_DP'<2>:
 C_SIGNAL='@t6g_mb_lib.t6g(sch_1):p5e_cpu1_p0_tx_buf_dp(2)';
NODE_NAME     C6633 2
 '@T6G_MB_LIB.T6G(SCH_1):PAGE439_I27@PURE_QUANTA.Q_CAP_DIFFBUS(CHIPS)':
 '2': CDS_PINID='\2\';
NODE_NAME     U6014 EC7
 '@T6G_MB_LIB.T6G(SCH_1):PAGE439_I142@PURE_QUANTA.PT5161LRS(CHIPS)':
 'B_PETP13': CDS_PINID='B_PETP13';
NET_NAME
'P5E_CPU1_P0_TX_BUF_DP<3>'
 '@T6G_MB_LIB.T6G(SCH_1):P5E_CPU1_P0_TX_BUF_DP'<3>:
 C_SIGNAL='@t6g_mb_lib.t6g(sch_1):p5e_cpu1_p0_tx_buf_dp(3)';
NODE_NAME     C6635 2
 '@T6G_MB_LIB.T6G(SCH_1):PAGE439_I25@PURE_QUANTA.Q_CAP_DIFFBUS(CHIPS)':
 '2': CDS_PINID='\2\';
NODE_NAME     U6014 DT7
 '@T6G_MB_LIB.T6G(SCH_1):PAGE439_I142@PURE_QUANTA.PT5161LRS(CHIPS)':
 'B_PETP12': CDS_PINID='B_PETP12';
NET_NAME
'P5E_CPU1_P0_TX_BUF_DP<4>'
 '@T6G_MB_LIB.T6G(SCH_1):P5E_CPU1_P0_TX_BUF_DP'<4>:
 C_SIGNAL='@t6g_mb_lib.t6g(sch_1):p5e_cpu1_p0_tx_buf_dp(4)';
NODE_NAME     C6637 2
 '@T6G_MB_LIB.T6G(SCH_1):PAGE439_I22@PURE_QUANTA.Q_CAP_DIFFBUS(CHIPS)':
 '2': CDS_PINID='\2\';
NODE_NAME     U6014 DJ7
 '@T6G_MB_LIB.T6G(SCH_1):PAGE439_I142@PURE_QUANTA.PT5161LRS(CHIPS)':
 'B_PETP11': CDS_PINID='B_PETP11';
NET_NAME
'P5E_CPU1_P0_TX_BUF_DP<5>'
 '@T6G_MB_LIB.T6G(SCH_1):P5E_CPU1_P0_TX_BUF_DP'<5>:
 C_SIGNAL='@t6g_mb_lib.t6g(sch_1):p5e_cpu1_p0_tx_buf_dp(5)';
NODE_NAME     C6639 2
 '@T6G_MB_LIB.T6G(SCH_1):PAGE439_I20@PURE_QUANTA.Q_CAP_DIFFBUS(CHIPS)':
 '2': CDS_PINID='\2\';
NODE_NAME     U6014 DB7
 '@T6G_MB_LIB.T6G(SCH_1):PAGE439_I142@PURE_QUANTA.PT5161LRS(CHIPS)':
 'B_PETP10': CDS_PINID='B_PETP10';
NET_NAME
'P5E_CPU1_P0_TX_BUF_DP<6>'
 '@T6G_MB_LIB.T6G(SCH_1):P5E_CPU1_P0_TX_BUF_DP'<6>:
 C_SIGNAL='@t6g_mb_lib.t6g(sch_1):p5e_cpu1_p0_tx_buf_dp(6)';
NODE_NAME     C6641 2
 '@T6G_MB_LIB.T6G(SCH_1):PAGE439_I18@PURE_QUANTA.Q_CAP_DIFFBUS(CHIPS)':
 '2': CDS_PINID='\2\';
NODE_NAME     U6014 CR7
 '@T6G_MB_LIB.T6G(SCH_1):PAGE439_I142@PURE_QUANTA.PT5161LRS(CHIPS)':
 'B_PETP9': CDS_PINID='B_PETP9';
NET_NAME
'P5E_CPU1_P0_TX_BUF_DP<7>'
 '@T6G_MB_LIB.T6G(SCH_1):P5E_CPU1_P0_TX_BUF_DP'<7>:
 C_SIGNAL='@t6g_mb_lib.t6g(sch_1):p5e_cpu1_p0_tx_buf_dp(7)';
NODE_NAME     C6643 2
 '@T6G_MB_LIB.T6G(SCH_1):PAGE439_I16@PURE_QUANTA.Q_CAP_DIFFBUS(CHIPS)':
 '2': CDS_PINID='\2\';
NODE_NAME     U6014 CH7
 '@T6G_MB_LIB.T6G(SCH_1):PAGE439_I142@PURE_QUANTA.PT5161LRS(CHIPS)':
 'B_PETP8': CDS_PINID='B_PETP8';
NET_NAME
'P5E_CPU1_P0_TX_BUF_DP<8>'
 '@T6G_MB_LIB.T6G(SCH_1):P5E_CPU1_P0_TX_BUF_DP'<8>:
 C_SIGNAL='@t6g_mb_lib.t6g(sch_1):p5e_cpu1_p0_tx_buf_dp(8)';
NODE_NAME     U6014 CA7
 '@T6G_MB_LIB.T6G(SCH_1):PAGE439_I43@PURE_QUANTA.PT5161LRS(CHIPS)':
 'B_PETP7': CDS_PINID='B_PETP7';
NODE_NAME     C6645 2
 '@T6G_MB_LIB.T6G(SCH_1):PAGE439_I105@PURE_QUANTA.Q_CAP_DIFFBUS(CHIPS)':
 '2': CDS_PINID='\2\';
NET_NAME
'P5E_CPU1_P0_TX_BUF_DP<9>'
 '@T6G_MB_LIB.T6G(SCH_1):P5E_CPU1_P0_TX_BUF_DP'<9>:
 C_SIGNAL='@t6g_mb_lib.t6g(sch_1):p5e_cpu1_p0_tx_buf_dp(9)';
NODE_NAME     U6014 BP7
 '@T6G_MB_LIB.T6G(SCH_1):PAGE439_I43@PURE_QUANTA.PT5161LRS(CHIPS)':
 'B_PETP6': CDS_PINID='B_PETP6';
NODE_NAME     C6647 2
 '@T6G_MB_LIB.T6G(SCH_1):PAGE439_I102@PURE_QUANTA.Q_CAP_DIFFBUS(CHIPS)':
 '2': CDS_PINID='\2\';
NET_NAME
'P5E_CPU1_P0_TX_C_DN<0>'
 '@T6G_MB_LIB.T6G(SCH_1):P5E_CPU1_P0_TX_C_DN'<0>:
 C_SIGNAL='@t6g_mb_lib.t6g(sch_1):p5e_cpu1_p0_tx_c_dn(0)';
NODE_NAME     C836 1
 '@T6G_MB_LIB.T6G(SCH_1):PAGE353_I333@PURE_QUANTA.Q_CAP_DIFFBUS(CHIPS)':
 '1': CDS_PINID='\1\';
NODE_NAME     U6014 EV34
 '@T6G_MB_LIB.T6G(SCH_1):PAGE437_I38@PURE_QUANTA.PT5161LRS(CHIPS)':
 'B_PERP15': CDS_PINID='B_PERP15';
NET_NAME
'P5E_CPU1_P0_TX_C_DN<10>'
 '@T6G_MB_LIB.T6G(SCH_1):P5E_CPU1_P0_TX_C_DN'<10>:
 C_SIGNAL='@t6g_mb_lib.t6g(sch_1):p5e_cpu1_p0_tx_c_dn(10)';
NODE_NAME     C816 1
 '@T6G_MB_LIB.T6G(SCH_1):PAGE353_I368@PURE_QUANTA.Q_CAP_DIFFBUS(CHIPS)':
 '1': CDS_PINID='\1\';
NODE_NAME     U6014 BH34
 '@T6G_MB_LIB.T6G(SCH_1):PAGE437_I1@PURE_QUANTA.PT5161LRS(CHIPS)':
 'B_PERP5': CDS_PINID='B_PERP5';
NET_NAME
'P5E_CPU1_P0_TX_C_DN<11>'
 '@T6G_MB_LIB.T6G(SCH_1):P5E_CPU1_P0_TX_C_DN'<11>:
 C_SIGNAL='@t6g_mb_lib.t6g(sch_1):p5e_cpu1_p0_tx_c_dn(11)';
NODE_NAME     C814 1
 '@T6G_MB_LIB.T6G(SCH_1):PAGE353_I370@PURE_QUANTA.Q_CAP_DIFFBUS(CHIPS)':
 '1': CDS_PINID='\1\';
NODE_NAME     U6014 BA34
 '@T6G_MB_LIB.T6G(SCH_1):PAGE437_I1@PURE_QUANTA.PT5161LRS(CHIPS)':
 'B_PERP4': CDS_PINID='B_PERP4';
NET_NAME
'P5E_CPU1_P0_TX_C_DN<12>'
 '@T6G_MB_LIB.T6G(SCH_1):P5E_CPU1_P0_TX_C_DN'<12>:
 C_SIGNAL='@t6g_mb_lib.t6g(sch_1):p5e_cpu1_p0_tx_c_dn(12)';
NODE_NAME     C812 1
 '@T6G_MB_LIB.T6G(SCH_1):PAGE353_I371@PURE_QUANTA.Q_CAP_DIFFBUS(CHIPS)':
 '1': CDS_PINID='\1\';
NODE_NAME     U6014 AP34
 '@T6G_MB_LIB.T6G(SCH_1):PAGE437_I1@PURE_QUANTA.PT5161LRS(CHIPS)':
 'B_PERP3': CDS_PINID='B_PERP3';
NET_NAME
'P5E_CPU1_P0_TX_C_DN<13>'
 '@T6G_MB_LIB.T6G(SCH_1):P5E_CPU1_P0_TX_C_DN'<13>:
 C_SIGNAL='@t6g_mb_lib.t6g(sch_1):p5e_cpu1_p0_tx_c_dn(13)';
NODE_NAME     C810 1
 '@T6G_MB_LIB.T6G(SCH_1):PAGE353_I374@PURE_QUANTA.Q_CAP_DIFFBUS(CHIPS)':
 '1': CDS_PINID='\1\';
NODE_NAME     U6014 AJ35
 '@T6G_MB_LIB.T6G(SCH_1):PAGE437_I1@PURE_QUANTA.PT5161LRS(CHIPS)':
 'B_PERN2': CDS_PINID='B_PERN2';
NET_NAME
'P5E_CPU1_P0_TX_C_DN<14>'
 '@T6G_MB_LIB.T6G(SCH_1):P5E_CPU1_P0_TX_C_DN'<14>:
 C_SIGNAL='@t6g_mb_lib.t6g(sch_1):p5e_cpu1_p0_tx_c_dn(14)';
NODE_NAME     C808 1
 '@T6G_MB_LIB.T6G(SCH_1):PAGE353_I376@PURE_QUANTA.Q_CAP_DIFFBUS(CHIPS)':
 '1': CDS_PINID='\1\';
NODE_NAME     U6014 Y34
 '@T6G_MB_LIB.T6G(SCH_1):PAGE437_I1@PURE_QUANTA.PT5161LRS(CHIPS)':
 'B_PERP1': CDS_PINID='B_PERP1';
NET_NAME
'P5E_CPU1_P0_TX_C_DN<15>'
 '@T6G_MB_LIB.T6G(SCH_1):P5E_CPU1_P0_TX_C_DN'<15>:
 C_SIGNAL='@t6g_mb_lib.t6g(sch_1):p5e_cpu1_p0_tx_c_dn(15)';
NODE_NAME     C806 1
 '@T6G_MB_LIB.T6G(SCH_1):PAGE353_I377@PURE_QUANTA.Q_CAP_DIFFBUS(CHIPS)':
 '1': CDS_PINID='\1\';
NODE_NAME     U6014 N34
 '@T6G_MB_LIB.T6G(SCH_1):PAGE437_I1@PURE_QUANTA.PT5161LRS(CHIPS)':
 'B_PERP0': CDS_PINID='B_PERP0';
NET_NAME
'P5E_CPU1_P0_TX_C_DN<1>'
 '@T6G_MB_LIB.T6G(SCH_1):P5E_CPU1_P0_TX_C_DN'<1>:
 C_SIGNAL='@t6g_mb_lib.t6g(sch_1):p5e_cpu1_p0_tx_c_dn(1)';
NODE_NAME     C834 1
 '@T6G_MB_LIB.T6G(SCH_1):PAGE353_I335@PURE_QUANTA.Q_CAP_DIFFBUS(CHIPS)':
 '1': CDS_PINID='\1\';
NODE_NAME     U6014 EN35
 '@T6G_MB_LIB.T6G(SCH_1):PAGE437_I38@PURE_QUANTA.PT5161LRS(CHIPS)':
 'B_PERN14': CDS_PINID='B_PERN14';
NET_NAME
'P5E_CPU1_P0_TX_C_DN<2>'
 '@T6G_MB_LIB.T6G(SCH_1):P5E_CPU1_P0_TX_C_DN'<2>:
 C_SIGNAL='@t6g_mb_lib.t6g(sch_1):p5e_cpu1_p0_tx_c_dn(2)';
NODE_NAME     C832 1
 '@T6G_MB_LIB.T6G(SCH_1):PAGE353_I338@PURE_QUANTA.Q_CAP_DIFFBUS(CHIPS)':
 '1': CDS_PINID='\1\';
NODE_NAME     U6014 ED34
 '@T6G_MB_LIB.T6G(SCH_1):PAGE437_I38@PURE_QUANTA.PT5161LRS(CHIPS)':
 'B_PERP13': CDS_PINID='B_PERP13';
NET_NAME
'P5E_CPU1_P0_TX_C_DN<3>'
 '@T6G_MB_LIB.T6G(SCH_1):P5E_CPU1_P0_TX_C_DN'<3>:
 C_SIGNAL='@t6g_mb_lib.t6g(sch_1):p5e_cpu1_p0_tx_c_dn(3)';
NODE_NAME     C830 1
 '@T6G_MB_LIB.T6G(SCH_1):PAGE353_I341@PURE_QUANTA.Q_CAP_DIFFBUS(CHIPS)':
 '1': CDS_PINID='\1\';
NODE_NAME     U6014 DU34
 '@T6G_MB_LIB.T6G(SCH_1):PAGE437_I38@PURE_QUANTA.PT5161LRS(CHIPS)':
 'B_PERP12': CDS_PINID='B_PERP12';
NET_NAME
'P5E_CPU1_P0_TX_C_DN<4>'
 '@T6G_MB_LIB.T6G(SCH_1):P5E_CPU1_P0_TX_C_DN'<4>:
 C_SIGNAL='@t6g_mb_lib.t6g(sch_1):p5e_cpu1_p0_tx_c_dn(4)';
NODE_NAME     C828 1
 '@T6G_MB_LIB.T6G(SCH_1):PAGE353_I340@PURE_QUANTA.Q_CAP_DIFFBUS(CHIPS)':
 '1': CDS_PINID='\1\';
NODE_NAME     U6014 DK34
 '@T6G_MB_LIB.T6G(SCH_1):PAGE437_I38@PURE_QUANTA.PT5161LRS(CHIPS)':
 'B_PERP11': CDS_PINID='B_PERP11';
NET_NAME
'P5E_CPU1_P0_TX_C_DN<5>'
 '@T6G_MB_LIB.T6G(SCH_1):P5E_CPU1_P0_TX_C_DN'<5>:
 C_SIGNAL='@t6g_mb_lib.t6g(sch_1):p5e_cpu1_p0_tx_c_dn(5)';
NODE_NAME     C826 1
 '@T6G_MB_LIB.T6G(SCH_1):PAGE353_I344@PURE_QUANTA.Q_CAP_DIFFBUS(CHIPS)':
 '1': CDS_PINID='\1\';
NODE_NAME     U6014 DC34
 '@T6G_MB_LIB.T6G(SCH_1):PAGE437_I38@PURE_QUANTA.PT5161LRS(CHIPS)':
 'B_PERP10': CDS_PINID='B_PERP10';
NET_NAME
'P5E_CPU1_P0_TX_C_DN<6>'
 '@T6G_MB_LIB.T6G(SCH_1):P5E_CPU1_P0_TX_C_DN'<6>:
 C_SIGNAL='@t6g_mb_lib.t6g(sch_1):p5e_cpu1_p0_tx_c_dn(6)';
NODE_NAME     C824 1
 '@T6G_MB_LIB.T6G(SCH_1):PAGE353_I416@PURE_QUANTA.Q_CAP_DIFFBUS(CHIPS)':
 '1': CDS_PINID='\1\';
NODE_NAME     U6014 CT34
 '@T6G_MB_LIB.T6G(SCH_1):PAGE437_I38@PURE_QUANTA.PT5161LRS(CHIPS)':
 'B_PERP9': CDS_PINID='B_PERP9';
NET_NAME
'P5E_CPU1_P0_TX_C_DN<7>'
 '@T6G_MB_LIB.T6G(SCH_1):P5E_CPU1_P0_TX_C_DN'<7>:
 C_SIGNAL='@t6g_mb_lib.t6g(sch_1):p5e_cpu1_p0_tx_c_dn(7)';
NODE_NAME     C822 1
 '@T6G_MB_LIB.T6G(SCH_1):PAGE353_I345@PURE_QUANTA.Q_CAP_DIFFBUS(CHIPS)':
 '1': CDS_PINID='\1\';
NODE_NAME     U6014 CJ34
 '@T6G_MB_LIB.T6G(SCH_1):PAGE437_I38@PURE_QUANTA.PT5161LRS(CHIPS)':
 'B_PERP8': CDS_PINID='B_PERP8';
NET_NAME
'P5E_CPU1_P0_TX_C_DN<8>'
 '@T6G_MB_LIB.T6G(SCH_1):P5E_CPU1_P0_TX_C_DN'<8>:
 C_SIGNAL='@t6g_mb_lib.t6g(sch_1):p5e_cpu1_p0_tx_c_dn(8)';
NODE_NAME     C820 1
 '@T6G_MB_LIB.T6G(SCH_1):PAGE353_I363@PURE_QUANTA.Q_CAP_DIFFBUS(CHIPS)':
 '1': CDS_PINID='\1\';
NODE_NAME     U6014 CB34
 '@T6G_MB_LIB.T6G(SCH_1):PAGE437_I1@PURE_QUANTA.PT5161LRS(CHIPS)':
 'B_PERP7': CDS_PINID='B_PERP7';
NET_NAME
'P5E_CPU1_P0_TX_C_DN<9>'
 '@T6G_MB_LIB.T6G(SCH_1):P5E_CPU1_P0_TX_C_DN'<9>:
 C_SIGNAL='@t6g_mb_lib.t6g(sch_1):p5e_cpu1_p0_tx_c_dn(9)';
NODE_NAME     C818 1
 '@T6G_MB_LIB.T6G(SCH_1):PAGE353_I365@PURE_QUANTA.Q_CAP_DIFFBUS(CHIPS)':
 '1': CDS_PINID='\1\';
NODE_NAME     U6014 BR34
 '@T6G_MB_LIB.T6G(SCH_1):PAGE437_I1@PURE_QUANTA.PT5161LRS(CHIPS)':
 'B_PERP6': CDS_PINID='B_PERP6';
NET_NAME
'P5E_CPU1_P0_TX_C_DP<0>'
 '@T6G_MB_LIB.T6G(SCH_1):P5E_CPU1_P0_TX_C_DP'<0>:
 C_SIGNAL='@t6g_mb_lib.t6g(sch_1):p5e_cpu1_p0_tx_c_dp(0)';
NODE_NAME     C837 1
 '@T6G_MB_LIB.T6G(SCH_1):PAGE353_I334@PURE_QUANTA.Q_CAP_DIFFBUS(CHIPS)':
 '1': CDS_PINID='\1\';
NODE_NAME     U6014 EY35
 '@T6G_MB_LIB.T6G(SCH_1):PAGE437_I38@PURE_QUANTA.PT5161LRS(CHIPS)':
 'B_PERN15': CDS_PINID='B_PERN15';
NET_NAME
'P5E_CPU1_P0_TX_C_DP<10>'
 '@T6G_MB_LIB.T6G(SCH_1):P5E_CPU1_P0_TX_C_DP'<10>:
 C_SIGNAL='@t6g_mb_lib.t6g(sch_1):p5e_cpu1_p0_tx_c_dp(10)';
NODE_NAME     C817 1
 '@T6G_MB_LIB.T6G(SCH_1):PAGE353_I367@PURE_QUANTA.Q_CAP_DIFFBUS(CHIPS)':
 '1': CDS_PINID='\1\';
NODE_NAME     U6014 BK35
 '@T6G_MB_LIB.T6G(SCH_1):PAGE437_I1@PURE_QUANTA.PT5161LRS(CHIPS)':
 'B_PERN5': CDS_PINID='B_PERN5';
NET_NAME
'P5E_CPU1_P0_TX_C_DP<11>'
 '@T6G_MB_LIB.T6G(SCH_1):P5E_CPU1_P0_TX_C_DP'<11>:
 C_SIGNAL='@t6g_mb_lib.t6g(sch_1):p5e_cpu1_p0_tx_c_dp(11)';
NODE_NAME     C815 1
 '@T6G_MB_LIB.T6G(SCH_1):PAGE353_I369@PURE_QUANTA.Q_CAP_DIFFBUS(CHIPS)':
 '1': CDS_PINID='\1\';
NODE_NAME     U6014 BC35
 '@T6G_MB_LIB.T6G(SCH_1):PAGE437_I1@PURE_QUANTA.PT5161LRS(CHIPS)':
 'B_PERN4': CDS_PINID='B_PERN4';
NET_NAME
'P5E_CPU1_P0_TX_C_DP<12>'
 '@T6G_MB_LIB.T6G(SCH_1):P5E_CPU1_P0_TX_C_DP'<12>:
 C_SIGNAL='@t6g_mb_lib.t6g(sch_1):p5e_cpu1_p0_tx_c_dp(12)';
NODE_NAME     C813 1
 '@T6G_MB_LIB.T6G(SCH_1):PAGE353_I372@PURE_QUANTA.Q_CAP_DIFFBUS(CHIPS)':
 '1': CDS_PINID='\1\';
NODE_NAME     U6014 AT35
 '@T6G_MB_LIB.T6G(SCH_1):PAGE437_I1@PURE_QUANTA.PT5161LRS(CHIPS)':
 'B_PERN3': CDS_PINID='B_PERN3';
NET_NAME
'P5E_CPU1_P0_TX_C_DP<13>'
 '@T6G_MB_LIB.T6G(SCH_1):P5E_CPU1_P0_TX_C_DP'<13>:
 C_SIGNAL='@t6g_mb_lib.t6g(sch_1):p5e_cpu1_p0_tx_c_dp(13)';
NODE_NAME     C811 1
 '@T6G_MB_LIB.T6G(SCH_1):PAGE353_I373@PURE_QUANTA.Q_CAP_DIFFBUS(CHIPS)':
 '1': CDS_PINID='\1\';
NODE_NAME     U6014 AG34
 '@T6G_MB_LIB.T6G(SCH_1):PAGE437_I1@PURE_QUANTA.PT5161LRS(CHIPS)':
 'B_PERP2': CDS_PINID='B_PERP2';
NET_NAME
'P5E_CPU1_P0_TX_C_DP<14>'
 '@T6G_MB_LIB.T6G(SCH_1):P5E_CPU1_P0_TX_C_DP'<14>:
 C_SIGNAL='@t6g_mb_lib.t6g(sch_1):p5e_cpu1_p0_tx_c_dp(14)';
NODE_NAME     C809 1
 '@T6G_MB_LIB.T6G(SCH_1):PAGE353_I375@PURE_QUANTA.Q_CAP_DIFFBUS(CHIPS)':
 '1': CDS_PINID='\1\';
NODE_NAME     U6014 AB35
 '@T6G_MB_LIB.T6G(SCH_1):PAGE437_I1@PURE_QUANTA.PT5161LRS(CHIPS)':
 'B_PERN1': CDS_PINID='B_PERN1';
NET_NAME
'P5E_CPU1_P0_TX_C_DP<15>'
 '@T6G_MB_LIB.T6G(SCH_1):P5E_CPU1_P0_TX_C_DP'<15>:
 C_SIGNAL='@t6g_mb_lib.t6g(sch_1):p5e_cpu1_p0_tx_c_dp(15)';
NODE_NAME     C807 1
 '@T6G_MB_LIB.T6G(SCH_1):PAGE353_I378@PURE_QUANTA.Q_CAP_DIFFBUS(CHIPS)':
 '1': CDS_PINID='\1\';
NODE_NAME     U6014 R35
 '@T6G_MB_LIB.T6G(SCH_1):PAGE437_I1@PURE_QUANTA.PT5161LRS(CHIPS)':
 'B_PERN0': CDS_PINID='B_PERN0';
NET_NAME
'P5E_CPU1_P0_TX_C_DP<1>'
 '@T6G_MB_LIB.T6G(SCH_1):P5E_CPU1_P0_TX_C_DP'<1>:
 C_SIGNAL='@t6g_mb_lib.t6g(sch_1):p5e_cpu1_p0_tx_c_dp(1)';
NODE_NAME     C835 1
 '@T6G_MB_LIB.T6G(SCH_1):PAGE353_I336@PURE_QUANTA.Q_CAP_DIFFBUS(CHIPS)':
 '1': CDS_PINID='\1\';
NODE_NAME     U6014 EL34
 '@T6G_MB_LIB.T6G(SCH_1):PAGE437_I38@PURE_QUANTA.PT5161LRS(CHIPS)':
 'B_PERP14': CDS_PINID='B_PERP14';
NET_NAME
'P5E_CPU1_P0_TX_C_DP<2>'
 '@T6G_MB_LIB.T6G(SCH_1):P5E_CPU1_P0_TX_C_DP'<2>:
 C_SIGNAL='@t6g_mb_lib.t6g(sch_1):p5e_cpu1_p0_tx_c_dp(2)';
NODE_NAME     C833 1
 '@T6G_MB_LIB.T6G(SCH_1):PAGE353_I339@PURE_QUANTA.Q_CAP_DIFFBUS(CHIPS)':
 '1': CDS_PINID='\1\';
NODE_NAME     U6014 EF35
 '@T6G_MB_LIB.T6G(SCH_1):PAGE437_I38@PURE_QUANTA.PT5161LRS(CHIPS)':
 'B_PERN13': CDS_PINID='B_PERN13';
NET_NAME
'P5E_CPU1_P0_TX_C_DP<3>'
 '@T6G_MB_LIB.T6G(SCH_1):P5E_CPU1_P0_TX_C_DP'<3>:
 C_SIGNAL='@t6g_mb_lib.t6g(sch_1):p5e_cpu1_p0_tx_c_dp(3)';
NODE_NAME     C831 1
 '@T6G_MB_LIB.T6G(SCH_1):PAGE353_I337@PURE_QUANTA.Q_CAP_DIFFBUS(CHIPS)':
 '1': CDS_PINID='\1\';
NODE_NAME     U6014 DW35
 '@T6G_MB_LIB.T6G(SCH_1):PAGE437_I38@PURE_QUANTA.PT5161LRS(CHIPS)':
 'B_PERN12': CDS_PINID='B_PERN12';
NET_NAME
'P5E_CPU1_P0_TX_C_DP<4>'
 '@T6G_MB_LIB.T6G(SCH_1):P5E_CPU1_P0_TX_C_DP'<4>:
 C_SIGNAL='@t6g_mb_lib.t6g(sch_1):p5e_cpu1_p0_tx_c_dp(4)';
NODE_NAME     C829 1
 '@T6G_MB_LIB.T6G(SCH_1):PAGE353_I342@PURE_QUANTA.Q_CAP_DIFFBUS(CHIPS)':
 '1': CDS_PINID='\1\';
NODE_NAME     U6014 DM35
 '@T6G_MB_LIB.T6G(SCH_1):PAGE437_I38@PURE_QUANTA.PT5161LRS(CHIPS)':
 'B_PERN11': CDS_PINID='B_PERN11';
NET_NAME
'P5E_CPU1_P0_TX_C_DP<5>'
 '@T6G_MB_LIB.T6G(SCH_1):P5E_CPU1_P0_TX_C_DP'<5>:
 C_SIGNAL='@t6g_mb_lib.t6g(sch_1):p5e_cpu1_p0_tx_c_dp(5)';
NODE_NAME     C827 1
 '@T6G_MB_LIB.T6G(SCH_1):PAGE353_I343@PURE_QUANTA.Q_CAP_DIFFBUS(CHIPS)':
 '1': CDS_PINID='\1\';
NODE_NAME     U6014 DE35
 '@T6G_MB_LIB.T6G(SCH_1):PAGE437_I38@PURE_QUANTA.PT5161LRS(CHIPS)':
 'B_PERN10': CDS_PINID='B_PERN10';
NET_NAME
'P5E_CPU1_P0_TX_C_DP<6>'
 '@T6G_MB_LIB.T6G(SCH_1):P5E_CPU1_P0_TX_C_DP'<6>:
 C_SIGNAL='@t6g_mb_lib.t6g(sch_1):p5e_cpu1_p0_tx_c_dp(6)';
NODE_NAME     C825 1
 '@T6G_MB_LIB.T6G(SCH_1):PAGE353_I415@PURE_QUANTA.Q_CAP_DIFFBUS(CHIPS)':
 '1': CDS_PINID='\1\';
NODE_NAME     U6014 CV35
 '@T6G_MB_LIB.T6G(SCH_1):PAGE437_I38@PURE_QUANTA.PT5161LRS(CHIPS)':
 'B_PERN9': CDS_PINID='B_PERN9';
NET_NAME
'P5E_CPU1_P0_TX_C_DP<7>'
 '@T6G_MB_LIB.T6G(SCH_1):P5E_CPU1_P0_TX_C_DP'<7>:
 C_SIGNAL='@t6g_mb_lib.t6g(sch_1):p5e_cpu1_p0_tx_c_dp(7)';
NODE_NAME     C823 1
 '@T6G_MB_LIB.T6G(SCH_1):PAGE353_I346@PURE_QUANTA.Q_CAP_DIFFBUS(CHIPS)':
 '1': CDS_PINID='\1\';
NODE_NAME     U6014 CL35
 '@T6G_MB_LIB.T6G(SCH_1):PAGE437_I38@PURE_QUANTA.PT5161LRS(CHIPS)':
 'B_PERN8': CDS_PINID='B_PERN8';
NET_NAME
'P5E_CPU1_P0_TX_C_DP<8>'
 '@T6G_MB_LIB.T6G(SCH_1):P5E_CPU1_P0_TX_C_DP'<8>:
 C_SIGNAL='@t6g_mb_lib.t6g(sch_1):p5e_cpu1_p0_tx_c_dp(8)';
NODE_NAME     C821 1
 '@T6G_MB_LIB.T6G(SCH_1):PAGE353_I364@PURE_QUANTA.Q_CAP_DIFFBUS(CHIPS)':
 '1': CDS_PINID='\1\';
NODE_NAME     U6014 CD35
 '@T6G_MB_LIB.T6G(SCH_1):PAGE437_I1@PURE_QUANTA.PT5161LRS(CHIPS)':
 'B_PERN7': CDS_PINID='B_PERN7';
NET_NAME
'P5E_CPU1_P0_TX_C_DP<9>'
 '@T6G_MB_LIB.T6G(SCH_1):P5E_CPU1_P0_TX_C_DP'<9>:
 C_SIGNAL='@t6g_mb_lib.t6g(sch_1):p5e_cpu1_p0_tx_c_dp(9)';
NODE_NAME     C819 1
 '@T6G_MB_LIB.T6G(SCH_1):PAGE353_I366@PURE_QUANTA.Q_CAP_DIFFBUS(CHIPS)':
 '1': CDS_PINID='\1\';
NODE_NAME     U6014 BU35
 '@T6G_MB_LIB.T6G(SCH_1):PAGE437_I1@PURE_QUANTA.PT5161LRS(CHIPS)':
 'B_PERN6': CDS_PINID='B_PERN6';
NET_NAME
'P5E_CPU1_P0_TX_DN<0>'
 '@T6G_MB_LIB.T6G(SCH_1):P5E_CPU1_P0_TX_DN'<0>:
 C_SIGNAL='@t6g_mb_lib.t6g(sch_1):p5e_cpu1_p0_tx_dn(0)';
NODE_NAME     U26 CN52
 '@T6G_MB_LIB.T6G(SCH_1):PAGE51_I147@PURE_QUANTA.GENOA_SP5(CHIPS)':
 'P0_TXN0||SATA00_TXN': CDS_PINID='\p0_txn0||sata00_txn\';
NODE_NAME     C836 2
 '@T6G_MB_LIB.T6G(SCH_1):PAGE353_I333@PURE_QUANTA.Q_CAP_DIFFBUS(CHIPS)':
 '2': CDS_PINID='\2\';
NET_NAME
'P5E_CPU1_P0_TX_DN<10>'
 '@T6G_MB_LIB.T6G(SCH_1):P5E_CPU1_P0_TX_DN'<10>:
 C_SIGNAL='@t6g_mb_lib.t6g(sch_1):p5e_cpu1_p0_tx_dn(10)';
NODE_NAME     U26 CR43
 '@T6G_MB_LIB.T6G(SCH_1):PAGE51_I147@PURE_QUANTA.GENOA_SP5(CHIPS)':
 'P0_TXN10||SATA12_TXN': CDS_PINID='\p0_txn10||sata12_txn\';
NODE_NAME     C816 2
 '@T6G_MB_LIB.T6G(SCH_1):PAGE353_I368@PURE_QUANTA.Q_CAP_DIFFBUS(CHIPS)':
 '2': CDS_PINID='\2\';
NET_NAME
'P5E_CPU1_P0_TX_DN<11>'
 '@T6G_MB_LIB.T6G(SCH_1):P5E_CPU1_P0_TX_DN'<11>:
 C_SIGNAL='@t6g_mb_lib.t6g(sch_1):p5e_cpu1_p0_tx_dn(11)';
NODE_NAME     U26 CU43
 '@T6G_MB_LIB.T6G(SCH_1):PAGE51_I147@PURE_QUANTA.GENOA_SP5(CHIPS)':
 'P0_TXN11||SATA13_TXN': CDS_PINID='\p0_txn11||sata13_txn\';
NODE_NAME     C814 2
 '@T6G_MB_LIB.T6G(SCH_1):PAGE353_I370@PURE_QUANTA.Q_CAP_DIFFBUS(CHIPS)':
 '2': CDS_PINID='\2\';
NET_NAME
'P5E_CPU1_P0_TX_DN<12>'
 '@T6G_MB_LIB.T6G(SCH_1):P5E_CPU1_P0_TX_DN'<12>:
 C_SIGNAL='@t6g_mb_lib.t6g(sch_1):p5e_cpu1_p0_tx_dn(12)';
NODE_NAME     U26 CN43
 '@T6G_MB_LIB.T6G(SCH_1):PAGE51_I147@PURE_QUANTA.GENOA_SP5(CHIPS)':
 'P0_TXN12||SATA14_TXN': CDS_PINID='\p0_txn12||sata14_txn\';
NODE_NAME     C812 2
 '@T6G_MB_LIB.T6G(SCH_1):PAGE353_I371@PURE_QUANTA.Q_CAP_DIFFBUS(CHIPS)':
 '2': CDS_PINID='\2\';
NET_NAME
'P5E_CPU1_P0_TX_DN<13>'
 '@T6G_MB_LIB.T6G(SCH_1):P5E_CPU1_P0_TX_DN'<13>:
 C_SIGNAL='@t6g_mb_lib.t6g(sch_1):p5e_cpu1_p0_tx_dn(13)';
NODE_NAME     U26 CT40
 '@T6G_MB_LIB.T6G(SCH_1):PAGE51_I147@PURE_QUANTA.GENOA_SP5(CHIPS)':
 'P0_TXN13||SATA15_TXN': CDS_PINID='\p0_txn13||sata15_txn\';
NODE_NAME     C810 2
 '@T6G_MB_LIB.T6G(SCH_1):PAGE353_I374@PURE_QUANTA.Q_CAP_DIFFBUS(CHIPS)':
 '2': CDS_PINID='\2\';
NET_NAME
'P5E_CPU1_P0_TX_DN<14>'
 '@T6G_MB_LIB.T6G(SCH_1):P5E_CPU1_P0_TX_DN'<14>:
 C_SIGNAL='@t6g_mb_lib.t6g(sch_1):p5e_cpu1_p0_tx_dn(14)';
NODE_NAME     U26 CP40
 '@T6G_MB_LIB.T6G(SCH_1):PAGE51_I147@PURE_QUANTA.GENOA_SP5(CHIPS)':
 'P0_TXN14||SATA16_TXN': CDS_PINID='\p0_txn14||sata16_txn\';
NODE_NAME     C808 2
 '@T6G_MB_LIB.T6G(SCH_1):PAGE353_I376@PURE_QUANTA.Q_CAP_DIFFBUS(CHIPS)':
 '2': CDS_PINID='\2\';
NET_NAME
'P5E_CPU1_P0_TX_DN<15>'
 '@T6G_MB_LIB.T6G(SCH_1):P5E_CPU1_P0_TX_DN'<15>:
 C_SIGNAL='@t6g_mb_lib.t6g(sch_1):p5e_cpu1_p0_tx_dn(15)';
NODE_NAME     U26 CM40
 '@T6G_MB_LIB.T6G(SCH_1):PAGE51_I147@PURE_QUANTA.GENOA_SP5(CHIPS)':
 'P0_TXN15||SATA17_TXN': CDS_PINID='\p0_txn15||sata17_txn\';
NODE_NAME     C806 2
 '@T6G_MB_LIB.T6G(SCH_1):PAGE353_I377@PURE_QUANTA.Q_CAP_DIFFBUS(CHIPS)':
 '2': CDS_PINID='\2\';
NET_NAME
'P5E_CPU1_P0_TX_DN<1>'
 '@T6G_MB_LIB.T6G(SCH_1):P5E_CPU1_P0_TX_DN'<1>:
 C_SIGNAL='@t6g_mb_lib.t6g(sch_1):p5e_cpu1_p0_tx_dn(1)';
NODE_NAME     U26 CR52
 '@T6G_MB_LIB.T6G(SCH_1):PAGE51_I147@PURE_QUANTA.GENOA_SP5(CHIPS)':
 'P0_TXN1||SATA01_TXN': CDS_PINID='\p0_txn1||sata01_txn\';
NODE_NAME     C834 2
 '@T6G_MB_LIB.T6G(SCH_1):PAGE353_I335@PURE_QUANTA.Q_CAP_DIFFBUS(CHIPS)':
 '2': CDS_PINID='\2\';
NET_NAME
'P5E_CPU1_P0_TX_DN<2>'
 '@T6G_MB_LIB.T6G(SCH_1):P5E_CPU1_P0_TX_DN'<2>:
 C_SIGNAL='@t6g_mb_lib.t6g(sch_1):p5e_cpu1_p0_tx_dn(2)';
NODE_NAME     U26 CL52
 '@T6G_MB_LIB.T6G(SCH_1):PAGE51_I147@PURE_QUANTA.GENOA_SP5(CHIPS)':
 'P0_TXN2||SATA02_TXN': CDS_PINID='\p0_txn2||sata02_txn\';
NODE_NAME     C832 2
 '@T6G_MB_LIB.T6G(SCH_1):PAGE353_I338@PURE_QUANTA.Q_CAP_DIFFBUS(CHIPS)':
 '2': CDS_PINID='\2\';
NET_NAME
'P5E_CPU1_P0_TX_DN<3>'
 '@T6G_MB_LIB.T6G(SCH_1):P5E_CPU1_P0_TX_DN'<3>:
 C_SIGNAL='@t6g_mb_lib.t6g(sch_1):p5e_cpu1_p0_tx_dn(3)';
NODE_NAME     U26 CN49
 '@T6G_MB_LIB.T6G(SCH_1):PAGE51_I147@PURE_QUANTA.GENOA_SP5(CHIPS)':
 'P0_TXN3||SATA03_TXN': CDS_PINID='\p0_txn3||sata03_txn\';
NODE_NAME     C830 2
 '@T6G_MB_LIB.T6G(SCH_1):PAGE353_I341@PURE_QUANTA.Q_CAP_DIFFBUS(CHIPS)':
 '2': CDS_PINID='\2\';
NET_NAME
'P5E_CPU1_P0_TX_DN<4>'
 '@T6G_MB_LIB.T6G(SCH_1):P5E_CPU1_P0_TX_DN'<4>:
 C_SIGNAL='@t6g_mb_lib.t6g(sch_1):p5e_cpu1_p0_tx_dn(4)';
NODE_NAME     U26 CR49
 '@T6G_MB_LIB.T6G(SCH_1):PAGE51_I147@PURE_QUANTA.GENOA_SP5(CHIPS)':
 'P0_TXN4||SATA04_TXN': CDS_PINID='\p0_txn4||sata04_txn\';
NODE_NAME     C828 2
 '@T6G_MB_LIB.T6G(SCH_1):PAGE353_I340@PURE_QUANTA.Q_CAP_DIFFBUS(CHIPS)':
 '2': CDS_PINID='\2\';
NET_NAME
'P5E_CPU1_P0_TX_DN<5>'
 '@T6G_MB_LIB.T6G(SCH_1):P5E_CPU1_P0_TX_DN'<5>:
 C_SIGNAL='@t6g_mb_lib.t6g(sch_1):p5e_cpu1_p0_tx_dn(5)';
NODE_NAME     U26 CU49
 '@T6G_MB_LIB.T6G(SCH_1):PAGE51_I147@PURE_QUANTA.GENOA_SP5(CHIPS)':
 'P0_TXN5||SATA05_TXN': CDS_PINID='\p0_txn5||sata05_txn\';
NODE_NAME     C826 2
 '@T6G_MB_LIB.T6G(SCH_1):PAGE353_I344@PURE_QUANTA.Q_CAP_DIFFBUS(CHIPS)':
 '2': CDS_PINID='\2\';
NET_NAME
'P5E_CPU1_P0_TX_DN<6>'
 '@T6G_MB_LIB.T6G(SCH_1):P5E_CPU1_P0_TX_DN'<6>:
 C_SIGNAL='@t6g_mb_lib.t6g(sch_1):p5e_cpu1_p0_tx_dn(6)';
NODE_NAME     U26 CL49
 '@T6G_MB_LIB.T6G(SCH_1):PAGE51_I147@PURE_QUANTA.GENOA_SP5(CHIPS)':
 'P0_TXN6||SATA06_TXN': CDS_PINID='\p0_txn6||sata06_txn\';
NODE_NAME     C824 2
 '@T6G_MB_LIB.T6G(SCH_1):PAGE353_I416@PURE_QUANTA.Q_CAP_DIFFBUS(CHIPS)':
 '2': CDS_PINID='\2\';
NET_NAME
'P5E_CPU1_P0_TX_DN<7>'
 '@T6G_MB_LIB.T6G(SCH_1):P5E_CPU1_P0_TX_DN'<7>:
 C_SIGNAL='@t6g_mb_lib.t6g(sch_1):p5e_cpu1_p0_tx_dn(7)';
NODE_NAME     U26 CR46
 '@T6G_MB_LIB.T6G(SCH_1):PAGE51_I147@PURE_QUANTA.GENOA_SP5(CHIPS)':
 'P0_TXN7||SATA07_TXN': CDS_PINID='\p0_txn7||sata07_txn\';
NODE_NAME     C822 2
 '@T6G_MB_LIB.T6G(SCH_1):PAGE353_I345@PURE_QUANTA.Q_CAP_DIFFBUS(CHIPS)':
 '2': CDS_PINID='\2\';
NET_NAME
'P5E_CPU1_P0_TX_DN<8>'
 '@T6G_MB_LIB.T6G(SCH_1):P5E_CPU1_P0_TX_DN'<8>:
 C_SIGNAL='@t6g_mb_lib.t6g(sch_1):p5e_cpu1_p0_tx_dn(8)';
NODE_NAME     U26 CU46
 '@T6G_MB_LIB.T6G(SCH_1):PAGE51_I147@PURE_QUANTA.GENOA_SP5(CHIPS)':
 'P0_TXN8||SATA10_TXN': CDS_PINID='\p0_txn8||sata10_txn\';
NODE_NAME     C820 2
 '@T6G_MB_LIB.T6G(SCH_1):PAGE353_I363@PURE_QUANTA.Q_CAP_DIFFBUS(CHIPS)':
 '2': CDS_PINID='\2\';
NET_NAME
'P5E_CPU1_P0_TX_DN<9>'
 '@T6G_MB_LIB.T6G(SCH_1):P5E_CPU1_P0_TX_DN'<9>:
 C_SIGNAL='@t6g_mb_lib.t6g(sch_1):p5e_cpu1_p0_tx_dn(9)';
NODE_NAME     U26 CN46
 '@T6G_MB_LIB.T6G(SCH_1):PAGE51_I147@PURE_QUANTA.GENOA_SP5(CHIPS)':
 'P0_TXN9||SATA11_TXN': CDS_PINID='\p0_txn9||sata11_txn\';
NODE_NAME     C818 2
 '@T6G_MB_LIB.T6G(SCH_1):PAGE353_I365@PURE_QUANTA.Q_CAP_DIFFBUS(CHIPS)':
 '2': CDS_PINID='\2\';
NET_NAME
'P5E_CPU1_P0_TX_DP<0>'
 '@T6G_MB_LIB.T6G(SCH_1):P5E_CPU1_P0_TX_DP'<0>:
 C_SIGNAL='@t6g_mb_lib.t6g(sch_1):p5e_cpu1_p0_tx_dp(0)';
NODE_NAME     U26 CN53
 '@T6G_MB_LIB.T6G(SCH_1):PAGE51_I147@PURE_QUANTA.GENOA_SP5(CHIPS)':
 'P0_TXP0||SATA00_TXP': CDS_PINID='\p0_txp0||sata00_txp\';
NODE_NAME     C837 2
 '@T6G_MB_LIB.T6G(SCH_1):PAGE353_I334@PURE_QUANTA.Q_CAP_DIFFBUS(CHIPS)':
 '2': CDS_PINID='\2\';
NET_NAME
'P5E_CPU1_P0_TX_DP<10>'
 '@T6G_MB_LIB.T6G(SCH_1):P5E_CPU1_P0_TX_DP'<10>:
 C_SIGNAL='@t6g_mb_lib.t6g(sch_1):p5e_cpu1_p0_tx_dp(10)';
NODE_NAME     U26 CR44
 '@T6G_MB_LIB.T6G(SCH_1):PAGE51_I147@PURE_QUANTA.GENOA_SP5(CHIPS)':
 'P0_TXP10||SATA12_TXP': CDS_PINID='\p0_txp10||sata12_txp\';
NODE_NAME     C817 2
 '@T6G_MB_LIB.T6G(SCH_1):PAGE353_I367@PURE_QUANTA.Q_CAP_DIFFBUS(CHIPS)':
 '2': CDS_PINID='\2\';
NET_NAME
'P5E_CPU1_P0_TX_DP<11>'
 '@T6G_MB_LIB.T6G(SCH_1):P5E_CPU1_P0_TX_DP'<11>:
 C_SIGNAL='@t6g_mb_lib.t6g(sch_1):p5e_cpu1_p0_tx_dp(11)';
NODE_NAME     U26 CU44
 '@T6G_MB_LIB.T6G(SCH_1):PAGE51_I147@PURE_QUANTA.GENOA_SP5(CHIPS)':
 'P0_TXP11||SATA13_TXP': CDS_PINID='\p0_txp11||sata13_txp\';
NODE_NAME     C815 2
 '@T6G_MB_LIB.T6G(SCH_1):PAGE353_I369@PURE_QUANTA.Q_CAP_DIFFBUS(CHIPS)':
 '2': CDS_PINID='\2\';
NET_NAME
'P5E_CPU1_P0_TX_DP<12>'
 '@T6G_MB_LIB.T6G(SCH_1):P5E_CPU1_P0_TX_DP'<12>:
 C_SIGNAL='@t6g_mb_lib.t6g(sch_1):p5e_cpu1_p0_tx_dp(12)';
NODE_NAME     U26 CN44
 '@T6G_MB_LIB.T6G(SCH_1):PAGE51_I147@PURE_QUANTA.GENOA_SP5(CHIPS)':
 'P0_TXP12||SATA14_TXP': CDS_PINID='\p0_txp12||sata14_txp\';
NODE_NAME     C813 2
 '@T6G_MB_LIB.T6G(SCH_1):PAGE353_I372@PURE_QUANTA.Q_CAP_DIFFBUS(CHIPS)':
 '2': CDS_PINID='\2\';
NET_NAME
'P5E_CPU1_P0_TX_DP<13>'
 '@T6G_MB_LIB.T6G(SCH_1):P5E_CPU1_P0_TX_DP'<13>:
 C_SIGNAL='@t6g_mb_lib.t6g(sch_1):p5e_cpu1_p0_tx_dp(13)';
NODE_NAME     U26 CT41
 '@T6G_MB_LIB.T6G(SCH_1):PAGE51_I147@PURE_QUANTA.GENOA_SP5(CHIPS)':
 'P0_TXP13||SATA15_TXP': CDS_PINID='\p0_txp13||sata15_txp\';
NODE_NAME     C811 2
 '@T6G_MB_LIB.T6G(SCH_1):PAGE353_I373@PURE_QUANTA.Q_CAP_DIFFBUS(CHIPS)':
 '2': CDS_PINID='\2\';
NET_NAME
'P5E_CPU1_P0_TX_DP<14>'
 '@T6G_MB_LIB.T6G(SCH_1):P5E_CPU1_P0_TX_DP'<14>:
 C_SIGNAL='@t6g_mb_lib.t6g(sch_1):p5e_cpu1_p0_tx_dp(14)';
NODE_NAME     U26 CP41
 '@T6G_MB_LIB.T6G(SCH_1):PAGE51_I147@PURE_QUANTA.GENOA_SP5(CHIPS)':
 'P0_TXP14||SATA16_TXP': CDS_PINID='\p0_txp14||sata16_txp\';
NODE_NAME     C809 2
 '@T6G_MB_LIB.T6G(SCH_1):PAGE353_I375@PURE_QUANTA.Q_CAP_DIFFBUS(CHIPS)':
 '2': CDS_PINID='\2\';
NET_NAME
'P5E_CPU1_P0_TX_DP<15>'
 '@T6G_MB_LIB.T6G(SCH_1):P5E_CPU1_P0_TX_DP'<15>:
 C_SIGNAL='@t6g_mb_lib.t6g(sch_1):p5e_cpu1_p0_tx_dp(15)';
NODE_NAME     U26 CM41
 '@T6G_MB_LIB.T6G(SCH_1):PAGE51_I147@PURE_QUANTA.GENOA_SP5(CHIPS)':
 'P0_TXP15||SATA17_TXP': CDS_PINID='\p0_txp15||sata17_txp\';
NODE_NAME     C807 2
 '@T6G_MB_LIB.T6G(SCH_1):PAGE353_I378@PURE_QUANTA.Q_CAP_DIFFBUS(CHIPS)':
 '2': CDS_PINID='\2\';
NET_NAME
'P5E_CPU1_P0_TX_DP<1>'
 '@T6G_MB_LIB.T6G(SCH_1):P5E_CPU1_P0_TX_DP'<1>:
 C_SIGNAL='@t6g_mb_lib.t6g(sch_1):p5e_cpu1_p0_tx_dp(1)';
NODE_NAME     U26 CR53
 '@T6G_MB_LIB.T6G(SCH_1):PAGE51_I147@PURE_QUANTA.GENOA_SP5(CHIPS)':
 'P0_TXP1||SATA01_TXP': CDS_PINID='\p0_txp1||sata01_txp\';
NODE_NAME     C835 2
 '@T6G_MB_LIB.T6G(SCH_1):PAGE353_I336@PURE_QUANTA.Q_CAP_DIFFBUS(CHIPS)':
 '2': CDS_PINID='\2\';
NET_NAME
'P5E_CPU1_P0_TX_DP<2>'
 '@T6G_MB_LIB.T6G(SCH_1):P5E_CPU1_P0_TX_DP'<2>:
 C_SIGNAL='@t6g_mb_lib.t6g(sch_1):p5e_cpu1_p0_tx_dp(2)';
NODE_NAME     U26 CL53
 '@T6G_MB_LIB.T6G(SCH_1):PAGE51_I147@PURE_QUANTA.GENOA_SP5(CHIPS)':
 'P0_TXP2||SATA02_TXP': CDS_PINID='\p0_txp2||sata02_txp\';
NODE_NAME     C833 2
 '@T6G_MB_LIB.T6G(SCH_1):PAGE353_I339@PURE_QUANTA.Q_CAP_DIFFBUS(CHIPS)':
 '2': CDS_PINID='\2\';
NET_NAME
'P5E_CPU1_P0_TX_DP<3>'
 '@T6G_MB_LIB.T6G(SCH_1):P5E_CPU1_P0_TX_DP'<3>:
 C_SIGNAL='@t6g_mb_lib.t6g(sch_1):p5e_cpu1_p0_tx_dp(3)';
NODE_NAME     U26 CN50
 '@T6G_MB_LIB.T6G(SCH_1):PAGE51_I147@PURE_QUANTA.GENOA_SP5(CHIPS)':
 'P0_TXP3||SATA03_TXP': CDS_PINID='\p0_txp3||sata03_txp\';
NODE_NAME     C831 2
 '@T6G_MB_LIB.T6G(SCH_1):PAGE353_I337@PURE_QUANTA.Q_CAP_DIFFBUS(CHIPS)':
 '2': CDS_PINID='\2\';
NET_NAME
'P5E_CPU1_P0_TX_DP<4>'
 '@T6G_MB_LIB.T6G(SCH_1):P5E_CPU1_P0_TX_DP'<4>:
 C_SIGNAL='@t6g_mb_lib.t6g(sch_1):p5e_cpu1_p0_tx_dp(4)';
NODE_NAME     U26 CR50
 '@T6G_MB_LIB.T6G(SCH_1):PAGE51_I147@PURE_QUANTA.GENOA_SP5(CHIPS)':
 'P0_TXP4||SATA04_TXP': CDS_PINID='\p0_txp4||sata04_txp\';
NODE_NAME     C829 2
 '@T6G_MB_LIB.T6G(SCH_1):PAGE353_I342@PURE_QUANTA.Q_CAP_DIFFBUS(CHIPS)':
 '2': CDS_PINID='\2\';
NET_NAME
'P5E_CPU1_P0_TX_DP<5>'
 '@T6G_MB_LIB.T6G(SCH_1):P5E_CPU1_P0_TX_DP'<5>:
 C_SIGNAL='@t6g_mb_lib.t6g(sch_1):p5e_cpu1_p0_tx_dp(5)';
NODE_NAME     U26 CU50
 '@T6G_MB_LIB.T6G(SCH_1):PAGE51_I147@PURE_QUANTA.GENOA_SP5(CHIPS)':
 'P0_TXP5||SATA05_TXP': CDS_PINID='\p0_txp5||sata05_txp\';
NODE_NAME     C827 2
 '@T6G_MB_LIB.T6G(SCH_1):PAGE353_I343@PURE_QUANTA.Q_CAP_DIFFBUS(CHIPS)':
 '2': CDS_PINID='\2\';
NET_NAME
'P5E_CPU1_P0_TX_DP<6>'
 '@T6G_MB_LIB.T6G(SCH_1):P5E_CPU1_P0_TX_DP'<6>:
 C_SIGNAL='@t6g_mb_lib.t6g(sch_1):p5e_cpu1_p0_tx_dp(6)';
NODE_NAME     U26 CL50
 '@T6G_MB_LIB.T6G(SCH_1):PAGE51_I147@PURE_QUANTA.GENOA_SP5(CHIPS)':
 'P0_TXP6||SATA06_TXP': CDS_PINID='\p0_txp6||sata06_txp\';
NODE_NAME     C825 2
 '@T6G_MB_LIB.T6G(SCH_1):PAGE353_I415@PURE_QUANTA.Q_CAP_DIFFBUS(CHIPS)':
 '2': CDS_PINID='\2\';
NET_NAME
'P5E_CPU1_P0_TX_DP<7>'
 '@T6G_MB_LIB.T6G(SCH_1):P5E_CPU1_P0_TX_DP'<7>:
 C_SIGNAL='@t6g_mb_lib.t6g(sch_1):p5e_cpu1_p0_tx_dp(7)';
NODE_NAME     U26 CR47
 '@T6G_MB_LIB.T6G(SCH_1):PAGE51_I147@PURE_QUANTA.GENOA_SP5(CHIPS)':
 'P0_TXP7||SATA07_TXP': CDS_PINID='\p0_txp7||sata07_txp\';
NODE_NAME     C823 2
 '@T6G_MB_LIB.T6G(SCH_1):PAGE353_I346@PURE_QUANTA.Q_CAP_DIFFBUS(CHIPS)':
 '2': CDS_PINID='\2\';
NET_NAME
'P5E_CPU1_P0_TX_DP<8>'
 '@T6G_MB_LIB.T6G(SCH_1):P5E_CPU1_P0_TX_DP'<8>:
 C_SIGNAL='@t6g_mb_lib.t6g(sch_1):p5e_cpu1_p0_tx_dp(8)';
NODE_NAME     U26 CU47
 '@T6G_MB_LIB.T6G(SCH_1):PAGE51_I147@PURE_QUANTA.GENOA_SP5(CHIPS)':
 'P0_TXP8||SATA10_TXP': CDS_PINID='\p0_txp8||sata10_txp\';
NODE_NAME     C821 2
 '@T6G_MB_LIB.T6G(SCH_1):PAGE353_I364@PURE_QUANTA.Q_CAP_DIFFBUS(CHIPS)':
 '2': CDS_PINID='\2\';
NET_NAME
'P5E_CPU1_P0_TX_DP<9>'
 '@T6G_MB_LIB.T6G(SCH_1):P5E_CPU1_P0_TX_DP'<9>:
 C_SIGNAL='@t6g_mb_lib.t6g(sch_1):p5e_cpu1_p0_tx_dp(9)';
NODE_NAME     U26 CN47
 '@T6G_MB_LIB.T6G(SCH_1):PAGE51_I147@PURE_QUANTA.GENOA_SP5(CHIPS)':
 'P0_TXP9||SATA11_TXP': CDS_PINID='\p0_txp9||sata11_txp\';
NODE_NAME     C819 2
 '@T6G_MB_LIB.T6G(SCH_1):PAGE353_I366@PURE_QUANTA.Q_CAP_DIFFBUS(CHIPS)':
 '2': CDS_PINID='\2\';
NET_NAME
'P5E_CPU1_P1_RX_BUF_DN<0>'
 '@T6G_MB_LIB.T6G(SCH_1):P5E_CPU1_P1_RX_BUF_DN'<0>:
 C_SIGNAL='@t6g_mb_lib.t6g(sch_1):p5e_cpu1_p1_rx_buf_dn(0)';
NODE_NAME     U6015 EV2
 '@T6G_MB_LIB.T6G(SCH_1):PAGE394_I38@PURE_QUANTA.PT5161LRS(CHIPS)':
 'A_PERN15': CDS_PINID='A_PERN15';
NODE_NAME     J112 F1
 '@T6G_MB_LIB.T6G(SCH_1):PAGE329_I102@PURE_QUANTA.CONN160_10131762101LF(CHIPS)':
 'F1': CDS_PINID='F1';
NET_NAME
'P5E_CPU1_P1_RX_BUF_DN<10>'
 '@T6G_MB_LIB.T6G(SCH_1):P5E_CPU1_P1_RX_BUF_DN'<10>:
 C_SIGNAL='@t6g_mb_lib.t6g(sch_1):p5e_cpu1_p1_rx_buf_dn(10)';
NODE_NAME     U6015 BH2
 '@T6G_MB_LIB.T6G(SCH_1):PAGE394_I1@PURE_QUANTA.PT5161LRS(CHIPS)':
 'A_PERN5': CDS_PINID='A_PERN5';
NODE_NAME     J111 F3
 '@T6G_MB_LIB.T6G(SCH_1):PAGE328_I76@PURE_QUANTA.CONN112_10137002101LF(CHIPS)':
 'F3': CDS_PINID='F3';
NET_NAME
'P5E_CPU1_P1_RX_BUF_DN<11>'
 '@T6G_MB_LIB.T6G(SCH_1):P5E_CPU1_P1_RX_BUF_DN'<11>:
 C_SIGNAL='@t6g_mb_lib.t6g(sch_1):p5e_cpu1_p1_rx_buf_dn(11)';
NODE_NAME     U6015 BA2
 '@T6G_MB_LIB.T6G(SCH_1):PAGE394_I1@PURE_QUANTA.PT5161LRS(CHIPS)':
 'A_PERN4': CDS_PINID='A_PERN4';
NODE_NAME     J111 E4
 '@T6G_MB_LIB.T6G(SCH_1):PAGE328_I76@PURE_QUANTA.CONN112_10137002101LF(CHIPS)':
 'E4': CDS_PINID='E4';
NET_NAME
'P5E_CPU1_P1_RX_BUF_DN<12>'
 '@T6G_MB_LIB.T6G(SCH_1):P5E_CPU1_P1_RX_BUF_DN'<12>:
 C_SIGNAL='@t6g_mb_lib.t6g(sch_1):p5e_cpu1_p1_rx_buf_dn(12)';
NODE_NAME     U6015 AP2
 '@T6G_MB_LIB.T6G(SCH_1):PAGE394_I1@PURE_QUANTA.PT5161LRS(CHIPS)':
 'A_PERN3': CDS_PINID='A_PERN3';
NODE_NAME     J111 F5
 '@T6G_MB_LIB.T6G(SCH_1):PAGE328_I38@PURE_QUANTA.CONN112_10137002101LF(CHIPS)':
 'F5': CDS_PINID='F5';
NET_NAME
'P5E_CPU1_P1_RX_BUF_DN<13>'
 '@T6G_MB_LIB.T6G(SCH_1):P5E_CPU1_P1_RX_BUF_DN'<13>:
 C_SIGNAL='@t6g_mb_lib.t6g(sch_1):p5e_cpu1_p1_rx_buf_dn(13)';
NODE_NAME     U6015 AG2
 '@T6G_MB_LIB.T6G(SCH_1):PAGE394_I1@PURE_QUANTA.PT5161LRS(CHIPS)':
 'A_PERN2': CDS_PINID='A_PERN2';
NODE_NAME     J111 E6
 '@T6G_MB_LIB.T6G(SCH_1):PAGE328_I38@PURE_QUANTA.CONN112_10137002101LF(CHIPS)':
 'E6': CDS_PINID='E6';
NET_NAME
'P5E_CPU1_P1_RX_BUF_DN<14>'
 '@T6G_MB_LIB.T6G(SCH_1):P5E_CPU1_P1_RX_BUF_DN'<14>:
 C_SIGNAL='@t6g_mb_lib.t6g(sch_1):p5e_cpu1_p1_rx_buf_dn(14)';
NODE_NAME     U6015 Y2
 '@T6G_MB_LIB.T6G(SCH_1):PAGE394_I1@PURE_QUANTA.PT5161LRS(CHIPS)':
 'A_PERN1': CDS_PINID='A_PERN1';
NODE_NAME     J111 F7
 '@T6G_MB_LIB.T6G(SCH_1):PAGE328_I38@PURE_QUANTA.CONN112_10137002101LF(CHIPS)':
 'F7': CDS_PINID='F7';
NET_NAME
'P5E_CPU1_P1_RX_BUF_DN<15>'
 '@T6G_MB_LIB.T6G(SCH_1):P5E_CPU1_P1_RX_BUF_DN'<15>:
 C_SIGNAL='@t6g_mb_lib.t6g(sch_1):p5e_cpu1_p1_rx_buf_dn(15)';
NODE_NAME     U6015 N2
 '@T6G_MB_LIB.T6G(SCH_1):PAGE394_I1@PURE_QUANTA.PT5161LRS(CHIPS)':
 'A_PERN0': CDS_PINID='A_PERN0';
NODE_NAME     J111 E8
 '@T6G_MB_LIB.T6G(SCH_1):PAGE328_I38@PURE_QUANTA.CONN112_10137002101LF(CHIPS)':
 'E8': CDS_PINID='E8';
NET_NAME
'P5E_CPU1_P1_RX_BUF_DN<1>'
 '@T6G_MB_LIB.T6G(SCH_1):P5E_CPU1_P1_RX_BUF_DN'<1>:
 C_SIGNAL='@t6g_mb_lib.t6g(sch_1):p5e_cpu1_p1_rx_buf_dn(1)';
NODE_NAME     U6015 EL2
 '@T6G_MB_LIB.T6G(SCH_1):PAGE394_I38@PURE_QUANTA.PT5161LRS(CHIPS)':
 'A_PERN14': CDS_PINID='A_PERN14';
NODE_NAME     J112 E2
 '@T6G_MB_LIB.T6G(SCH_1):PAGE329_I102@PURE_QUANTA.CONN160_10131762101LF(CHIPS)':
 'E2': CDS_PINID='E2';
NET_NAME
'P5E_CPU1_P1_RX_BUF_DN<2>'
 '@T6G_MB_LIB.T6G(SCH_1):P5E_CPU1_P1_RX_BUF_DN'<2>:
 C_SIGNAL='@t6g_mb_lib.t6g(sch_1):p5e_cpu1_p1_rx_buf_dn(2)';
NODE_NAME     U6015 ED2
 '@T6G_MB_LIB.T6G(SCH_1):PAGE394_I38@PURE_QUANTA.PT5161LRS(CHIPS)':
 'A_PERN13': CDS_PINID='A_PERN13';
NODE_NAME     J112 F3
 '@T6G_MB_LIB.T6G(SCH_1):PAGE329_I102@PURE_QUANTA.CONN160_10131762101LF(CHIPS)':
 'F3': CDS_PINID='F3';
NET_NAME
'P5E_CPU1_P1_RX_BUF_DN<3>'
 '@T6G_MB_LIB.T6G(SCH_1):P5E_CPU1_P1_RX_BUF_DN'<3>:
 C_SIGNAL='@t6g_mb_lib.t6g(sch_1):p5e_cpu1_p1_rx_buf_dn(3)';
NODE_NAME     U6015 DU2
 '@T6G_MB_LIB.T6G(SCH_1):PAGE394_I38@PURE_QUANTA.PT5161LRS(CHIPS)':
 'A_PERN12': CDS_PINID='A_PERN12';
NODE_NAME     J112 E4
 '@T6G_MB_LIB.T6G(SCH_1):PAGE329_I102@PURE_QUANTA.CONN160_10131762101LF(CHIPS)':
 'E4': CDS_PINID='E4';
NET_NAME
'P5E_CPU1_P1_RX_BUF_DN<4>'
 '@T6G_MB_LIB.T6G(SCH_1):P5E_CPU1_P1_RX_BUF_DN'<4>:
 C_SIGNAL='@t6g_mb_lib.t6g(sch_1):p5e_cpu1_p1_rx_buf_dn(4)';
NODE_NAME     U6015 DK2
 '@T6G_MB_LIB.T6G(SCH_1):PAGE394_I38@PURE_QUANTA.PT5161LRS(CHIPS)':
 'A_PERN11': CDS_PINID='A_PERN11';
NODE_NAME     J112 F5
 '@T6G_MB_LIB.T6G(SCH_1):PAGE329_I7@PURE_QUANTA.CONN160_10131762101LF(CHIPS)':
 'F5': CDS_PINID='F5';
NET_NAME
'P5E_CPU1_P1_RX_BUF_DN<5>'
 '@T6G_MB_LIB.T6G(SCH_1):P5E_CPU1_P1_RX_BUF_DN'<5>:
 C_SIGNAL='@t6g_mb_lib.t6g(sch_1):p5e_cpu1_p1_rx_buf_dn(5)';
NODE_NAME     U6015 DC2
 '@T6G_MB_LIB.T6G(SCH_1):PAGE394_I38@PURE_QUANTA.PT5161LRS(CHIPS)':
 'A_PERN10': CDS_PINID='A_PERN10';
NODE_NAME     J112 E6
 '@T6G_MB_LIB.T6G(SCH_1):PAGE329_I7@PURE_QUANTA.CONN160_10131762101LF(CHIPS)':
 'E6': CDS_PINID='E6';
NET_NAME
'P5E_CPU1_P1_RX_BUF_DN<6>'
 '@T6G_MB_LIB.T6G(SCH_1):P5E_CPU1_P1_RX_BUF_DN'<6>:
 C_SIGNAL='@t6g_mb_lib.t6g(sch_1):p5e_cpu1_p1_rx_buf_dn(6)';
NODE_NAME     U6015 CT2
 '@T6G_MB_LIB.T6G(SCH_1):PAGE394_I38@PURE_QUANTA.PT5161LRS(CHIPS)':
 'A_PERN9': CDS_PINID='A_PERN9';
NODE_NAME     J112 F7
 '@T6G_MB_LIB.T6G(SCH_1):PAGE329_I7@PURE_QUANTA.CONN160_10131762101LF(CHIPS)':
 'F7': CDS_PINID='F7';
NET_NAME
'P5E_CPU1_P1_RX_BUF_DN<7>'
 '@T6G_MB_LIB.T6G(SCH_1):P5E_CPU1_P1_RX_BUF_DN'<7>:
 C_SIGNAL='@t6g_mb_lib.t6g(sch_1):p5e_cpu1_p1_rx_buf_dn(7)';
NODE_NAME     U6015 CJ2
 '@T6G_MB_LIB.T6G(SCH_1):PAGE394_I38@PURE_QUANTA.PT5161LRS(CHIPS)':
 'A_PERN8': CDS_PINID='A_PERN8';
NODE_NAME     J112 E8
 '@T6G_MB_LIB.T6G(SCH_1):PAGE329_I7@PURE_QUANTA.CONN160_10131762101LF(CHIPS)':
 'E8': CDS_PINID='E8';
NET_NAME
'P5E_CPU1_P1_RX_BUF_DN<8>'
 '@T6G_MB_LIB.T6G(SCH_1):P5E_CPU1_P1_RX_BUF_DN'<8>:
 C_SIGNAL='@t6g_mb_lib.t6g(sch_1):p5e_cpu1_p1_rx_buf_dn(8)';
NODE_NAME     U6015 CB2
 '@T6G_MB_LIB.T6G(SCH_1):PAGE394_I1@PURE_QUANTA.PT5161LRS(CHIPS)':
 'A_PERN7': CDS_PINID='A_PERN7';
NODE_NAME     J111 F1
 '@T6G_MB_LIB.T6G(SCH_1):PAGE328_I76@PURE_QUANTA.CONN112_10137002101LF(CHIPS)':
 'F1': CDS_PINID='F1';
NET_NAME
'P5E_CPU1_P1_RX_BUF_DN<9>'
 '@T6G_MB_LIB.T6G(SCH_1):P5E_CPU1_P1_RX_BUF_DN'<9>:
 C_SIGNAL='@t6g_mb_lib.t6g(sch_1):p5e_cpu1_p1_rx_buf_dn(9)';
NODE_NAME     U6015 BR2
 '@T6G_MB_LIB.T6G(SCH_1):PAGE394_I1@PURE_QUANTA.PT5161LRS(CHIPS)':
 'A_PERN6': CDS_PINID='A_PERN6';
NODE_NAME     J111 E2
 '@T6G_MB_LIB.T6G(SCH_1):PAGE328_I76@PURE_QUANTA.CONN112_10137002101LF(CHIPS)':
 'E2': CDS_PINID='E2';
NET_NAME
'P5E_CPU1_P1_RX_BUF_DP<0>'
 '@T6G_MB_LIB.T6G(SCH_1):P5E_CPU1_P1_RX_BUF_DP'<0>:
 C_SIGNAL='@t6g_mb_lib.t6g(sch_1):p5e_cpu1_p1_rx_buf_dp(0)';
NODE_NAME     U6015 EY1
 '@T6G_MB_LIB.T6G(SCH_1):PAGE394_I38@PURE_QUANTA.PT5161LRS(CHIPS)':
 'A_PERP15': CDS_PINID='A_PERP15';
NODE_NAME     J112 G1
 '@T6G_MB_LIB.T6G(SCH_1):PAGE329_I102@PURE_QUANTA.CONN160_10131762101LF(CHIPS)':
 'G1': CDS_PINID='G1';
NET_NAME
'P5E_CPU1_P1_RX_BUF_DP<10>'
 '@T6G_MB_LIB.T6G(SCH_1):P5E_CPU1_P1_RX_BUF_DP'<10>:
 C_SIGNAL='@t6g_mb_lib.t6g(sch_1):p5e_cpu1_p1_rx_buf_dp(10)';
NODE_NAME     U6015 BK1
 '@T6G_MB_LIB.T6G(SCH_1):PAGE394_I1@PURE_QUANTA.PT5161LRS(CHIPS)':
 'A_PERP5': CDS_PINID='A_PERP5';
NODE_NAME     J111 G3
 '@T6G_MB_LIB.T6G(SCH_1):PAGE328_I76@PURE_QUANTA.CONN112_10137002101LF(CHIPS)':
 'G3': CDS_PINID='G3';
NET_NAME
'P5E_CPU1_P1_RX_BUF_DP<11>'
 '@T6G_MB_LIB.T6G(SCH_1):P5E_CPU1_P1_RX_BUF_DP'<11>:
 C_SIGNAL='@t6g_mb_lib.t6g(sch_1):p5e_cpu1_p1_rx_buf_dp(11)';
NODE_NAME     U6015 BC1
 '@T6G_MB_LIB.T6G(SCH_1):PAGE394_I1@PURE_QUANTA.PT5161LRS(CHIPS)':
 'A_PERP4': CDS_PINID='A_PERP4';
NODE_NAME     J111 F4
 '@T6G_MB_LIB.T6G(SCH_1):PAGE328_I76@PURE_QUANTA.CONN112_10137002101LF(CHIPS)':
 'F4': CDS_PINID='F4';
NET_NAME
'P5E_CPU1_P1_RX_BUF_DP<12>'
 '@T6G_MB_LIB.T6G(SCH_1):P5E_CPU1_P1_RX_BUF_DP'<12>:
 C_SIGNAL='@t6g_mb_lib.t6g(sch_1):p5e_cpu1_p1_rx_buf_dp(12)';
NODE_NAME     U6015 AT1
 '@T6G_MB_LIB.T6G(SCH_1):PAGE394_I1@PURE_QUANTA.PT5161LRS(CHIPS)':
 'A_PERP3': CDS_PINID='A_PERP3';
NODE_NAME     J111 G5
 '@T6G_MB_LIB.T6G(SCH_1):PAGE328_I38@PURE_QUANTA.CONN112_10137002101LF(CHIPS)':
 'G5': CDS_PINID='G5';
NET_NAME
'P5E_CPU1_P1_RX_BUF_DP<13>'
 '@T6G_MB_LIB.T6G(SCH_1):P5E_CPU1_P1_RX_BUF_DP'<13>:
 C_SIGNAL='@t6g_mb_lib.t6g(sch_1):p5e_cpu1_p1_rx_buf_dp(13)';
NODE_NAME     U6015 AJ1
 '@T6G_MB_LIB.T6G(SCH_1):PAGE394_I1@PURE_QUANTA.PT5161LRS(CHIPS)':
 'A_PERP2': CDS_PINID='A_PERP2';
NODE_NAME     J111 F6
 '@T6G_MB_LIB.T6G(SCH_1):PAGE328_I38@PURE_QUANTA.CONN112_10137002101LF(CHIPS)':
 'F6': CDS_PINID='F6';
NET_NAME
'P5E_CPU1_P1_RX_BUF_DP<14>'
 '@T6G_MB_LIB.T6G(SCH_1):P5E_CPU1_P1_RX_BUF_DP'<14>:
 C_SIGNAL='@t6g_mb_lib.t6g(sch_1):p5e_cpu1_p1_rx_buf_dp(14)';
NODE_NAME     U6015 AB1
 '@T6G_MB_LIB.T6G(SCH_1):PAGE394_I1@PURE_QUANTA.PT5161LRS(CHIPS)':
 'A_PERP1': CDS_PINID='A_PERP1';
NODE_NAME     J111 G7
 '@T6G_MB_LIB.T6G(SCH_1):PAGE328_I38@PURE_QUANTA.CONN112_10137002101LF(CHIPS)':
 'G7': CDS_PINID='G7';
NET_NAME
'P5E_CPU1_P1_RX_BUF_DP<15>'
 '@T6G_MB_LIB.T6G(SCH_1):P5E_CPU1_P1_RX_BUF_DP'<15>:
 C_SIGNAL='@t6g_mb_lib.t6g(sch_1):p5e_cpu1_p1_rx_buf_dp(15)';
NODE_NAME     U6015 R1
 '@T6G_MB_LIB.T6G(SCH_1):PAGE394_I1@PURE_QUANTA.PT5161LRS(CHIPS)':
 'A_PERP0': CDS_PINID='A_PERP0';
NODE_NAME     J111 F8
 '@T6G_MB_LIB.T6G(SCH_1):PAGE328_I38@PURE_QUANTA.CONN112_10137002101LF(CHIPS)':
 'F8': CDS_PINID='F8';
NET_NAME
'P5E_CPU1_P1_RX_BUF_DP<1>'
 '@T6G_MB_LIB.T6G(SCH_1):P5E_CPU1_P1_RX_BUF_DP'<1>:
 C_SIGNAL='@t6g_mb_lib.t6g(sch_1):p5e_cpu1_p1_rx_buf_dp(1)';
NODE_NAME     U6015 EN1
 '@T6G_MB_LIB.T6G(SCH_1):PAGE394_I38@PURE_QUANTA.PT5161LRS(CHIPS)':
 'A_PERP14': CDS_PINID='A_PERP14';
NODE_NAME     J112 F2
 '@T6G_MB_LIB.T6G(SCH_1):PAGE329_I102@PURE_QUANTA.CONN160_10131762101LF(CHIPS)':
 'F2': CDS_PINID='F2';
NET_NAME
'P5E_CPU1_P1_RX_BUF_DP<2>'
 '@T6G_MB_LIB.T6G(SCH_1):P5E_CPU1_P1_RX_BUF_DP'<2>:
 C_SIGNAL='@t6g_mb_lib.t6g(sch_1):p5e_cpu1_p1_rx_buf_dp(2)';
NODE_NAME     U6015 EF1
 '@T6G_MB_LIB.T6G(SCH_1):PAGE394_I38@PURE_QUANTA.PT5161LRS(CHIPS)':
 'A_PERP13': CDS_PINID='A_PERP13';
NODE_NAME     J112 G3
 '@T6G_MB_LIB.T6G(SCH_1):PAGE329_I102@PURE_QUANTA.CONN160_10131762101LF(CHIPS)':
 'G3': CDS_PINID='G3';
NET_NAME
'P5E_CPU1_P1_RX_BUF_DP<3>'
 '@T6G_MB_LIB.T6G(SCH_1):P5E_CPU1_P1_RX_BUF_DP'<3>:
 C_SIGNAL='@t6g_mb_lib.t6g(sch_1):p5e_cpu1_p1_rx_buf_dp(3)';
NODE_NAME     U6015 DW1
 '@T6G_MB_LIB.T6G(SCH_1):PAGE394_I38@PURE_QUANTA.PT5161LRS(CHIPS)':
 'A_PERP12': CDS_PINID='A_PERP12';
NODE_NAME     J112 F4
 '@T6G_MB_LIB.T6G(SCH_1):PAGE329_I102@PURE_QUANTA.CONN160_10131762101LF(CHIPS)':
 'F4': CDS_PINID='F4';
NET_NAME
'P5E_CPU1_P1_RX_BUF_DP<4>'
 '@T6G_MB_LIB.T6G(SCH_1):P5E_CPU1_P1_RX_BUF_DP'<4>:
 C_SIGNAL='@t6g_mb_lib.t6g(sch_1):p5e_cpu1_p1_rx_buf_dp(4)';
NODE_NAME     U6015 DM1
 '@T6G_MB_LIB.T6G(SCH_1):PAGE394_I38@PURE_QUANTA.PT5161LRS(CHIPS)':
 'A_PERP11': CDS_PINID='A_PERP11';
NODE_NAME     J112 G5
 '@T6G_MB_LIB.T6G(SCH_1):PAGE329_I7@PURE_QUANTA.CONN160_10131762101LF(CHIPS)':
 'G5': CDS_PINID='G5';
NET_NAME
'P5E_CPU1_P1_RX_BUF_DP<5>'
 '@T6G_MB_LIB.T6G(SCH_1):P5E_CPU1_P1_RX_BUF_DP'<5>:
 C_SIGNAL='@t6g_mb_lib.t6g(sch_1):p5e_cpu1_p1_rx_buf_dp(5)';
NODE_NAME     U6015 DE1
 '@T6G_MB_LIB.T6G(SCH_1):PAGE394_I38@PURE_QUANTA.PT5161LRS(CHIPS)':
 'A_PERP10': CDS_PINID='A_PERP10';
NODE_NAME     J112 F6
 '@T6G_MB_LIB.T6G(SCH_1):PAGE329_I7@PURE_QUANTA.CONN160_10131762101LF(CHIPS)':
 'F6': CDS_PINID='F6';
NET_NAME
'P5E_CPU1_P1_RX_BUF_DP<6>'
 '@T6G_MB_LIB.T6G(SCH_1):P5E_CPU1_P1_RX_BUF_DP'<6>:
 C_SIGNAL='@t6g_mb_lib.t6g(sch_1):p5e_cpu1_p1_rx_buf_dp(6)';
NODE_NAME     U6015 CV1
 '@T6G_MB_LIB.T6G(SCH_1):PAGE394_I38@PURE_QUANTA.PT5161LRS(CHIPS)':
 'A_PERP9': CDS_PINID='A_PERP9';
NODE_NAME     J112 G7
 '@T6G_MB_LIB.T6G(SCH_1):PAGE329_I7@PURE_QUANTA.CONN160_10131762101LF(CHIPS)':
 'G7': CDS_PINID='G7';
NET_NAME
'P5E_CPU1_P1_RX_BUF_DP<7>'
 '@T6G_MB_LIB.T6G(SCH_1):P5E_CPU1_P1_RX_BUF_DP'<7>:
 C_SIGNAL='@t6g_mb_lib.t6g(sch_1):p5e_cpu1_p1_rx_buf_dp(7)';
NODE_NAME     U6015 CL1
 '@T6G_MB_LIB.T6G(SCH_1):PAGE394_I38@PURE_QUANTA.PT5161LRS(CHIPS)':
 'A_PERP8': CDS_PINID='A_PERP8';
NODE_NAME     J112 F8
 '@T6G_MB_LIB.T6G(SCH_1):PAGE329_I7@PURE_QUANTA.CONN160_10131762101LF(CHIPS)':
 'F8': CDS_PINID='F8';
NET_NAME
'P5E_CPU1_P1_RX_BUF_DP<8>'
 '@T6G_MB_LIB.T6G(SCH_1):P5E_CPU1_P1_RX_BUF_DP'<8>:
 C_SIGNAL='@t6g_mb_lib.t6g(sch_1):p5e_cpu1_p1_rx_buf_dp(8)';
NODE_NAME     U6015 CD1
 '@T6G_MB_LIB.T6G(SCH_1):PAGE394_I1@PURE_QUANTA.PT5161LRS(CHIPS)':
 'A_PERP7': CDS_PINID='A_PERP7';
NODE_NAME     J111 G1
 '@T6G_MB_LIB.T6G(SCH_1):PAGE328_I76@PURE_QUANTA.CONN112_10137002101LF(CHIPS)':
 'G1': CDS_PINID='G1';
NET_NAME
'P5E_CPU1_P1_RX_BUF_DP<9>'
 '@T6G_MB_LIB.T6G(SCH_1):P5E_CPU1_P1_RX_BUF_DP'<9>:
 C_SIGNAL='@t6g_mb_lib.t6g(sch_1):p5e_cpu1_p1_rx_buf_dp(9)';
NODE_NAME     U6015 BU1
 '@T6G_MB_LIB.T6G(SCH_1):PAGE394_I1@PURE_QUANTA.PT5161LRS(CHIPS)':
 'A_PERP6': CDS_PINID='A_PERP6';
NODE_NAME     J111 F2
 '@T6G_MB_LIB.T6G(SCH_1):PAGE328_I76@PURE_QUANTA.CONN112_10137002101LF(CHIPS)':
 'F2': CDS_PINID='F2';
NET_NAME
'P5E_CPU1_P1_RX_DN<0>'
 '@T6G_MB_LIB.T6G(SCH_1):P5E_CPU1_P1_RX_DN'<0>:
 C_SIGNAL='@t6g_mb_lib.t6g(sch_1):p5e_cpu1_p1_rx_dn(0)';
NODE_NAME     U26 CE53
 '@T6G_MB_LIB.T6G(SCH_1):PAGE51_I148@PURE_QUANTA.GENOA_SP5(CHIPS)':
 'P1_RXN0': CDS_PINID='P1_RXN0';
NODE_NAME     U6015 EW29
 '@T6G_MB_LIB.T6G(SCH_1):PAGE395_I38@PURE_QUANTA.PT5161LRS(CHIPS)':
 'A_PETN15': CDS_PINID='A_PETN15';
NET_NAME
'P5E_CPU1_P1_RX_DN<10>'
 '@T6G_MB_LIB.T6G(SCH_1):P5E_CPU1_P1_RX_DN'<10>:
 C_SIGNAL='@t6g_mb_lib.t6g(sch_1):p5e_cpu1_p1_rx_dn(10)';
NODE_NAME     U26 CG44
 '@T6G_MB_LIB.T6G(SCH_1):PAGE51_I148@PURE_QUANTA.GENOA_SP5(CHIPS)':
 'P1_RXN10': CDS_PINID='P1_RXN10';
NODE_NAME     U6015 BJ29
 '@T6G_MB_LIB.T6G(SCH_1):PAGE395_I1@PURE_QUANTA.PT5161LRS(CHIPS)':
 'A_PETN5': CDS_PINID='A_PETN5';
NET_NAME
'P5E_CPU1_P1_RX_DN<11>'
 '@T6G_MB_LIB.T6G(SCH_1):P5E_CPU1_P1_RX_DN'<11>:
 C_SIGNAL='@t6g_mb_lib.t6g(sch_1):p5e_cpu1_p1_rx_dn(11)';
NODE_NAME     U26 CJ44
 '@T6G_MB_LIB.T6G(SCH_1):PAGE51_I148@PURE_QUANTA.GENOA_SP5(CHIPS)':
 'P1_RXN11': CDS_PINID='P1_RXN11';
NODE_NAME     U6015 BB29
 '@T6G_MB_LIB.T6G(SCH_1):PAGE395_I1@PURE_QUANTA.PT5161LRS(CHIPS)':
 'A_PETN4': CDS_PINID='A_PETN4';
NET_NAME
'P5E_CPU1_P1_RX_DN<12>'
 '@T6G_MB_LIB.T6G(SCH_1):P5E_CPU1_P1_RX_DN'<12>:
 C_SIGNAL='@t6g_mb_lib.t6g(sch_1):p5e_cpu1_p1_rx_dn(12)';
NODE_NAME     U26 CC44
 '@T6G_MB_LIB.T6G(SCH_1):PAGE51_I148@PURE_QUANTA.GENOA_SP5(CHIPS)':
 'P1_RXN12': CDS_PINID='P1_RXN12';
NODE_NAME     U6015 AR29
 '@T6G_MB_LIB.T6G(SCH_1):PAGE395_I1@PURE_QUANTA.PT5161LRS(CHIPS)':
 'A_PETN3': CDS_PINID='A_PETN3';
NET_NAME
'P5E_CPU1_P1_RX_DN<13>'
 '@T6G_MB_LIB.T6G(SCH_1):P5E_CPU1_P1_RX_DN'<13>:
 C_SIGNAL='@t6g_mb_lib.t6g(sch_1):p5e_cpu1_p1_rx_dn(13)';
NODE_NAME     U26 CH41
 '@T6G_MB_LIB.T6G(SCH_1):PAGE51_I148@PURE_QUANTA.GENOA_SP5(CHIPS)':
 'P1_RXN13': CDS_PINID='P1_RXN13';
NODE_NAME     U6015 AH29
 '@T6G_MB_LIB.T6G(SCH_1):PAGE395_I1@PURE_QUANTA.PT5161LRS(CHIPS)':
 'A_PETN2': CDS_PINID='A_PETN2';
NET_NAME
'P5E_CPU1_P1_RX_DN<14>'
 '@T6G_MB_LIB.T6G(SCH_1):P5E_CPU1_P1_RX_DN'<14>:
 C_SIGNAL='@t6g_mb_lib.t6g(sch_1):p5e_cpu1_p1_rx_dn(14)';
NODE_NAME     U26 CF41
 '@T6G_MB_LIB.T6G(SCH_1):PAGE51_I148@PURE_QUANTA.GENOA_SP5(CHIPS)':
 'P1_RXN14': CDS_PINID='P1_RXN14';
NODE_NAME     U6015 AA29
 '@T6G_MB_LIB.T6G(SCH_1):PAGE395_I1@PURE_QUANTA.PT5161LRS(CHIPS)':
 'A_PETN1': CDS_PINID='A_PETN1';
NET_NAME
'P5E_CPU1_P1_RX_DN<15>'
 '@T6G_MB_LIB.T6G(SCH_1):P5E_CPU1_P1_RX_DN'<15>:
 C_SIGNAL='@t6g_mb_lib.t6g(sch_1):p5e_cpu1_p1_rx_dn(15)';
NODE_NAME     U26 CD41
 '@T6G_MB_LIB.T6G(SCH_1):PAGE51_I148@PURE_QUANTA.GENOA_SP5(CHIPS)':
 'P1_RXN15': CDS_PINID='P1_RXN15';
NODE_NAME     U6015 P29
 '@T6G_MB_LIB.T6G(SCH_1):PAGE395_I1@PURE_QUANTA.PT5161LRS(CHIPS)':
 'A_PETN0': CDS_PINID='A_PETN0';
NET_NAME
'P5E_CPU1_P1_RX_DN<1>'
 '@T6G_MB_LIB.T6G(SCH_1):P5E_CPU1_P1_RX_DN'<1>:
 C_SIGNAL='@t6g_mb_lib.t6g(sch_1):p5e_cpu1_p1_rx_dn(1)';
NODE_NAME     U26 CG53
 '@T6G_MB_LIB.T6G(SCH_1):PAGE51_I148@PURE_QUANTA.GENOA_SP5(CHIPS)':
 'P1_RXN1': CDS_PINID='P1_RXN1';
NODE_NAME     U6015 EM29
 '@T6G_MB_LIB.T6G(SCH_1):PAGE395_I38@PURE_QUANTA.PT5161LRS(CHIPS)':
 'A_PETN14': CDS_PINID='A_PETN14';
NET_NAME
'P5E_CPU1_P1_RX_DN<2>'
 '@T6G_MB_LIB.T6G(SCH_1):P5E_CPU1_P1_RX_DN'<2>:
 C_SIGNAL='@t6g_mb_lib.t6g(sch_1):p5e_cpu1_p1_rx_dn(2)';
NODE_NAME     U26 CC53
 '@T6G_MB_LIB.T6G(SCH_1):PAGE51_I148@PURE_QUANTA.GENOA_SP5(CHIPS)':
 'P1_RXN2': CDS_PINID='P1_RXN2';
NODE_NAME     U6015 EE29
 '@T6G_MB_LIB.T6G(SCH_1):PAGE395_I38@PURE_QUANTA.PT5161LRS(CHIPS)':
 'A_PETN13': CDS_PINID='A_PETN13';
NET_NAME
'P5E_CPU1_P1_RX_DN<3>'
 '@T6G_MB_LIB.T6G(SCH_1):P5E_CPU1_P1_RX_DN'<3>:
 C_SIGNAL='@t6g_mb_lib.t6g(sch_1):p5e_cpu1_p1_rx_dn(3)';
NODE_NAME     U26 CE50
 '@T6G_MB_LIB.T6G(SCH_1):PAGE51_I148@PURE_QUANTA.GENOA_SP5(CHIPS)':
 'P1_RXN3': CDS_PINID='P1_RXN3';
NODE_NAME     U6015 DV29
 '@T6G_MB_LIB.T6G(SCH_1):PAGE395_I38@PURE_QUANTA.PT5161LRS(CHIPS)':
 'A_PETN12': CDS_PINID='A_PETN12';
NET_NAME
'P5E_CPU1_P1_RX_DN<4>'
 '@T6G_MB_LIB.T6G(SCH_1):P5E_CPU1_P1_RX_DN'<4>:
 C_SIGNAL='@t6g_mb_lib.t6g(sch_1):p5e_cpu1_p1_rx_dn(4)';
NODE_NAME     U26 CG50
 '@T6G_MB_LIB.T6G(SCH_1):PAGE51_I148@PURE_QUANTA.GENOA_SP5(CHIPS)':
 'P1_RXN4': CDS_PINID='P1_RXN4';
NODE_NAME     U6015 DL29
 '@T6G_MB_LIB.T6G(SCH_1):PAGE395_I38@PURE_QUANTA.PT5161LRS(CHIPS)':
 'A_PETN11': CDS_PINID='A_PETN11';
NET_NAME
'P5E_CPU1_P1_RX_DN<5>'
 '@T6G_MB_LIB.T6G(SCH_1):P5E_CPU1_P1_RX_DN'<5>:
 C_SIGNAL='@t6g_mb_lib.t6g(sch_1):p5e_cpu1_p1_rx_dn(5)';
NODE_NAME     U26 CC50
 '@T6G_MB_LIB.T6G(SCH_1):PAGE51_I148@PURE_QUANTA.GENOA_SP5(CHIPS)':
 'P1_RXN5': CDS_PINID='P1_RXN5';
NODE_NAME     U6015 DD29
 '@T6G_MB_LIB.T6G(SCH_1):PAGE395_I38@PURE_QUANTA.PT5161LRS(CHIPS)':
 'A_PETN10': CDS_PINID='A_PETN10';
NET_NAME
'P5E_CPU1_P1_RX_DN<6>'
 '@T6G_MB_LIB.T6G(SCH_1):P5E_CPU1_P1_RX_DN'<6>:
 C_SIGNAL='@t6g_mb_lib.t6g(sch_1):p5e_cpu1_p1_rx_dn(6)';
NODE_NAME     U26 CE47
 '@T6G_MB_LIB.T6G(SCH_1):PAGE51_I148@PURE_QUANTA.GENOA_SP5(CHIPS)':
 'P1_RXN6': CDS_PINID='P1_RXN6';
NODE_NAME     U6015 CU29
 '@T6G_MB_LIB.T6G(SCH_1):PAGE395_I38@PURE_QUANTA.PT5161LRS(CHIPS)':
 'A_PETN9': CDS_PINID='A_PETN9';
NET_NAME
'P5E_CPU1_P1_RX_DN<7>'
 '@T6G_MB_LIB.T6G(SCH_1):P5E_CPU1_P1_RX_DN'<7>:
 C_SIGNAL='@t6g_mb_lib.t6g(sch_1):p5e_cpu1_p1_rx_dn(7)';
NODE_NAME     U26 CG47
 '@T6G_MB_LIB.T6G(SCH_1):PAGE51_I148@PURE_QUANTA.GENOA_SP5(CHIPS)':
 'P1_RXN7': CDS_PINID='P1_RXN7';
NODE_NAME     U6015 CK29
 '@T6G_MB_LIB.T6G(SCH_1):PAGE395_I38@PURE_QUANTA.PT5161LRS(CHIPS)':
 'A_PETN8': CDS_PINID='A_PETN8';
NET_NAME
'P5E_CPU1_P1_RX_DN<8>'
 '@T6G_MB_LIB.T6G(SCH_1):P5E_CPU1_P1_RX_DN'<8>:
 C_SIGNAL='@t6g_mb_lib.t6g(sch_1):p5e_cpu1_p1_rx_dn(8)';
NODE_NAME     U26 CC47
 '@T6G_MB_LIB.T6G(SCH_1):PAGE51_I148@PURE_QUANTA.GENOA_SP5(CHIPS)':
 'P1_RXN8': CDS_PINID='P1_RXN8';
NODE_NAME     U6015 CC29
 '@T6G_MB_LIB.T6G(SCH_1):PAGE395_I1@PURE_QUANTA.PT5161LRS(CHIPS)':
 'A_PETN7': CDS_PINID='A_PETN7';
NET_NAME
'P5E_CPU1_P1_RX_DN<9>'
 '@T6G_MB_LIB.T6G(SCH_1):P5E_CPU1_P1_RX_DN'<9>:
 C_SIGNAL='@t6g_mb_lib.t6g(sch_1):p5e_cpu1_p1_rx_dn(9)';
NODE_NAME     U26 CE44
 '@T6G_MB_LIB.T6G(SCH_1):PAGE51_I148@PURE_QUANTA.GENOA_SP5(CHIPS)':
 'P1_RXN9': CDS_PINID='P1_RXN9';
NODE_NAME     U6015 BT29
 '@T6G_MB_LIB.T6G(SCH_1):PAGE395_I1@PURE_QUANTA.PT5161LRS(CHIPS)':
 'A_PETN6': CDS_PINID='A_PETN6';
NET_NAME
'P5E_CPU1_P1_RX_DP<0>'
 '@T6G_MB_LIB.T6G(SCH_1):P5E_CPU1_P1_RX_DP'<0>:
 C_SIGNAL='@t6g_mb_lib.t6g(sch_1):p5e_cpu1_p1_rx_dp(0)';
NODE_NAME     U26 CE52
 '@T6G_MB_LIB.T6G(SCH_1):PAGE51_I148@PURE_QUANTA.GENOA_SP5(CHIPS)':
 'P1_RXP0': CDS_PINID='P1_RXP0';
NODE_NAME     U6015 EU26
 '@T6G_MB_LIB.T6G(SCH_1):PAGE395_I38@PURE_QUANTA.PT5161LRS(CHIPS)':
 'A_PETP15': CDS_PINID='A_PETP15';
NET_NAME
'P5E_CPU1_P1_RX_DP<10>'
 '@T6G_MB_LIB.T6G(SCH_1):P5E_CPU1_P1_RX_DP'<10>:
 C_SIGNAL='@t6g_mb_lib.t6g(sch_1):p5e_cpu1_p1_rx_dp(10)';
NODE_NAME     U26 CG43
 '@T6G_MB_LIB.T6G(SCH_1):PAGE51_I148@PURE_QUANTA.GENOA_SP5(CHIPS)':
 'P1_RXP10': CDS_PINID='P1_RXP10';
NODE_NAME     U6015 BG26
 '@T6G_MB_LIB.T6G(SCH_1):PAGE395_I1@PURE_QUANTA.PT5161LRS(CHIPS)':
 'A_PETP5': CDS_PINID='A_PETP5';
NET_NAME
'P5E_CPU1_P1_RX_DP<11>'
 '@T6G_MB_LIB.T6G(SCH_1):P5E_CPU1_P1_RX_DP'<11>:
 C_SIGNAL='@t6g_mb_lib.t6g(sch_1):p5e_cpu1_p1_rx_dp(11)';
NODE_NAME     U26 CJ43
 '@T6G_MB_LIB.T6G(SCH_1):PAGE51_I148@PURE_QUANTA.GENOA_SP5(CHIPS)':
 'P1_RXP11': CDS_PINID='P1_RXP11';
NODE_NAME     U6015 AY26
 '@T6G_MB_LIB.T6G(SCH_1):PAGE395_I1@PURE_QUANTA.PT5161LRS(CHIPS)':
 'A_PETP4': CDS_PINID='A_PETP4';
NET_NAME
'P5E_CPU1_P1_RX_DP<12>'
 '@T6G_MB_LIB.T6G(SCH_1):P5E_CPU1_P1_RX_DP'<12>:
 C_SIGNAL='@t6g_mb_lib.t6g(sch_1):p5e_cpu1_p1_rx_dp(12)';
NODE_NAME     U26 CC43
 '@T6G_MB_LIB.T6G(SCH_1):PAGE51_I148@PURE_QUANTA.GENOA_SP5(CHIPS)':
 'P1_RXP12': CDS_PINID='P1_RXP12';
NODE_NAME     U6015 AN26
 '@T6G_MB_LIB.T6G(SCH_1):PAGE395_I1@PURE_QUANTA.PT5161LRS(CHIPS)':
 'A_PETP3': CDS_PINID='A_PETP3';
NET_NAME
'P5E_CPU1_P1_RX_DP<13>'
 '@T6G_MB_LIB.T6G(SCH_1):P5E_CPU1_P1_RX_DP'<13>:
 C_SIGNAL='@t6g_mb_lib.t6g(sch_1):p5e_cpu1_p1_rx_dp(13)';
NODE_NAME     U26 CH40
 '@T6G_MB_LIB.T6G(SCH_1):PAGE51_I148@PURE_QUANTA.GENOA_SP5(CHIPS)':
 'P1_RXP13': CDS_PINID='P1_RXP13';
NODE_NAME     U6015 AF26
 '@T6G_MB_LIB.T6G(SCH_1):PAGE395_I1@PURE_QUANTA.PT5161LRS(CHIPS)':
 'A_PETP2': CDS_PINID='A_PETP2';
NET_NAME
'P5E_CPU1_P1_RX_DP<14>'
 '@T6G_MB_LIB.T6G(SCH_1):P5E_CPU1_P1_RX_DP'<14>:
 C_SIGNAL='@t6g_mb_lib.t6g(sch_1):p5e_cpu1_p1_rx_dp(14)';
NODE_NAME     U26 CF40
 '@T6G_MB_LIB.T6G(SCH_1):PAGE51_I148@PURE_QUANTA.GENOA_SP5(CHIPS)':
 'P1_RXP14': CDS_PINID='P1_RXP14';
NODE_NAME     U6015 W26
 '@T6G_MB_LIB.T6G(SCH_1):PAGE395_I1@PURE_QUANTA.PT5161LRS(CHIPS)':
 'A_PETP1': CDS_PINID='A_PETP1';
NET_NAME
'P5E_CPU1_P1_RX_DP<15>'
 '@T6G_MB_LIB.T6G(SCH_1):P5E_CPU1_P1_RX_DP'<15>:
 C_SIGNAL='@t6g_mb_lib.t6g(sch_1):p5e_cpu1_p1_rx_dp(15)';
NODE_NAME     U26 CD40
 '@T6G_MB_LIB.T6G(SCH_1):PAGE51_I148@PURE_QUANTA.GENOA_SP5(CHIPS)':
 'P1_RXP15': CDS_PINID='P1_RXP15';
NODE_NAME     U6015 M26
 '@T6G_MB_LIB.T6G(SCH_1):PAGE395_I1@PURE_QUANTA.PT5161LRS(CHIPS)':
 'A_PETP0': CDS_PINID='A_PETP0';
NET_NAME
'P5E_CPU1_P1_RX_DP<1>'
 '@T6G_MB_LIB.T6G(SCH_1):P5E_CPU1_P1_RX_DP'<1>:
 C_SIGNAL='@t6g_mb_lib.t6g(sch_1):p5e_cpu1_p1_rx_dp(1)';
NODE_NAME     U26 CG52
 '@T6G_MB_LIB.T6G(SCH_1):PAGE51_I148@PURE_QUANTA.GENOA_SP5(CHIPS)':
 'P1_RXP1': CDS_PINID='P1_RXP1';
NODE_NAME     U6015 EK26
 '@T6G_MB_LIB.T6G(SCH_1):PAGE395_I38@PURE_QUANTA.PT5161LRS(CHIPS)':
 'A_PETP14': CDS_PINID='A_PETP14';
NET_NAME
'P5E_CPU1_P1_RX_DP<2>'
 '@T6G_MB_LIB.T6G(SCH_1):P5E_CPU1_P1_RX_DP'<2>:
 C_SIGNAL='@t6g_mb_lib.t6g(sch_1):p5e_cpu1_p1_rx_dp(2)';
NODE_NAME     U26 CC52
 '@T6G_MB_LIB.T6G(SCH_1):PAGE51_I148@PURE_QUANTA.GENOA_SP5(CHIPS)':
 'P1_RXP2': CDS_PINID='P1_RXP2';
NODE_NAME     U6015 EC26
 '@T6G_MB_LIB.T6G(SCH_1):PAGE395_I38@PURE_QUANTA.PT5161LRS(CHIPS)':
 'A_PETP13': CDS_PINID='A_PETP13';
NET_NAME
'P5E_CPU1_P1_RX_DP<3>'
 '@T6G_MB_LIB.T6G(SCH_1):P5E_CPU1_P1_RX_DP'<3>:
 C_SIGNAL='@t6g_mb_lib.t6g(sch_1):p5e_cpu1_p1_rx_dp(3)';
NODE_NAME     U26 CE49
 '@T6G_MB_LIB.T6G(SCH_1):PAGE51_I148@PURE_QUANTA.GENOA_SP5(CHIPS)':
 'P1_RXP3': CDS_PINID='P1_RXP3';
NODE_NAME     U6015 DT26
 '@T6G_MB_LIB.T6G(SCH_1):PAGE395_I38@PURE_QUANTA.PT5161LRS(CHIPS)':
 'A_PETP12': CDS_PINID='A_PETP12';
NET_NAME
'P5E_CPU1_P1_RX_DP<4>'
 '@T6G_MB_LIB.T6G(SCH_1):P5E_CPU1_P1_RX_DP'<4>:
 C_SIGNAL='@t6g_mb_lib.t6g(sch_1):p5e_cpu1_p1_rx_dp(4)';
NODE_NAME     U26 CG49
 '@T6G_MB_LIB.T6G(SCH_1):PAGE51_I148@PURE_QUANTA.GENOA_SP5(CHIPS)':
 'P1_RXP4': CDS_PINID='P1_RXP4';
NODE_NAME     U6015 DJ26
 '@T6G_MB_LIB.T6G(SCH_1):PAGE395_I38@PURE_QUANTA.PT5161LRS(CHIPS)':
 'A_PETP11': CDS_PINID='A_PETP11';
NET_NAME
'P5E_CPU1_P1_RX_DP<5>'
 '@T6G_MB_LIB.T6G(SCH_1):P5E_CPU1_P1_RX_DP'<5>:
 C_SIGNAL='@t6g_mb_lib.t6g(sch_1):p5e_cpu1_p1_rx_dp(5)';
NODE_NAME     U26 CC49
 '@T6G_MB_LIB.T6G(SCH_1):PAGE51_I148@PURE_QUANTA.GENOA_SP5(CHIPS)':
 'P1_RXP5': CDS_PINID='P1_RXP5';
NODE_NAME     U6015 DB26
 '@T6G_MB_LIB.T6G(SCH_1):PAGE395_I38@PURE_QUANTA.PT5161LRS(CHIPS)':
 'A_PETP10': CDS_PINID='A_PETP10';
NET_NAME
'P5E_CPU1_P1_RX_DP<6>'
 '@T6G_MB_LIB.T6G(SCH_1):P5E_CPU1_P1_RX_DP'<6>:
 C_SIGNAL='@t6g_mb_lib.t6g(sch_1):p5e_cpu1_p1_rx_dp(6)';
NODE_NAME     U26 CE46
 '@T6G_MB_LIB.T6G(SCH_1):PAGE51_I148@PURE_QUANTA.GENOA_SP5(CHIPS)':
 'P1_RXP6': CDS_PINID='P1_RXP6';
NODE_NAME     U6015 CR26
 '@T6G_MB_LIB.T6G(SCH_1):PAGE395_I38@PURE_QUANTA.PT5161LRS(CHIPS)':
 'A_PETP9': CDS_PINID='A_PETP9';
NET_NAME
'P5E_CPU1_P1_RX_DP<7>'
 '@T6G_MB_LIB.T6G(SCH_1):P5E_CPU1_P1_RX_DP'<7>:
 C_SIGNAL='@t6g_mb_lib.t6g(sch_1):p5e_cpu1_p1_rx_dp(7)';
NODE_NAME     U26 CG46
 '@T6G_MB_LIB.T6G(SCH_1):PAGE51_I148@PURE_QUANTA.GENOA_SP5(CHIPS)':
 'P1_RXP7': CDS_PINID='P1_RXP7';
NODE_NAME     U6015 CH26
 '@T6G_MB_LIB.T6G(SCH_1):PAGE395_I38@PURE_QUANTA.PT5161LRS(CHIPS)':
 'A_PETP8': CDS_PINID='A_PETP8';
NET_NAME
'P5E_CPU1_P1_RX_DP<8>'
 '@T6G_MB_LIB.T6G(SCH_1):P5E_CPU1_P1_RX_DP'<8>:
 C_SIGNAL='@t6g_mb_lib.t6g(sch_1):p5e_cpu1_p1_rx_dp(8)';
NODE_NAME     U26 CC46
 '@T6G_MB_LIB.T6G(SCH_1):PAGE51_I148@PURE_QUANTA.GENOA_SP5(CHIPS)':
 'P1_RXP8': CDS_PINID='P1_RXP8';
NODE_NAME     U6015 CA26
 '@T6G_MB_LIB.T6G(SCH_1):PAGE395_I1@PURE_QUANTA.PT5161LRS(CHIPS)':
 'A_PETP7': CDS_PINID='A_PETP7';
NET_NAME
'P5E_CPU1_P1_RX_DP<9>'
 '@T6G_MB_LIB.T6G(SCH_1):P5E_CPU1_P1_RX_DP'<9>:
 C_SIGNAL='@t6g_mb_lib.t6g(sch_1):p5e_cpu1_p1_rx_dp(9)';
NODE_NAME     U26 CE43
 '@T6G_MB_LIB.T6G(SCH_1):PAGE51_I148@PURE_QUANTA.GENOA_SP5(CHIPS)':
 'P1_RXP9': CDS_PINID='P1_RXP9';
NODE_NAME     U6015 BP26
 '@T6G_MB_LIB.T6G(SCH_1):PAGE395_I1@PURE_QUANTA.PT5161LRS(CHIPS)':
 'A_PETP6': CDS_PINID='A_PETP6';
NET_NAME
'P5E_CPU1_P1_TX_BUF_C_DN<0>'
 '@T6G_MB_LIB.T6G(SCH_1):P5E_CPU1_P1_TX_BUF_C_DN'<0>:
 C_SIGNAL='@t6g_mb_lib.t6g(sch_1):p5e_cpu1_p1_tx_buf_c_dn(0)';
NODE_NAME     C6662 1
 '@T6G_MB_LIB.T6G(SCH_1):PAGE393_I33@PURE_QUANTA.Q_CAP_DIFFBUS(CHIPS)':
 '1': CDS_PINID='\1\';
NODE_NAME     J112 L1
 '@T6G_MB_LIB.T6G(SCH_1):PAGE329_I102@PURE_QUANTA.CONN160_10131762101LF(CHIPS)':
 'L1': CDS_PINID='L1';
NET_NAME
'P5E_CPU1_P1_TX_BUF_C_DN<10>'
 '@T6G_MB_LIB.T6G(SCH_1):P5E_CPU1_P1_TX_BUF_C_DN'<10>:
 C_SIGNAL='@t6g_mb_lib.t6g(sch_1):p5e_cpu1_p1_tx_buf_c_dn(10)';
NODE_NAME     C6682 1
 '@T6G_MB_LIB.T6G(SCH_1):PAGE393_I100@PURE_QUANTA.Q_CAP_DIFFBUS(CHIPS)':
 '1': CDS_PINID='\1\';
NODE_NAME     J111 L3
 '@T6G_MB_LIB.T6G(SCH_1):PAGE328_I76@PURE_QUANTA.CONN112_10137002101LF(CHIPS)':
 'L3': CDS_PINID='L3';
NET_NAME
'P5E_CPU1_P1_TX_BUF_C_DN<11>'
 '@T6G_MB_LIB.T6G(SCH_1):P5E_CPU1_P1_TX_BUF_C_DN'<11>:
 C_SIGNAL='@t6g_mb_lib.t6g(sch_1):p5e_cpu1_p1_tx_buf_c_dn(11)';
NODE_NAME     C6684 1
 '@T6G_MB_LIB.T6G(SCH_1):PAGE393_I97@PURE_QUANTA.Q_CAP_DIFFBUS(CHIPS)':
 '1': CDS_PINID='\1\';
NODE_NAME     J111 K4
 '@T6G_MB_LIB.T6G(SCH_1):PAGE328_I76@PURE_QUANTA.CONN112_10137002101LF(CHIPS)':
 'K4': CDS_PINID='K4';
NET_NAME
'P5E_CPU1_P1_TX_BUF_C_DN<12>'
 '@T6G_MB_LIB.T6G(SCH_1):P5E_CPU1_P1_TX_BUF_C_DN'<12>:
 C_SIGNAL='@t6g_mb_lib.t6g(sch_1):p5e_cpu1_p1_tx_buf_c_dn(12)';
NODE_NAME     C6686 1
 '@T6G_MB_LIB.T6G(SCH_1):PAGE393_I95@PURE_QUANTA.Q_CAP_DIFFBUS(CHIPS)':
 '1': CDS_PINID='\1\';
NODE_NAME     J111 L5
 '@T6G_MB_LIB.T6G(SCH_1):PAGE328_I38@PURE_QUANTA.CONN112_10137002101LF(CHIPS)':
 'L5': CDS_PINID='L5';
NET_NAME
'P5E_CPU1_P1_TX_BUF_C_DN<13>'
 '@T6G_MB_LIB.T6G(SCH_1):P5E_CPU1_P1_TX_BUF_C_DN'<13>:
 C_SIGNAL='@t6g_mb_lib.t6g(sch_1):p5e_cpu1_p1_tx_buf_c_dn(13)';
NODE_NAME     C6688 1
 '@T6G_MB_LIB.T6G(SCH_1):PAGE393_I88@PURE_QUANTA.Q_CAP_DIFFBUS(CHIPS)':
 '1': CDS_PINID='\1\';
NODE_NAME     J111 K6
 '@T6G_MB_LIB.T6G(SCH_1):PAGE328_I38@PURE_QUANTA.CONN112_10137002101LF(CHIPS)':
 'K6': CDS_PINID='K6';
NET_NAME
'P5E_CPU1_P1_TX_BUF_C_DN<14>'
 '@T6G_MB_LIB.T6G(SCH_1):P5E_CPU1_P1_TX_BUF_C_DN'<14>:
 C_SIGNAL='@t6g_mb_lib.t6g(sch_1):p5e_cpu1_p1_tx_buf_c_dn(14)';
NODE_NAME     C6690 1
 '@T6G_MB_LIB.T6G(SCH_1):PAGE393_I86@PURE_QUANTA.Q_CAP_DIFFBUS(CHIPS)':
 '1': CDS_PINID='\1\';
NODE_NAME     J111 L7
 '@T6G_MB_LIB.T6G(SCH_1):PAGE328_I38@PURE_QUANTA.CONN112_10137002101LF(CHIPS)':
 'L7': CDS_PINID='L7';
NET_NAME
'P5E_CPU1_P1_TX_BUF_C_DN<15>'
 '@T6G_MB_LIB.T6G(SCH_1):P5E_CPU1_P1_TX_BUF_C_DN'<15>:
 C_SIGNAL='@t6g_mb_lib.t6g(sch_1):p5e_cpu1_p1_tx_buf_c_dn(15)';
NODE_NAME     C6692 1
 '@T6G_MB_LIB.T6G(SCH_1):PAGE393_I84@PURE_QUANTA.Q_CAP_DIFFBUS(CHIPS)':
 '1': CDS_PINID='\1\';
NODE_NAME     J111 K8
 '@T6G_MB_LIB.T6G(SCH_1):PAGE328_I38@PURE_QUANTA.CONN112_10137002101LF(CHIPS)':
 'K8': CDS_PINID='K8';
NET_NAME
'P5E_CPU1_P1_TX_BUF_C_DN<1>'
 '@T6G_MB_LIB.T6G(SCH_1):P5E_CPU1_P1_TX_BUF_C_DN'<1>:
 C_SIGNAL='@t6g_mb_lib.t6g(sch_1):p5e_cpu1_p1_tx_buf_c_dn(1)';
NODE_NAME     C6664 1
 '@T6G_MB_LIB.T6G(SCH_1):PAGE393_I32@PURE_QUANTA.Q_CAP_DIFFBUS(CHIPS)':
 '1': CDS_PINID='\1\';
NODE_NAME     J112 K2
 '@T6G_MB_LIB.T6G(SCH_1):PAGE329_I102@PURE_QUANTA.CONN160_10131762101LF(CHIPS)':
 'K2': CDS_PINID='K2';
NET_NAME
'P5E_CPU1_P1_TX_BUF_C_DN<2>'
 '@T6G_MB_LIB.T6G(SCH_1):P5E_CPU1_P1_TX_BUF_C_DN'<2>:
 C_SIGNAL='@t6g_mb_lib.t6g(sch_1):p5e_cpu1_p1_tx_buf_c_dn(2)';
NODE_NAME     C6666 1
 '@T6G_MB_LIB.T6G(SCH_1):PAGE393_I29@PURE_QUANTA.Q_CAP_DIFFBUS(CHIPS)':
 '1': CDS_PINID='\1\';
NODE_NAME     J112 L3
 '@T6G_MB_LIB.T6G(SCH_1):PAGE329_I102@PURE_QUANTA.CONN160_10131762101LF(CHIPS)':
 'L3': CDS_PINID='L3';
NET_NAME
'P5E_CPU1_P1_TX_BUF_C_DN<3>'
 '@T6G_MB_LIB.T6G(SCH_1):P5E_CPU1_P1_TX_BUF_C_DN'<3>:
 C_SIGNAL='@t6g_mb_lib.t6g(sch_1):p5e_cpu1_p1_tx_buf_c_dn(3)';
NODE_NAME     C6668 1
 '@T6G_MB_LIB.T6G(SCH_1):PAGE393_I28@PURE_QUANTA.Q_CAP_DIFFBUS(CHIPS)':
 '1': CDS_PINID='\1\';
NODE_NAME     J112 K4
 '@T6G_MB_LIB.T6G(SCH_1):PAGE329_I102@PURE_QUANTA.CONN160_10131762101LF(CHIPS)':
 'K4': CDS_PINID='K4';
NET_NAME
'P5E_CPU1_P1_TX_BUF_C_DN<4>'
 '@T6G_MB_LIB.T6G(SCH_1):P5E_CPU1_P1_TX_BUF_C_DN'<4>:
 C_SIGNAL='@t6g_mb_lib.t6g(sch_1):p5e_cpu1_p1_tx_buf_c_dn(4)';
NODE_NAME     C6670 1
 '@T6G_MB_LIB.T6G(SCH_1):PAGE393_I25@PURE_QUANTA.Q_CAP_DIFFBUS(CHIPS)':
 '1': CDS_PINID='\1\';
NODE_NAME     J112 L5
 '@T6G_MB_LIB.T6G(SCH_1):PAGE329_I7@PURE_QUANTA.CONN160_10131762101LF(CHIPS)':
 'L5': CDS_PINID='L5';
NET_NAME
'P5E_CPU1_P1_TX_BUF_C_DN<5>'
 '@T6G_MB_LIB.T6G(SCH_1):P5E_CPU1_P1_TX_BUF_C_DN'<5>:
 C_SIGNAL='@t6g_mb_lib.t6g(sch_1):p5e_cpu1_p1_tx_buf_c_dn(5)';
NODE_NAME     C6672 1
 '@T6G_MB_LIB.T6G(SCH_1):PAGE393_I23@PURE_QUANTA.Q_CAP_DIFFBUS(CHIPS)':
 '1': CDS_PINID='\1\';
NODE_NAME     J112 K6
 '@T6G_MB_LIB.T6G(SCH_1):PAGE329_I7@PURE_QUANTA.CONN160_10131762101LF(CHIPS)':
 'K6': CDS_PINID='K6';
NET_NAME
'P5E_CPU1_P1_TX_BUF_C_DN<6>'
 '@T6G_MB_LIB.T6G(SCH_1):P5E_CPU1_P1_TX_BUF_C_DN'<6>:
 C_SIGNAL='@t6g_mb_lib.t6g(sch_1):p5e_cpu1_p1_tx_buf_c_dn(6)';
NODE_NAME     C6674 1
 '@T6G_MB_LIB.T6G(SCH_1):PAGE393_I19@PURE_QUANTA.Q_CAP_DIFFBUS(CHIPS)':
 '1': CDS_PINID='\1\';
NODE_NAME     J112 L7
 '@T6G_MB_LIB.T6G(SCH_1):PAGE329_I7@PURE_QUANTA.CONN160_10131762101LF(CHIPS)':
 'L7': CDS_PINID='L7';
NET_NAME
'P5E_CPU1_P1_TX_BUF_C_DN<7>'
 '@T6G_MB_LIB.T6G(SCH_1):P5E_CPU1_P1_TX_BUF_C_DN'<7>:
 C_SIGNAL='@t6g_mb_lib.t6g(sch_1):p5e_cpu1_p1_tx_buf_c_dn(7)';
NODE_NAME     C6676 1
 '@T6G_MB_LIB.T6G(SCH_1):PAGE393_I17@PURE_QUANTA.Q_CAP_DIFFBUS(CHIPS)':
 '1': CDS_PINID='\1\';
NODE_NAME     J112 K8
 '@T6G_MB_LIB.T6G(SCH_1):PAGE329_I7@PURE_QUANTA.CONN160_10131762101LF(CHIPS)':
 'K8': CDS_PINID='K8';
NET_NAME
'P5E_CPU1_P1_TX_BUF_C_DN<8>'
 '@T6G_MB_LIB.T6G(SCH_1):P5E_CPU1_P1_TX_BUF_C_DN'<8>:
 C_SIGNAL='@t6g_mb_lib.t6g(sch_1):p5e_cpu1_p1_tx_buf_c_dn(8)';
NODE_NAME     C6678 1
 '@T6G_MB_LIB.T6G(SCH_1):PAGE393_I103@PURE_QUANTA.Q_CAP_DIFFBUS(CHIPS)':
 '1': CDS_PINID='\1\';
NODE_NAME     J111 L1
 '@T6G_MB_LIB.T6G(SCH_1):PAGE328_I76@PURE_QUANTA.CONN112_10137002101LF(CHIPS)':
 'L1': CDS_PINID='L1';
NET_NAME
'P5E_CPU1_P1_TX_BUF_C_DN<9>'
 '@T6G_MB_LIB.T6G(SCH_1):P5E_CPU1_P1_TX_BUF_C_DN'<9>:
 C_SIGNAL='@t6g_mb_lib.t6g(sch_1):p5e_cpu1_p1_tx_buf_c_dn(9)';
NODE_NAME     C6680 1
 '@T6G_MB_LIB.T6G(SCH_1):PAGE393_I102@PURE_QUANTA.Q_CAP_DIFFBUS(CHIPS)':
 '1': CDS_PINID='\1\';
NODE_NAME     J111 K2
 '@T6G_MB_LIB.T6G(SCH_1):PAGE328_I76@PURE_QUANTA.CONN112_10137002101LF(CHIPS)':
 'K2': CDS_PINID='K2';
NET_NAME
'P5E_CPU1_P1_TX_BUF_C_DP<0>'
 '@T6G_MB_LIB.T6G(SCH_1):P5E_CPU1_P1_TX_BUF_C_DP'<0>:
 C_SIGNAL='@t6g_mb_lib.t6g(sch_1):p5e_cpu1_p1_tx_buf_c_dp(0)';
NODE_NAME     C6661 1
 '@T6G_MB_LIB.T6G(SCH_1):PAGE393_I42@PURE_QUANTA.Q_CAP_DIFFBUS(CHIPS)':
 '1': CDS_PINID='\1\';
NODE_NAME     J112 M1
 '@T6G_MB_LIB.T6G(SCH_1):PAGE329_I102@PURE_QUANTA.CONN160_10131762101LF(CHIPS)':
 'M1': CDS_PINID='M1';
NET_NAME
'P5E_CPU1_P1_TX_BUF_C_DP<10>'
 '@T6G_MB_LIB.T6G(SCH_1):P5E_CPU1_P1_TX_BUF_C_DP'<10>:
 C_SIGNAL='@t6g_mb_lib.t6g(sch_1):p5e_cpu1_p1_tx_buf_c_dp(10)';
NODE_NAME     C6681 1
 '@T6G_MB_LIB.T6G(SCH_1):PAGE393_I99@PURE_QUANTA.Q_CAP_DIFFBUS(CHIPS)':
 '1': CDS_PINID='\1\';
NODE_NAME     J111 M3
 '@T6G_MB_LIB.T6G(SCH_1):PAGE328_I76@PURE_QUANTA.CONN112_10137002101LF(CHIPS)':
 'M3': CDS_PINID='M3';
NET_NAME
'P5E_CPU1_P1_TX_BUF_C_DP<11>'
 '@T6G_MB_LIB.T6G(SCH_1):P5E_CPU1_P1_TX_BUF_C_DP'<11>:
 C_SIGNAL='@t6g_mb_lib.t6g(sch_1):p5e_cpu1_p1_tx_buf_c_dp(11)';
NODE_NAME     C6683 1
 '@T6G_MB_LIB.T6G(SCH_1):PAGE393_I98@PURE_QUANTA.Q_CAP_DIFFBUS(CHIPS)':
 '1': CDS_PINID='\1\';
NODE_NAME     J111 L4
 '@T6G_MB_LIB.T6G(SCH_1):PAGE328_I76@PURE_QUANTA.CONN112_10137002101LF(CHIPS)':
 'L4': CDS_PINID='L4';
NET_NAME
'P5E_CPU1_P1_TX_BUF_C_DP<12>'
 '@T6G_MB_LIB.T6G(SCH_1):P5E_CPU1_P1_TX_BUF_C_DP'<12>:
 C_SIGNAL='@t6g_mb_lib.t6g(sch_1):p5e_cpu1_p1_tx_buf_c_dp(12)';
NODE_NAME     C6685 1
 '@T6G_MB_LIB.T6G(SCH_1):PAGE393_I96@PURE_QUANTA.Q_CAP_DIFFBUS(CHIPS)':
 '1': CDS_PINID='\1\';
NODE_NAME     J111 M5
 '@T6G_MB_LIB.T6G(SCH_1):PAGE328_I38@PURE_QUANTA.CONN112_10137002101LF(CHIPS)':
 'M5': CDS_PINID='M5';
NET_NAME
'P5E_CPU1_P1_TX_BUF_C_DP<13>'
 '@T6G_MB_LIB.T6G(SCH_1):P5E_CPU1_P1_TX_BUF_C_DP'<13>:
 C_SIGNAL='@t6g_mb_lib.t6g(sch_1):p5e_cpu1_p1_tx_buf_c_dp(13)';
NODE_NAME     C6687 1
 '@T6G_MB_LIB.T6G(SCH_1):PAGE393_I89@PURE_QUANTA.Q_CAP_DIFFBUS(CHIPS)':
 '1': CDS_PINID='\1\';
NODE_NAME     J111 L6
 '@T6G_MB_LIB.T6G(SCH_1):PAGE328_I38@PURE_QUANTA.CONN112_10137002101LF(CHIPS)':
 'L6': CDS_PINID='L6';
NET_NAME
'P5E_CPU1_P1_TX_BUF_C_DP<14>'
 '@T6G_MB_LIB.T6G(SCH_1):P5E_CPU1_P1_TX_BUF_C_DP'<14>:
 C_SIGNAL='@t6g_mb_lib.t6g(sch_1):p5e_cpu1_p1_tx_buf_c_dp(14)';
NODE_NAME     C6689 1
 '@T6G_MB_LIB.T6G(SCH_1):PAGE393_I87@PURE_QUANTA.Q_CAP_DIFFBUS(CHIPS)':
 '1': CDS_PINID='\1\';
NODE_NAME     J111 M7
 '@T6G_MB_LIB.T6G(SCH_1):PAGE328_I38@PURE_QUANTA.CONN112_10137002101LF(CHIPS)':
 'M7': CDS_PINID='M7';
NET_NAME
'P5E_CPU1_P1_TX_BUF_C_DP<15>'
 '@T6G_MB_LIB.T6G(SCH_1):P5E_CPU1_P1_TX_BUF_C_DP'<15>:
 C_SIGNAL='@t6g_mb_lib.t6g(sch_1):p5e_cpu1_p1_tx_buf_c_dp(15)';
NODE_NAME     C6691 1
 '@T6G_MB_LIB.T6G(SCH_1):PAGE393_I85@PURE_QUANTA.Q_CAP_DIFFBUS(CHIPS)':
 '1': CDS_PINID='\1\';
NODE_NAME     J111 L8
 '@T6G_MB_LIB.T6G(SCH_1):PAGE328_I38@PURE_QUANTA.CONN112_10137002101LF(CHIPS)':
 'L8': CDS_PINID='L8';
NET_NAME
'P5E_CPU1_P1_TX_BUF_C_DP<1>'
 '@T6G_MB_LIB.T6G(SCH_1):P5E_CPU1_P1_TX_BUF_C_DP'<1>:
 C_SIGNAL='@t6g_mb_lib.t6g(sch_1):p5e_cpu1_p1_tx_buf_c_dp(1)';
NODE_NAME     C6663 1
 '@T6G_MB_LIB.T6G(SCH_1):PAGE393_I31@PURE_QUANTA.Q_CAP_DIFFBUS(CHIPS)':
 '1': CDS_PINID='\1\';
NODE_NAME     J112 L2
 '@T6G_MB_LIB.T6G(SCH_1):PAGE329_I102@PURE_QUANTA.CONN160_10131762101LF(CHIPS)':
 'L2': CDS_PINID='L2';
NET_NAME
'P5E_CPU1_P1_TX_BUF_C_DP<2>'
 '@T6G_MB_LIB.T6G(SCH_1):P5E_CPU1_P1_TX_BUF_C_DP'<2>:
 C_SIGNAL='@t6g_mb_lib.t6g(sch_1):p5e_cpu1_p1_tx_buf_c_dp(2)';
NODE_NAME     C6665 1
 '@T6G_MB_LIB.T6G(SCH_1):PAGE393_I30@PURE_QUANTA.Q_CAP_DIFFBUS(CHIPS)':
 '1': CDS_PINID='\1\';
NODE_NAME     J112 M3
 '@T6G_MB_LIB.T6G(SCH_1):PAGE329_I102@PURE_QUANTA.CONN160_10131762101LF(CHIPS)':
 'M3': CDS_PINID='M3';
NET_NAME
'P5E_CPU1_P1_TX_BUF_C_DP<3>'
 '@T6G_MB_LIB.T6G(SCH_1):P5E_CPU1_P1_TX_BUF_C_DP'<3>:
 C_SIGNAL='@t6g_mb_lib.t6g(sch_1):p5e_cpu1_p1_tx_buf_c_dp(3)';
NODE_NAME     C6667 1
 '@T6G_MB_LIB.T6G(SCH_1):PAGE393_I27@PURE_QUANTA.Q_CAP_DIFFBUS(CHIPS)':
 '1': CDS_PINID='\1\';
NODE_NAME     J112 L4
 '@T6G_MB_LIB.T6G(SCH_1):PAGE329_I102@PURE_QUANTA.CONN160_10131762101LF(CHIPS)':
 'L4': CDS_PINID='L4';
NET_NAME
'P5E_CPU1_P1_TX_BUF_C_DP<4>'
 '@T6G_MB_LIB.T6G(SCH_1):P5E_CPU1_P1_TX_BUF_C_DP'<4>:
 C_SIGNAL='@t6g_mb_lib.t6g(sch_1):p5e_cpu1_p1_tx_buf_c_dp(4)';
NODE_NAME     C6669 1
 '@T6G_MB_LIB.T6G(SCH_1):PAGE393_I26@PURE_QUANTA.Q_CAP_DIFFBUS(CHIPS)':
 '1': CDS_PINID='\1\';
NODE_NAME     J112 M5
 '@T6G_MB_LIB.T6G(SCH_1):PAGE329_I7@PURE_QUANTA.CONN160_10131762101LF(CHIPS)':
 'M5': CDS_PINID='M5';
NET_NAME
'P5E_CPU1_P1_TX_BUF_C_DP<5>'
 '@T6G_MB_LIB.T6G(SCH_1):P5E_CPU1_P1_TX_BUF_C_DP'<5>:
 C_SIGNAL='@t6g_mb_lib.t6g(sch_1):p5e_cpu1_p1_tx_buf_c_dp(5)';
NODE_NAME     C6671 1
 '@T6G_MB_LIB.T6G(SCH_1):PAGE393_I24@PURE_QUANTA.Q_CAP_DIFFBUS(CHIPS)':
 '1': CDS_PINID='\1\';
NODE_NAME     J112 L6
 '@T6G_MB_LIB.T6G(SCH_1):PAGE329_I7@PURE_QUANTA.CONN160_10131762101LF(CHIPS)':
 'L6': CDS_PINID='L6';
NET_NAME
'P5E_CPU1_P1_TX_BUF_C_DP<6>'
 '@T6G_MB_LIB.T6G(SCH_1):P5E_CPU1_P1_TX_BUF_C_DP'<6>:
 C_SIGNAL='@t6g_mb_lib.t6g(sch_1):p5e_cpu1_p1_tx_buf_c_dp(6)';
NODE_NAME     C6673 1
 '@T6G_MB_LIB.T6G(SCH_1):PAGE393_I20@PURE_QUANTA.Q_CAP_DIFFBUS(CHIPS)':
 '1': CDS_PINID='\1\';
NODE_NAME     J112 M7
 '@T6G_MB_LIB.T6G(SCH_1):PAGE329_I7@PURE_QUANTA.CONN160_10131762101LF(CHIPS)':
 'M7': CDS_PINID='M7';
NET_NAME
'P5E_CPU1_P1_TX_BUF_C_DP<7>'
 '@T6G_MB_LIB.T6G(SCH_1):P5E_CPU1_P1_TX_BUF_C_DP'<7>:
 C_SIGNAL='@t6g_mb_lib.t6g(sch_1):p5e_cpu1_p1_tx_buf_c_dp(7)';
NODE_NAME     C6675 1
 '@T6G_MB_LIB.T6G(SCH_1):PAGE393_I18@PURE_QUANTA.Q_CAP_DIFFBUS(CHIPS)':
 '1': CDS_PINID='\1\';
NODE_NAME     J112 L8
 '@T6G_MB_LIB.T6G(SCH_1):PAGE329_I7@PURE_QUANTA.CONN160_10131762101LF(CHIPS)':
 'L8': CDS_PINID='L8';
NET_NAME
'P5E_CPU1_P1_TX_BUF_C_DP<8>'
 '@T6G_MB_LIB.T6G(SCH_1):P5E_CPU1_P1_TX_BUF_C_DP'<8>:
 C_SIGNAL='@t6g_mb_lib.t6g(sch_1):p5e_cpu1_p1_tx_buf_c_dp(8)';
NODE_NAME     C6677 1
 '@T6G_MB_LIB.T6G(SCH_1):PAGE393_I104@PURE_QUANTA.Q_CAP_DIFFBUS(CHIPS)':
 '1': CDS_PINID='\1\';
NODE_NAME     J111 M1
 '@T6G_MB_LIB.T6G(SCH_1):PAGE328_I76@PURE_QUANTA.CONN112_10137002101LF(CHIPS)':
 'M1': CDS_PINID='M1';
NET_NAME
'P5E_CPU1_P1_TX_BUF_C_DP<9>'
 '@T6G_MB_LIB.T6G(SCH_1):P5E_CPU1_P1_TX_BUF_C_DP'<9>:
 C_SIGNAL='@t6g_mb_lib.t6g(sch_1):p5e_cpu1_p1_tx_buf_c_dp(9)';
NODE_NAME     C6679 1
 '@T6G_MB_LIB.T6G(SCH_1):PAGE393_I101@PURE_QUANTA.Q_CAP_DIFFBUS(CHIPS)':
 '1': CDS_PINID='\1\';
NODE_NAME     J111 L2
 '@T6G_MB_LIB.T6G(SCH_1):PAGE328_I76@PURE_QUANTA.CONN112_10137002101LF(CHIPS)':
 'L2': CDS_PINID='L2';
NET_NAME
'P5E_CPU1_P1_TX_BUF_DN<0>'
 '@T6G_MB_LIB.T6G(SCH_1):P5E_CPU1_P1_TX_BUF_DN'<0>:
 C_SIGNAL='@t6g_mb_lib.t6g(sch_1):p5e_cpu1_p1_tx_buf_dn(0)';
NODE_NAME     C6662 2
 '@T6G_MB_LIB.T6G(SCH_1):PAGE393_I33@PURE_QUANTA.Q_CAP_DIFFBUS(CHIPS)':
 '2': CDS_PINID='\2\';
NODE_NAME     U6015 EW10
 '@T6G_MB_LIB.T6G(SCH_1):PAGE393_I142@PURE_QUANTA.PT5161LRS(CHIPS)':
 'B_PETN15': CDS_PINID='B_PETN15';
NET_NAME
'P5E_CPU1_P1_TX_BUF_DN<10>'
 '@T6G_MB_LIB.T6G(SCH_1):P5E_CPU1_P1_TX_BUF_DN'<10>:
 C_SIGNAL='@t6g_mb_lib.t6g(sch_1):p5e_cpu1_p1_tx_buf_dn(10)';
NODE_NAME     U6015 BJ10
 '@T6G_MB_LIB.T6G(SCH_1):PAGE393_I41@PURE_QUANTA.PT5161LRS(CHIPS)':
 'B_PETN5': CDS_PINID='B_PETN5';
NODE_NAME     C6682 2
 '@T6G_MB_LIB.T6G(SCH_1):PAGE393_I100@PURE_QUANTA.Q_CAP_DIFFBUS(CHIPS)':
 '2': CDS_PINID='\2\';
NET_NAME
'P5E_CPU1_P1_TX_BUF_DN<11>'
 '@T6G_MB_LIB.T6G(SCH_1):P5E_CPU1_P1_TX_BUF_DN'<11>:
 C_SIGNAL='@t6g_mb_lib.t6g(sch_1):p5e_cpu1_p1_tx_buf_dn(11)';
NODE_NAME     U6015 BB10
 '@T6G_MB_LIB.T6G(SCH_1):PAGE393_I41@PURE_QUANTA.PT5161LRS(CHIPS)':
 'B_PETN4': CDS_PINID='B_PETN4';
NODE_NAME     C6684 2
 '@T6G_MB_LIB.T6G(SCH_1):PAGE393_I97@PURE_QUANTA.Q_CAP_DIFFBUS(CHIPS)':
 '2': CDS_PINID='\2\';
NET_NAME
'P5E_CPU1_P1_TX_BUF_DN<12>'
 '@T6G_MB_LIB.T6G(SCH_1):P5E_CPU1_P1_TX_BUF_DN'<12>:
 C_SIGNAL='@t6g_mb_lib.t6g(sch_1):p5e_cpu1_p1_tx_buf_dn(12)';
NODE_NAME     U6015 AR10
 '@T6G_MB_LIB.T6G(SCH_1):PAGE393_I41@PURE_QUANTA.PT5161LRS(CHIPS)':
 'B_PETN3': CDS_PINID='B_PETN3';
NODE_NAME     C6686 2
 '@T6G_MB_LIB.T6G(SCH_1):PAGE393_I95@PURE_QUANTA.Q_CAP_DIFFBUS(CHIPS)':
 '2': CDS_PINID='\2\';
NET_NAME
'P5E_CPU1_P1_TX_BUF_DN<13>'
 '@T6G_MB_LIB.T6G(SCH_1):P5E_CPU1_P1_TX_BUF_DN'<13>:
 C_SIGNAL='@t6g_mb_lib.t6g(sch_1):p5e_cpu1_p1_tx_buf_dn(13)';
NODE_NAME     U6015 AH10
 '@T6G_MB_LIB.T6G(SCH_1):PAGE393_I41@PURE_QUANTA.PT5161LRS(CHIPS)':
 'B_PETN2': CDS_PINID='B_PETN2';
NODE_NAME     C6688 2
 '@T6G_MB_LIB.T6G(SCH_1):PAGE393_I88@PURE_QUANTA.Q_CAP_DIFFBUS(CHIPS)':
 '2': CDS_PINID='\2\';
NET_NAME
'P5E_CPU1_P1_TX_BUF_DN<14>'
 '@T6G_MB_LIB.T6G(SCH_1):P5E_CPU1_P1_TX_BUF_DN'<14>:
 C_SIGNAL='@t6g_mb_lib.t6g(sch_1):p5e_cpu1_p1_tx_buf_dn(14)';
NODE_NAME     U6015 AA10
 '@T6G_MB_LIB.T6G(SCH_1):PAGE393_I41@PURE_QUANTA.PT5161LRS(CHIPS)':
 'B_PETN1': CDS_PINID='B_PETN1';
NODE_NAME     C6690 2
 '@T6G_MB_LIB.T6G(SCH_1):PAGE393_I86@PURE_QUANTA.Q_CAP_DIFFBUS(CHIPS)':
 '2': CDS_PINID='\2\';
NET_NAME
'P5E_CPU1_P1_TX_BUF_DN<15>'
 '@T6G_MB_LIB.T6G(SCH_1):P5E_CPU1_P1_TX_BUF_DN'<15>:
 C_SIGNAL='@t6g_mb_lib.t6g(sch_1):p5e_cpu1_p1_tx_buf_dn(15)';
NODE_NAME     U6015 P10
 '@T6G_MB_LIB.T6G(SCH_1):PAGE393_I41@PURE_QUANTA.PT5161LRS(CHIPS)':
 'B_PETN0': CDS_PINID='B_PETN0';
NODE_NAME     C6692 2
 '@T6G_MB_LIB.T6G(SCH_1):PAGE393_I84@PURE_QUANTA.Q_CAP_DIFFBUS(CHIPS)':
 '2': CDS_PINID='\2\';
NET_NAME
'P5E_CPU1_P1_TX_BUF_DN<1>'
 '@T6G_MB_LIB.T6G(SCH_1):P5E_CPU1_P1_TX_BUF_DN'<1>:
 C_SIGNAL='@t6g_mb_lib.t6g(sch_1):p5e_cpu1_p1_tx_buf_dn(1)';
NODE_NAME     C6664 2
 '@T6G_MB_LIB.T6G(SCH_1):PAGE393_I32@PURE_QUANTA.Q_CAP_DIFFBUS(CHIPS)':
 '2': CDS_PINID='\2\';
NODE_NAME     U6015 EM10
 '@T6G_MB_LIB.T6G(SCH_1):PAGE393_I142@PURE_QUANTA.PT5161LRS(CHIPS)':
 'B_PETN14': CDS_PINID='B_PETN14';
NET_NAME
'P5E_CPU1_P1_TX_BUF_DN<2>'
 '@T6G_MB_LIB.T6G(SCH_1):P5E_CPU1_P1_TX_BUF_DN'<2>:
 C_SIGNAL='@t6g_mb_lib.t6g(sch_1):p5e_cpu1_p1_tx_buf_dn(2)';
NODE_NAME     C6666 2
 '@T6G_MB_LIB.T6G(SCH_1):PAGE393_I29@PURE_QUANTA.Q_CAP_DIFFBUS(CHIPS)':
 '2': CDS_PINID='\2\';
NODE_NAME     U6015 EE10
 '@T6G_MB_LIB.T6G(SCH_1):PAGE393_I142@PURE_QUANTA.PT5161LRS(CHIPS)':
 'B_PETN13': CDS_PINID='B_PETN13';
NET_NAME
'P5E_CPU1_P1_TX_BUF_DN<3>'
 '@T6G_MB_LIB.T6G(SCH_1):P5E_CPU1_P1_TX_BUF_DN'<3>:
 C_SIGNAL='@t6g_mb_lib.t6g(sch_1):p5e_cpu1_p1_tx_buf_dn(3)';
NODE_NAME     C6668 2
 '@T6G_MB_LIB.T6G(SCH_1):PAGE393_I28@PURE_QUANTA.Q_CAP_DIFFBUS(CHIPS)':
 '2': CDS_PINID='\2\';
NODE_NAME     U6015 DV10
 '@T6G_MB_LIB.T6G(SCH_1):PAGE393_I142@PURE_QUANTA.PT5161LRS(CHIPS)':
 'B_PETN12': CDS_PINID='B_PETN12';
NET_NAME
'P5E_CPU1_P1_TX_BUF_DN<4>'
 '@T6G_MB_LIB.T6G(SCH_1):P5E_CPU1_P1_TX_BUF_DN'<4>:
 C_SIGNAL='@t6g_mb_lib.t6g(sch_1):p5e_cpu1_p1_tx_buf_dn(4)';
NODE_NAME     C6670 2
 '@T6G_MB_LIB.T6G(SCH_1):PAGE393_I25@PURE_QUANTA.Q_CAP_DIFFBUS(CHIPS)':
 '2': CDS_PINID='\2\';
NODE_NAME     U6015 DL10
 '@T6G_MB_LIB.T6G(SCH_1):PAGE393_I142@PURE_QUANTA.PT5161LRS(CHIPS)':
 'B_PETN11': CDS_PINID='B_PETN11';
NET_NAME
'P5E_CPU1_P1_TX_BUF_DN<5>'
 '@T6G_MB_LIB.T6G(SCH_1):P5E_CPU1_P1_TX_BUF_DN'<5>:
 C_SIGNAL='@t6g_mb_lib.t6g(sch_1):p5e_cpu1_p1_tx_buf_dn(5)';
NODE_NAME     C6672 2
 '@T6G_MB_LIB.T6G(SCH_1):PAGE393_I23@PURE_QUANTA.Q_CAP_DIFFBUS(CHIPS)':
 '2': CDS_PINID='\2\';
NODE_NAME     U6015 DD10
 '@T6G_MB_LIB.T6G(SCH_1):PAGE393_I142@PURE_QUANTA.PT5161LRS(CHIPS)':
 'B_PETN10': CDS_PINID='B_PETN10';
NET_NAME
'P5E_CPU1_P1_TX_BUF_DN<6>'
 '@T6G_MB_LIB.T6G(SCH_1):P5E_CPU1_P1_TX_BUF_DN'<6>:
 C_SIGNAL='@t6g_mb_lib.t6g(sch_1):p5e_cpu1_p1_tx_buf_dn(6)';
NODE_NAME     C6674 2
 '@T6G_MB_LIB.T6G(SCH_1):PAGE393_I19@PURE_QUANTA.Q_CAP_DIFFBUS(CHIPS)':
 '2': CDS_PINID='\2\';
NODE_NAME     U6015 CU10
 '@T6G_MB_LIB.T6G(SCH_1):PAGE393_I142@PURE_QUANTA.PT5161LRS(CHIPS)':
 'B_PETN9': CDS_PINID='B_PETN9';
NET_NAME
'P5E_CPU1_P1_TX_BUF_DN<7>'
 '@T6G_MB_LIB.T6G(SCH_1):P5E_CPU1_P1_TX_BUF_DN'<7>:
 C_SIGNAL='@t6g_mb_lib.t6g(sch_1):p5e_cpu1_p1_tx_buf_dn(7)';
NODE_NAME     C6676 2
 '@T6G_MB_LIB.T6G(SCH_1):PAGE393_I17@PURE_QUANTA.Q_CAP_DIFFBUS(CHIPS)':
 '2': CDS_PINID='\2\';
NODE_NAME     U6015 CK10
 '@T6G_MB_LIB.T6G(SCH_1):PAGE393_I142@PURE_QUANTA.PT5161LRS(CHIPS)':
 'B_PETN8': CDS_PINID='B_PETN8';
NET_NAME
'P5E_CPU1_P1_TX_BUF_DN<8>'
 '@T6G_MB_LIB.T6G(SCH_1):P5E_CPU1_P1_TX_BUF_DN'<8>:
 C_SIGNAL='@t6g_mb_lib.t6g(sch_1):p5e_cpu1_p1_tx_buf_dn(8)';
NODE_NAME     U6015 CC10
 '@T6G_MB_LIB.T6G(SCH_1):PAGE393_I41@PURE_QUANTA.PT5161LRS(CHIPS)':
 'B_PETN7': CDS_PINID='B_PETN7';
NODE_NAME     C6678 2
 '@T6G_MB_LIB.T6G(SCH_1):PAGE393_I103@PURE_QUANTA.Q_CAP_DIFFBUS(CHIPS)':
 '2': CDS_PINID='\2\';
NET_NAME
'P5E_CPU1_P1_TX_BUF_DN<9>'
 '@T6G_MB_LIB.T6G(SCH_1):P5E_CPU1_P1_TX_BUF_DN'<9>:
 C_SIGNAL='@t6g_mb_lib.t6g(sch_1):p5e_cpu1_p1_tx_buf_dn(9)';
NODE_NAME     U6015 BT10
 '@T6G_MB_LIB.T6G(SCH_1):PAGE393_I41@PURE_QUANTA.PT5161LRS(CHIPS)':
 'B_PETN6': CDS_PINID='B_PETN6';
NODE_NAME     C6680 2
 '@T6G_MB_LIB.T6G(SCH_1):PAGE393_I102@PURE_QUANTA.Q_CAP_DIFFBUS(CHIPS)':
 '2': CDS_PINID='\2\';
NET_NAME
'P5E_CPU1_P1_TX_BUF_DP<0>'
 '@T6G_MB_LIB.T6G(SCH_1):P5E_CPU1_P1_TX_BUF_DP'<0>:
 C_SIGNAL='@t6g_mb_lib.t6g(sch_1):p5e_cpu1_p1_tx_buf_dp(0)';
NODE_NAME     C6661 2
 '@T6G_MB_LIB.T6G(SCH_1):PAGE393_I42@PURE_QUANTA.Q_CAP_DIFFBUS(CHIPS)':
 '2': CDS_PINID='\2\';
NODE_NAME     U6015 EU7
 '@T6G_MB_LIB.T6G(SCH_1):PAGE393_I142@PURE_QUANTA.PT5161LRS(CHIPS)':
 'B_PETP15': CDS_PINID='B_PETP15';
NET_NAME
'P5E_CPU1_P1_TX_BUF_DP<10>'
 '@T6G_MB_LIB.T6G(SCH_1):P5E_CPU1_P1_TX_BUF_DP'<10>:
 C_SIGNAL='@t6g_mb_lib.t6g(sch_1):p5e_cpu1_p1_tx_buf_dp(10)';
NODE_NAME     U6015 BG7
 '@T6G_MB_LIB.T6G(SCH_1):PAGE393_I41@PURE_QUANTA.PT5161LRS(CHIPS)':
 'B_PETP5': CDS_PINID='B_PETP5';
NODE_NAME     C6681 2
 '@T6G_MB_LIB.T6G(SCH_1):PAGE393_I99@PURE_QUANTA.Q_CAP_DIFFBUS(CHIPS)':
 '2': CDS_PINID='\2\';
NET_NAME
'P5E_CPU1_P1_TX_BUF_DP<11>'
 '@T6G_MB_LIB.T6G(SCH_1):P5E_CPU1_P1_TX_BUF_DP'<11>:
 C_SIGNAL='@t6g_mb_lib.t6g(sch_1):p5e_cpu1_p1_tx_buf_dp(11)';
NODE_NAME     U6015 AY7
 '@T6G_MB_LIB.T6G(SCH_1):PAGE393_I41@PURE_QUANTA.PT5161LRS(CHIPS)':
 'B_PETP4': CDS_PINID='B_PETP4';
NODE_NAME     C6683 2
 '@T6G_MB_LIB.T6G(SCH_1):PAGE393_I98@PURE_QUANTA.Q_CAP_DIFFBUS(CHIPS)':
 '2': CDS_PINID='\2\';
NET_NAME
'P5E_CPU1_P1_TX_BUF_DP<12>'
 '@T6G_MB_LIB.T6G(SCH_1):P5E_CPU1_P1_TX_BUF_DP'<12>:
 C_SIGNAL='@t6g_mb_lib.t6g(sch_1):p5e_cpu1_p1_tx_buf_dp(12)';
NODE_NAME     U6015 AN7
 '@T6G_MB_LIB.T6G(SCH_1):PAGE393_I41@PURE_QUANTA.PT5161LRS(CHIPS)':
 'B_PETP3': CDS_PINID='B_PETP3';
NODE_NAME     C6685 2
 '@T6G_MB_LIB.T6G(SCH_1):PAGE393_I96@PURE_QUANTA.Q_CAP_DIFFBUS(CHIPS)':
 '2': CDS_PINID='\2\';
NET_NAME
'P5E_CPU1_P1_TX_BUF_DP<13>'
 '@T6G_MB_LIB.T6G(SCH_1):P5E_CPU1_P1_TX_BUF_DP'<13>:
 C_SIGNAL='@t6g_mb_lib.t6g(sch_1):p5e_cpu1_p1_tx_buf_dp(13)';
NODE_NAME     U6015 AF7
 '@T6G_MB_LIB.T6G(SCH_1):PAGE393_I41@PURE_QUANTA.PT5161LRS(CHIPS)':
 'B_PETP2': CDS_PINID='B_PETP2';
NODE_NAME     C6687 2
 '@T6G_MB_LIB.T6G(SCH_1):PAGE393_I89@PURE_QUANTA.Q_CAP_DIFFBUS(CHIPS)':
 '2': CDS_PINID='\2\';
NET_NAME
'P5E_CPU1_P1_TX_BUF_DP<14>'
 '@T6G_MB_LIB.T6G(SCH_1):P5E_CPU1_P1_TX_BUF_DP'<14>:
 C_SIGNAL='@t6g_mb_lib.t6g(sch_1):p5e_cpu1_p1_tx_buf_dp(14)';
NODE_NAME     U6015 W7
 '@T6G_MB_LIB.T6G(SCH_1):PAGE393_I41@PURE_QUANTA.PT5161LRS(CHIPS)':
 'B_PETP1': CDS_PINID='B_PETP1';
NODE_NAME     C6689 2
 '@T6G_MB_LIB.T6G(SCH_1):PAGE393_I87@PURE_QUANTA.Q_CAP_DIFFBUS(CHIPS)':
 '2': CDS_PINID='\2\';
NET_NAME
'P5E_CPU1_P1_TX_BUF_DP<15>'
 '@T6G_MB_LIB.T6G(SCH_1):P5E_CPU1_P1_TX_BUF_DP'<15>:
 C_SIGNAL='@t6g_mb_lib.t6g(sch_1):p5e_cpu1_p1_tx_buf_dp(15)';
NODE_NAME     U6015 M7
 '@T6G_MB_LIB.T6G(SCH_1):PAGE393_I41@PURE_QUANTA.PT5161LRS(CHIPS)':
 'B_PETP0': CDS_PINID='B_PETP0';
NODE_NAME     C6691 2
 '@T6G_MB_LIB.T6G(SCH_1):PAGE393_I85@PURE_QUANTA.Q_CAP_DIFFBUS(CHIPS)':
 '2': CDS_PINID='\2\';
NET_NAME
'P5E_CPU1_P1_TX_BUF_DP<1>'
 '@T6G_MB_LIB.T6G(SCH_1):P5E_CPU1_P1_TX_BUF_DP'<1>:
 C_SIGNAL='@t6g_mb_lib.t6g(sch_1):p5e_cpu1_p1_tx_buf_dp(1)';
NODE_NAME     C6663 2
 '@T6G_MB_LIB.T6G(SCH_1):PAGE393_I31@PURE_QUANTA.Q_CAP_DIFFBUS(CHIPS)':
 '2': CDS_PINID='\2\';
NODE_NAME     U6015 EK7
 '@T6G_MB_LIB.T6G(SCH_1):PAGE393_I142@PURE_QUANTA.PT5161LRS(CHIPS)':
 'B_PETP14': CDS_PINID='B_PETP14';
NET_NAME
'P5E_CPU1_P1_TX_BUF_DP<2>'
 '@T6G_MB_LIB.T6G(SCH_1):P5E_CPU1_P1_TX_BUF_DP'<2>:
 C_SIGNAL='@t6g_mb_lib.t6g(sch_1):p5e_cpu1_p1_tx_buf_dp(2)';
NODE_NAME     C6665 2
 '@T6G_MB_LIB.T6G(SCH_1):PAGE393_I30@PURE_QUANTA.Q_CAP_DIFFBUS(CHIPS)':
 '2': CDS_PINID='\2\';
NODE_NAME     U6015 EC7
 '@T6G_MB_LIB.T6G(SCH_1):PAGE393_I142@PURE_QUANTA.PT5161LRS(CHIPS)':
 'B_PETP13': CDS_PINID='B_PETP13';
NET_NAME
'P5E_CPU1_P1_TX_BUF_DP<3>'
 '@T6G_MB_LIB.T6G(SCH_1):P5E_CPU1_P1_TX_BUF_DP'<3>:
 C_SIGNAL='@t6g_mb_lib.t6g(sch_1):p5e_cpu1_p1_tx_buf_dp(3)';
NODE_NAME     C6667 2
 '@T6G_MB_LIB.T6G(SCH_1):PAGE393_I27@PURE_QUANTA.Q_CAP_DIFFBUS(CHIPS)':
 '2': CDS_PINID='\2\';
NODE_NAME     U6015 DT7
 '@T6G_MB_LIB.T6G(SCH_1):PAGE393_I142@PURE_QUANTA.PT5161LRS(CHIPS)':
 'B_PETP12': CDS_PINID='B_PETP12';
NET_NAME
'P5E_CPU1_P1_TX_BUF_DP<4>'
 '@T6G_MB_LIB.T6G(SCH_1):P5E_CPU1_P1_TX_BUF_DP'<4>:
 C_SIGNAL='@t6g_mb_lib.t6g(sch_1):p5e_cpu1_p1_tx_buf_dp(4)';
NODE_NAME     C6669 2
 '@T6G_MB_LIB.T6G(SCH_1):PAGE393_I26@PURE_QUANTA.Q_CAP_DIFFBUS(CHIPS)':
 '2': CDS_PINID='\2\';
NODE_NAME     U6015 DJ7
 '@T6G_MB_LIB.T6G(SCH_1):PAGE393_I142@PURE_QUANTA.PT5161LRS(CHIPS)':
 'B_PETP11': CDS_PINID='B_PETP11';
NET_NAME
'P5E_CPU1_P1_TX_BUF_DP<5>'
 '@T6G_MB_LIB.T6G(SCH_1):P5E_CPU1_P1_TX_BUF_DP'<5>:
 C_SIGNAL='@t6g_mb_lib.t6g(sch_1):p5e_cpu1_p1_tx_buf_dp(5)';
NODE_NAME     C6671 2
 '@T6G_MB_LIB.T6G(SCH_1):PAGE393_I24@PURE_QUANTA.Q_CAP_DIFFBUS(CHIPS)':
 '2': CDS_PINID='\2\';
NODE_NAME     U6015 DB7
 '@T6G_MB_LIB.T6G(SCH_1):PAGE393_I142@PURE_QUANTA.PT5161LRS(CHIPS)':
 'B_PETP10': CDS_PINID='B_PETP10';
NET_NAME
'P5E_CPU1_P1_TX_BUF_DP<6>'
 '@T6G_MB_LIB.T6G(SCH_1):P5E_CPU1_P1_TX_BUF_DP'<6>:
 C_SIGNAL='@t6g_mb_lib.t6g(sch_1):p5e_cpu1_p1_tx_buf_dp(6)';
NODE_NAME     C6673 2
 '@T6G_MB_LIB.T6G(SCH_1):PAGE393_I20@PURE_QUANTA.Q_CAP_DIFFBUS(CHIPS)':
 '2': CDS_PINID='\2\';
NODE_NAME     U6015 CR7
 '@T6G_MB_LIB.T6G(SCH_1):PAGE393_I142@PURE_QUANTA.PT5161LRS(CHIPS)':
 'B_PETP9': CDS_PINID='B_PETP9';
NET_NAME
'P5E_CPU1_P1_TX_BUF_DP<7>'
 '@T6G_MB_LIB.T6G(SCH_1):P5E_CPU1_P1_TX_BUF_DP'<7>:
 C_SIGNAL='@t6g_mb_lib.t6g(sch_1):p5e_cpu1_p1_tx_buf_dp(7)';
NODE_NAME     C6675 2
 '@T6G_MB_LIB.T6G(SCH_1):PAGE393_I18@PURE_QUANTA.Q_CAP_DIFFBUS(CHIPS)':
 '2': CDS_PINID='\2\';
NODE_NAME     U6015 CH7
 '@T6G_MB_LIB.T6G(SCH_1):PAGE393_I142@PURE_QUANTA.PT5161LRS(CHIPS)':
 'B_PETP8': CDS_PINID='B_PETP8';
NET_NAME
'P5E_CPU1_P1_TX_BUF_DP<8>'
 '@T6G_MB_LIB.T6G(SCH_1):P5E_CPU1_P1_TX_BUF_DP'<8>:
 C_SIGNAL='@t6g_mb_lib.t6g(sch_1):p5e_cpu1_p1_tx_buf_dp(8)';
NODE_NAME     U6015 CA7
 '@T6G_MB_LIB.T6G(SCH_1):PAGE393_I41@PURE_QUANTA.PT5161LRS(CHIPS)':
 'B_PETP7': CDS_PINID='B_PETP7';
NODE_NAME     C6677 2
 '@T6G_MB_LIB.T6G(SCH_1):PAGE393_I104@PURE_QUANTA.Q_CAP_DIFFBUS(CHIPS)':
 '2': CDS_PINID='\2\';
NET_NAME
'P5E_CPU1_P1_TX_BUF_DP<9>'
 '@T6G_MB_LIB.T6G(SCH_1):P5E_CPU1_P1_TX_BUF_DP'<9>:
 C_SIGNAL='@t6g_mb_lib.t6g(sch_1):p5e_cpu1_p1_tx_buf_dp(9)';
NODE_NAME     U6015 BP7
 '@T6G_MB_LIB.T6G(SCH_1):PAGE393_I41@PURE_QUANTA.PT5161LRS(CHIPS)':
 'B_PETP6': CDS_PINID='B_PETP6';
NODE_NAME     C6679 2
 '@T6G_MB_LIB.T6G(SCH_1):PAGE393_I101@PURE_QUANTA.Q_CAP_DIFFBUS(CHIPS)':
 '2': CDS_PINID='\2\';
NET_NAME
'P5E_CPU1_P1_TX_C_DN<0>'
 '@T6G_MB_LIB.T6G(SCH_1):P5E_CPU1_P1_TX_C_DN'<0>:
 C_SIGNAL='@t6g_mb_lib.t6g(sch_1):p5e_cpu1_p1_tx_c_dn(0)';
NODE_NAME     C740 1
 '@T6G_MB_LIB.T6G(SCH_1):PAGE354_I229@PURE_QUANTA.Q_CAP_DIFFBUS(CHIPS)':
 '1': CDS_PINID='\1\';
NODE_NAME     U6015 EV34
 '@T6G_MB_LIB.T6G(SCH_1):PAGE396_I38@PURE_QUANTA.PT5161LRS(CHIPS)':
 'B_PERP15': CDS_PINID='B_PERP15';
NET_NAME
'P5E_CPU1_P1_TX_C_DN<10>'
 '@T6G_MB_LIB.T6G(SCH_1):P5E_CPU1_P1_TX_C_DN'<10>:
 C_SIGNAL='@t6g_mb_lib.t6g(sch_1):p5e_cpu1_p1_tx_c_dn(10)';
NODE_NAME     C720 1
 '@T6G_MB_LIB.T6G(SCH_1):PAGE354_I279@PURE_QUANTA.Q_CAP_DIFFBUS(CHIPS)':
 '1': CDS_PINID='\1\';
NODE_NAME     U6015 BH34
 '@T6G_MB_LIB.T6G(SCH_1):PAGE396_I1@PURE_QUANTA.PT5161LRS(CHIPS)':
 'B_PERP5': CDS_PINID='B_PERP5';
NET_NAME
'P5E_CPU1_P1_TX_C_DN<11>'
 '@T6G_MB_LIB.T6G(SCH_1):P5E_CPU1_P1_TX_C_DN'<11>:
 C_SIGNAL='@t6g_mb_lib.t6g(sch_1):p5e_cpu1_p1_tx_c_dn(11)';
NODE_NAME     C718 1
 '@T6G_MB_LIB.T6G(SCH_1):PAGE354_I281@PURE_QUANTA.Q_CAP_DIFFBUS(CHIPS)':
 '1': CDS_PINID='\1\';
NODE_NAME     U6015 BA34
 '@T6G_MB_LIB.T6G(SCH_1):PAGE396_I1@PURE_QUANTA.PT5161LRS(CHIPS)':
 'B_PERP4': CDS_PINID='B_PERP4';
NET_NAME
'P5E_CPU1_P1_TX_C_DN<12>'
 '@T6G_MB_LIB.T6G(SCH_1):P5E_CPU1_P1_TX_C_DN'<12>:
 C_SIGNAL='@t6g_mb_lib.t6g(sch_1):p5e_cpu1_p1_tx_c_dn(12)';
NODE_NAME     C716 1
 '@T6G_MB_LIB.T6G(SCH_1):PAGE354_I283@PURE_QUANTA.Q_CAP_DIFFBUS(CHIPS)':
 '1': CDS_PINID='\1\';
NODE_NAME     U6015 AP34
 '@T6G_MB_LIB.T6G(SCH_1):PAGE396_I1@PURE_QUANTA.PT5161LRS(CHIPS)':
 'B_PERP3': CDS_PINID='B_PERP3';
NET_NAME
'P5E_CPU1_P1_TX_C_DN<13>'
 '@T6G_MB_LIB.T6G(SCH_1):P5E_CPU1_P1_TX_C_DN'<13>:
 C_SIGNAL='@t6g_mb_lib.t6g(sch_1):p5e_cpu1_p1_tx_c_dn(13)';
NODE_NAME     C714 1
 '@T6G_MB_LIB.T6G(SCH_1):PAGE354_I295@PURE_QUANTA.Q_CAP_DIFFBUS(CHIPS)':
 '1': CDS_PINID='\1\';
NODE_NAME     U6015 AG34
 '@T6G_MB_LIB.T6G(SCH_1):PAGE396_I1@PURE_QUANTA.PT5161LRS(CHIPS)':
 'B_PERP2': CDS_PINID='B_PERP2';
NET_NAME
'P5E_CPU1_P1_TX_C_DN<14>'
 '@T6G_MB_LIB.T6G(SCH_1):P5E_CPU1_P1_TX_C_DN'<14>:
 C_SIGNAL='@t6g_mb_lib.t6g(sch_1):p5e_cpu1_p1_tx_c_dn(14)';
NODE_NAME     C712 1
 '@T6G_MB_LIB.T6G(SCH_1):PAGE354_I296@PURE_QUANTA.Q_CAP_DIFFBUS(CHIPS)':
 '1': CDS_PINID='\1\';
NODE_NAME     U6015 AB35
 '@T6G_MB_LIB.T6G(SCH_1):PAGE396_I1@PURE_QUANTA.PT5161LRS(CHIPS)':
 'B_PERN1': CDS_PINID='B_PERN1';
NET_NAME
'P5E_CPU1_P1_TX_C_DN<15>'
 '@T6G_MB_LIB.T6G(SCH_1):P5E_CPU1_P1_TX_C_DN'<15>:
 C_SIGNAL='@t6g_mb_lib.t6g(sch_1):p5e_cpu1_p1_tx_c_dn(15)';
NODE_NAME     C710 1
 '@T6G_MB_LIB.T6G(SCH_1):PAGE354_I299@PURE_QUANTA.Q_CAP_DIFFBUS(CHIPS)':
 '1': CDS_PINID='\1\';
NODE_NAME     U6015 N34
 '@T6G_MB_LIB.T6G(SCH_1):PAGE396_I1@PURE_QUANTA.PT5161LRS(CHIPS)':
 'B_PERP0': CDS_PINID='B_PERP0';
NET_NAME
'P5E_CPU1_P1_TX_C_DN<1>'
 '@T6G_MB_LIB.T6G(SCH_1):P5E_CPU1_P1_TX_C_DN'<1>:
 C_SIGNAL='@t6g_mb_lib.t6g(sch_1):p5e_cpu1_p1_tx_c_dn(1)';
NODE_NAME     C738 1
 '@T6G_MB_LIB.T6G(SCH_1):PAGE354_I232@PURE_QUANTA.Q_CAP_DIFFBUS(CHIPS)':
 '1': CDS_PINID='\1\';
NODE_NAME     U6015 EN35
 '@T6G_MB_LIB.T6G(SCH_1):PAGE396_I38@PURE_QUANTA.PT5161LRS(CHIPS)':
 'B_PERN14': CDS_PINID='B_PERN14';
NET_NAME
'P5E_CPU1_P1_TX_C_DN<2>'
 '@T6G_MB_LIB.T6G(SCH_1):P5E_CPU1_P1_TX_C_DN'<2>:
 C_SIGNAL='@t6g_mb_lib.t6g(sch_1):p5e_cpu1_p1_tx_c_dn(2)';
NODE_NAME     C736 1
 '@T6G_MB_LIB.T6G(SCH_1):PAGE354_I234@PURE_QUANTA.Q_CAP_DIFFBUS(CHIPS)':
 '1': CDS_PINID='\1\';
NODE_NAME     U6015 ED34
 '@T6G_MB_LIB.T6G(SCH_1):PAGE396_I38@PURE_QUANTA.PT5161LRS(CHIPS)':
 'B_PERP13': CDS_PINID='B_PERP13';
NET_NAME
'P5E_CPU1_P1_TX_C_DN<3>'
 '@T6G_MB_LIB.T6G(SCH_1):P5E_CPU1_P1_TX_C_DN'<3>:
 C_SIGNAL='@t6g_mb_lib.t6g(sch_1):p5e_cpu1_p1_tx_c_dn(3)';
NODE_NAME     C734 1
 '@T6G_MB_LIB.T6G(SCH_1):PAGE354_I235@PURE_QUANTA.Q_CAP_DIFFBUS(CHIPS)':
 '1': CDS_PINID='\1\';
NODE_NAME     U6015 DU34
 '@T6G_MB_LIB.T6G(SCH_1):PAGE396_I38@PURE_QUANTA.PT5161LRS(CHIPS)':
 'B_PERP12': CDS_PINID='B_PERP12';
NET_NAME
'P5E_CPU1_P1_TX_C_DN<4>'
 '@T6G_MB_LIB.T6G(SCH_1):P5E_CPU1_P1_TX_C_DN'<4>:
 C_SIGNAL='@t6g_mb_lib.t6g(sch_1):p5e_cpu1_p1_tx_c_dn(4)';
NODE_NAME     C732 1
 '@T6G_MB_LIB.T6G(SCH_1):PAGE354_I246@PURE_QUANTA.Q_CAP_DIFFBUS(CHIPS)':
 '1': CDS_PINID='\1\';
NODE_NAME     U6015 DK34
 '@T6G_MB_LIB.T6G(SCH_1):PAGE396_I38@PURE_QUANTA.PT5161LRS(CHIPS)':
 'B_PERP11': CDS_PINID='B_PERP11';
NET_NAME
'P5E_CPU1_P1_TX_C_DN<5>'
 '@T6G_MB_LIB.T6G(SCH_1):P5E_CPU1_P1_TX_C_DN'<5>:
 C_SIGNAL='@t6g_mb_lib.t6g(sch_1):p5e_cpu1_p1_tx_c_dn(5)';
NODE_NAME     C730 1
 '@T6G_MB_LIB.T6G(SCH_1):PAGE354_I248@PURE_QUANTA.Q_CAP_DIFFBUS(CHIPS)':
 '1': CDS_PINID='\1\';
NODE_NAME     U6015 DC34
 '@T6G_MB_LIB.T6G(SCH_1):PAGE396_I38@PURE_QUANTA.PT5161LRS(CHIPS)':
 'B_PERP10': CDS_PINID='B_PERP10';
NET_NAME
'P5E_CPU1_P1_TX_C_DN<6>'
 '@T6G_MB_LIB.T6G(SCH_1):P5E_CPU1_P1_TX_C_DN'<6>:
 C_SIGNAL='@t6g_mb_lib.t6g(sch_1):p5e_cpu1_p1_tx_c_dn(6)';
NODE_NAME     C728 1
 '@T6G_MB_LIB.T6G(SCH_1):PAGE354_I250@PURE_QUANTA.Q_CAP_DIFFBUS(CHIPS)':
 '1': CDS_PINID='\1\';
NODE_NAME     U6015 CT34
 '@T6G_MB_LIB.T6G(SCH_1):PAGE396_I38@PURE_QUANTA.PT5161LRS(CHIPS)':
 'B_PERP9': CDS_PINID='B_PERP9';
NET_NAME
'P5E_CPU1_P1_TX_C_DN<7>'
 '@T6G_MB_LIB.T6G(SCH_1):P5E_CPU1_P1_TX_C_DN'<7>:
 C_SIGNAL='@t6g_mb_lib.t6g(sch_1):p5e_cpu1_p1_tx_c_dn(7)';
NODE_NAME     C726 1
 '@T6G_MB_LIB.T6G(SCH_1):PAGE354_I312@PURE_QUANTA.Q_CAP_DIFFBUS(CHIPS)':
 '1': CDS_PINID='\1\';
NODE_NAME     U6015 CJ34
 '@T6G_MB_LIB.T6G(SCH_1):PAGE396_I38@PURE_QUANTA.PT5161LRS(CHIPS)':
 'B_PERP8': CDS_PINID='B_PERP8';
NET_NAME
'P5E_CPU1_P1_TX_C_DN<8>'
 '@T6G_MB_LIB.T6G(SCH_1):P5E_CPU1_P1_TX_C_DN'<8>:
 C_SIGNAL='@t6g_mb_lib.t6g(sch_1):p5e_cpu1_p1_tx_c_dn(8)';
NODE_NAME     C724 1
 '@T6G_MB_LIB.T6G(SCH_1):PAGE354_I275@PURE_QUANTA.Q_CAP_DIFFBUS(CHIPS)':
 '1': CDS_PINID='\1\';
NODE_NAME     U6015 CB34
 '@T6G_MB_LIB.T6G(SCH_1):PAGE396_I1@PURE_QUANTA.PT5161LRS(CHIPS)':
 'B_PERP7': CDS_PINID='B_PERP7';
NET_NAME
'P5E_CPU1_P1_TX_C_DN<9>'
 '@T6G_MB_LIB.T6G(SCH_1):P5E_CPU1_P1_TX_C_DN'<9>:
 C_SIGNAL='@t6g_mb_lib.t6g(sch_1):p5e_cpu1_p1_tx_c_dn(9)';
NODE_NAME     C722 1
 '@T6G_MB_LIB.T6G(SCH_1):PAGE354_I276@PURE_QUANTA.Q_CAP_DIFFBUS(CHIPS)':
 '1': CDS_PINID='\1\';
NODE_NAME     U6015 BR34
 '@T6G_MB_LIB.T6G(SCH_1):PAGE396_I1@PURE_QUANTA.PT5161LRS(CHIPS)':
 'B_PERP6': CDS_PINID='B_PERP6';
NET_NAME
'P5E_CPU1_P1_TX_C_DP<0>'
 '@T6G_MB_LIB.T6G(SCH_1):P5E_CPU1_P1_TX_C_DP'<0>:
 C_SIGNAL='@t6g_mb_lib.t6g(sch_1):p5e_cpu1_p1_tx_c_dp(0)';
NODE_NAME     C741 1
 '@T6G_MB_LIB.T6G(SCH_1):PAGE354_I230@PURE_QUANTA.Q_CAP_DIFFBUS(CHIPS)':
 '1': CDS_PINID='\1\';
NODE_NAME     U6015 EY35
 '@T6G_MB_LIB.T6G(SCH_1):PAGE396_I38@PURE_QUANTA.PT5161LRS(CHIPS)':
 'B_PERN15': CDS_PINID='B_PERN15';
NET_NAME
'P5E_CPU1_P1_TX_C_DP<10>'
 '@T6G_MB_LIB.T6G(SCH_1):P5E_CPU1_P1_TX_C_DP'<10>:
 C_SIGNAL='@t6g_mb_lib.t6g(sch_1):p5e_cpu1_p1_tx_c_dp(10)';
NODE_NAME     C721 1
 '@T6G_MB_LIB.T6G(SCH_1):PAGE354_I278@PURE_QUANTA.Q_CAP_DIFFBUS(CHIPS)':
 '1': CDS_PINID='\1\';
NODE_NAME     U6015 BK35
 '@T6G_MB_LIB.T6G(SCH_1):PAGE396_I1@PURE_QUANTA.PT5161LRS(CHIPS)':
 'B_PERN5': CDS_PINID='B_PERN5';
NET_NAME
'P5E_CPU1_P1_TX_C_DP<11>'
 '@T6G_MB_LIB.T6G(SCH_1):P5E_CPU1_P1_TX_C_DP'<11>:
 C_SIGNAL='@t6g_mb_lib.t6g(sch_1):p5e_cpu1_p1_tx_c_dp(11)';
NODE_NAME     C719 1
 '@T6G_MB_LIB.T6G(SCH_1):PAGE354_I280@PURE_QUANTA.Q_CAP_DIFFBUS(CHIPS)':
 '1': CDS_PINID='\1\';
NODE_NAME     U6015 BC35
 '@T6G_MB_LIB.T6G(SCH_1):PAGE396_I1@PURE_QUANTA.PT5161LRS(CHIPS)':
 'B_PERN4': CDS_PINID='B_PERN4';
NET_NAME
'P5E_CPU1_P1_TX_C_DP<12>'
 '@T6G_MB_LIB.T6G(SCH_1):P5E_CPU1_P1_TX_C_DP'<12>:
 C_SIGNAL='@t6g_mb_lib.t6g(sch_1):p5e_cpu1_p1_tx_c_dp(12)';
NODE_NAME     C717 1
 '@T6G_MB_LIB.T6G(SCH_1):PAGE354_I282@PURE_QUANTA.Q_CAP_DIFFBUS(CHIPS)':
 '1': CDS_PINID='\1\';
NODE_NAME     U6015 AT35
 '@T6G_MB_LIB.T6G(SCH_1):PAGE396_I1@PURE_QUANTA.PT5161LRS(CHIPS)':
 'B_PERN3': CDS_PINID='B_PERN3';
NET_NAME
'P5E_CPU1_P1_TX_C_DP<13>'
 '@T6G_MB_LIB.T6G(SCH_1):P5E_CPU1_P1_TX_C_DP'<13>:
 C_SIGNAL='@t6g_mb_lib.t6g(sch_1):p5e_cpu1_p1_tx_c_dp(13)';
NODE_NAME     C715 1
 '@T6G_MB_LIB.T6G(SCH_1):PAGE354_I294@PURE_QUANTA.Q_CAP_DIFFBUS(CHIPS)':
 '1': CDS_PINID='\1\';
NODE_NAME     U6015 AJ35
 '@T6G_MB_LIB.T6G(SCH_1):PAGE396_I1@PURE_QUANTA.PT5161LRS(CHIPS)':
 'B_PERN2': CDS_PINID='B_PERN2';
NET_NAME
'P5E_CPU1_P1_TX_C_DP<14>'
 '@T6G_MB_LIB.T6G(SCH_1):P5E_CPU1_P1_TX_C_DP'<14>:
 C_SIGNAL='@t6g_mb_lib.t6g(sch_1):p5e_cpu1_p1_tx_c_dp(14)';
NODE_NAME     C713 1
 '@T6G_MB_LIB.T6G(SCH_1):PAGE354_I297@PURE_QUANTA.Q_CAP_DIFFBUS(CHIPS)':
 '1': CDS_PINID='\1\';
NODE_NAME     U6015 Y34
 '@T6G_MB_LIB.T6G(SCH_1):PAGE396_I1@PURE_QUANTA.PT5161LRS(CHIPS)':
 'B_PERP1': CDS_PINID='B_PERP1';
NET_NAME
'P5E_CPU1_P1_TX_C_DP<15>'
 '@T6G_MB_LIB.T6G(SCH_1):P5E_CPU1_P1_TX_C_DP'<15>:
 C_SIGNAL='@t6g_mb_lib.t6g(sch_1):p5e_cpu1_p1_tx_c_dp(15)';
NODE_NAME     C711 1
 '@T6G_MB_LIB.T6G(SCH_1):PAGE354_I298@PURE_QUANTA.Q_CAP_DIFFBUS(CHIPS)':
 '1': CDS_PINID='\1\';
NODE_NAME     U6015 R35
 '@T6G_MB_LIB.T6G(SCH_1):PAGE396_I1@PURE_QUANTA.PT5161LRS(CHIPS)':
 'B_PERN0': CDS_PINID='B_PERN0';
NET_NAME
'P5E_CPU1_P1_TX_C_DP<1>'
 '@T6G_MB_LIB.T6G(SCH_1):P5E_CPU1_P1_TX_C_DP'<1>:
 C_SIGNAL='@t6g_mb_lib.t6g(sch_1):p5e_cpu1_p1_tx_c_dp(1)';
NODE_NAME     C739 1
 '@T6G_MB_LIB.T6G(SCH_1):PAGE354_I231@PURE_QUANTA.Q_CAP_DIFFBUS(CHIPS)':
 '1': CDS_PINID='\1\';
NODE_NAME     U6015 EL34
 '@T6G_MB_LIB.T6G(SCH_1):PAGE396_I38@PURE_QUANTA.PT5161LRS(CHIPS)':
 'B_PERP14': CDS_PINID='B_PERP14';
NET_NAME
'P5E_CPU1_P1_TX_C_DP<2>'
 '@T6G_MB_LIB.T6G(SCH_1):P5E_CPU1_P1_TX_C_DP'<2>:
 C_SIGNAL='@t6g_mb_lib.t6g(sch_1):p5e_cpu1_p1_tx_c_dp(2)';
NODE_NAME     C737 1
 '@T6G_MB_LIB.T6G(SCH_1):PAGE354_I233@PURE_QUANTA.Q_CAP_DIFFBUS(CHIPS)':
 '1': CDS_PINID='\1\';
NODE_NAME     U6015 EF35
 '@T6G_MB_LIB.T6G(SCH_1):PAGE396_I38@PURE_QUANTA.PT5161LRS(CHIPS)':
 'B_PERN13': CDS_PINID='B_PERN13';
NET_NAME
'P5E_CPU1_P1_TX_C_DP<3>'
 '@T6G_MB_LIB.T6G(SCH_1):P5E_CPU1_P1_TX_C_DP'<3>:
 C_SIGNAL='@t6g_mb_lib.t6g(sch_1):p5e_cpu1_p1_tx_c_dp(3)';
NODE_NAME     C735 1
 '@T6G_MB_LIB.T6G(SCH_1):PAGE354_I236@PURE_QUANTA.Q_CAP_DIFFBUS(CHIPS)':
 '1': CDS_PINID='\1\';
NODE_NAME     U6015 DW35
 '@T6G_MB_LIB.T6G(SCH_1):PAGE396_I38@PURE_QUANTA.PT5161LRS(CHIPS)':
 'B_PERN12': CDS_PINID='B_PERN12';
NET_NAME
'P5E_CPU1_P1_TX_C_DP<4>'
 '@T6G_MB_LIB.T6G(SCH_1):P5E_CPU1_P1_TX_C_DP'<4>:
 C_SIGNAL='@t6g_mb_lib.t6g(sch_1):p5e_cpu1_p1_tx_c_dp(4)';
NODE_NAME     C733 1
 '@T6G_MB_LIB.T6G(SCH_1):PAGE354_I237@PURE_QUANTA.Q_CAP_DIFFBUS(CHIPS)':
 '1': CDS_PINID='\1\';
NODE_NAME     U6015 DM35
 '@T6G_MB_LIB.T6G(SCH_1):PAGE396_I38@PURE_QUANTA.PT5161LRS(CHIPS)':
 'B_PERN11': CDS_PINID='B_PERN11';
NET_NAME
'P5E_CPU1_P1_TX_C_DP<5>'
 '@T6G_MB_LIB.T6G(SCH_1):P5E_CPU1_P1_TX_C_DP'<5>:
 C_SIGNAL='@t6g_mb_lib.t6g(sch_1):p5e_cpu1_p1_tx_c_dp(5)';
NODE_NAME     C731 1
 '@T6G_MB_LIB.T6G(SCH_1):PAGE354_I247@PURE_QUANTA.Q_CAP_DIFFBUS(CHIPS)':
 '1': CDS_PINID='\1\';
NODE_NAME     U6015 DE35
 '@T6G_MB_LIB.T6G(SCH_1):PAGE396_I38@PURE_QUANTA.PT5161LRS(CHIPS)':
 'B_PERN10': CDS_PINID='B_PERN10';
NET_NAME
'P5E_CPU1_P1_TX_C_DP<6>'
 '@T6G_MB_LIB.T6G(SCH_1):P5E_CPU1_P1_TX_C_DP'<6>:
 C_SIGNAL='@t6g_mb_lib.t6g(sch_1):p5e_cpu1_p1_tx_c_dp(6)';
NODE_NAME     C729 1
 '@T6G_MB_LIB.T6G(SCH_1):PAGE354_I249@PURE_QUANTA.Q_CAP_DIFFBUS(CHIPS)':
 '1': CDS_PINID='\1\';
NODE_NAME     U6015 CV35
 '@T6G_MB_LIB.T6G(SCH_1):PAGE396_I38@PURE_QUANTA.PT5161LRS(CHIPS)':
 'B_PERN9': CDS_PINID='B_PERN9';
NET_NAME
'P5E_CPU1_P1_TX_C_DP<7>'
 '@T6G_MB_LIB.T6G(SCH_1):P5E_CPU1_P1_TX_C_DP'<7>:
 C_SIGNAL='@t6g_mb_lib.t6g(sch_1):p5e_cpu1_p1_tx_c_dp(7)';
NODE_NAME     C727 1
 '@T6G_MB_LIB.T6G(SCH_1):PAGE354_I251@PURE_QUANTA.Q_CAP_DIFFBUS(CHIPS)':
 '1': CDS_PINID='\1\';
NODE_NAME     U6015 CL35
 '@T6G_MB_LIB.T6G(SCH_1):PAGE396_I38@PURE_QUANTA.PT5161LRS(CHIPS)':
 'B_PERN8': CDS_PINID='B_PERN8';
NET_NAME
'P5E_CPU1_P1_TX_C_DP<8>'
 '@T6G_MB_LIB.T6G(SCH_1):P5E_CPU1_P1_TX_C_DP'<8>:
 C_SIGNAL='@t6g_mb_lib.t6g(sch_1):p5e_cpu1_p1_tx_c_dp(8)';
NODE_NAME     C725 1
 '@T6G_MB_LIB.T6G(SCH_1):PAGE354_I274@PURE_QUANTA.Q_CAP_DIFFBUS(CHIPS)':
 '1': CDS_PINID='\1\';
NODE_NAME     U6015 CD35
 '@T6G_MB_LIB.T6G(SCH_1):PAGE396_I1@PURE_QUANTA.PT5161LRS(CHIPS)':
 'B_PERN7': CDS_PINID='B_PERN7';
NET_NAME
'P5E_CPU1_P1_TX_C_DP<9>'
 '@T6G_MB_LIB.T6G(SCH_1):P5E_CPU1_P1_TX_C_DP'<9>:
 C_SIGNAL='@t6g_mb_lib.t6g(sch_1):p5e_cpu1_p1_tx_c_dp(9)';
NODE_NAME     C723 1
 '@T6G_MB_LIB.T6G(SCH_1):PAGE354_I277@PURE_QUANTA.Q_CAP_DIFFBUS(CHIPS)':
 '1': CDS_PINID='\1\';
NODE_NAME     U6015 BU35
 '@T6G_MB_LIB.T6G(SCH_1):PAGE396_I1@PURE_QUANTA.PT5161LRS(CHIPS)':
 'B_PERN6': CDS_PINID='B_PERN6';
NET_NAME
'P5E_CPU1_P1_TX_DN<0>'
 '@T6G_MB_LIB.T6G(SCH_1):P5E_CPU1_P1_TX_DN'<0>:
 C_SIGNAL='@t6g_mb_lib.t6g(sch_1):p5e_cpu1_p1_tx_dn(0)';
NODE_NAME     U26 CU52
 '@T6G_MB_LIB.T6G(SCH_1):PAGE51_I148@PURE_QUANTA.GENOA_SP5(CHIPS)':
 'P1_TXN0': CDS_PINID='P1_TXN0';
NODE_NAME     C740 2
 '@T6G_MB_LIB.T6G(SCH_1):PAGE354_I229@PURE_QUANTA.Q_CAP_DIFFBUS(CHIPS)':
 '2': CDS_PINID='\2\';
NET_NAME
'P5E_CPU1_P1_TX_DN<10>'
 '@T6G_MB_LIB.T6G(SCH_1):P5E_CPU1_P1_TX_DN'<10>:
 C_SIGNAL='@t6g_mb_lib.t6g(sch_1):p5e_cpu1_p1_tx_dn(10)';
NODE_NAME     U26 DA43
 '@T6G_MB_LIB.T6G(SCH_1):PAGE51_I148@PURE_QUANTA.GENOA_SP5(CHIPS)':
 'P1_TXN10': CDS_PINID='P1_TXN10';
NODE_NAME     C720 2
 '@T6G_MB_LIB.T6G(SCH_1):PAGE354_I279@PURE_QUANTA.Q_CAP_DIFFBUS(CHIPS)':
 '2': CDS_PINID='\2\';
NET_NAME
'P5E_CPU1_P1_TX_DN<11>'
 '@T6G_MB_LIB.T6G(SCH_1):P5E_CPU1_P1_TX_DN'<11>:
 C_SIGNAL='@t6g_mb_lib.t6g(sch_1):p5e_cpu1_p1_tx_dn(11)';
NODE_NAME     U26 DC43
 '@T6G_MB_LIB.T6G(SCH_1):PAGE51_I148@PURE_QUANTA.GENOA_SP5(CHIPS)':
 'P1_TXN11': CDS_PINID='P1_TXN11';
NODE_NAME     C718 2
 '@T6G_MB_LIB.T6G(SCH_1):PAGE354_I281@PURE_QUANTA.Q_CAP_DIFFBUS(CHIPS)':
 '2': CDS_PINID='\2\';
NET_NAME
'P5E_CPU1_P1_TX_DN<12>'
 '@T6G_MB_LIB.T6G(SCH_1):P5E_CPU1_P1_TX_DN'<12>:
 C_SIGNAL='@t6g_mb_lib.t6g(sch_1):p5e_cpu1_p1_tx_dn(12)';
NODE_NAME     U26 CW43
 '@T6G_MB_LIB.T6G(SCH_1):PAGE51_I148@PURE_QUANTA.GENOA_SP5(CHIPS)':
 'P1_TXN12': CDS_PINID='P1_TXN12';
NODE_NAME     C716 2
 '@T6G_MB_LIB.T6G(SCH_1):PAGE354_I283@PURE_QUANTA.Q_CAP_DIFFBUS(CHIPS)':
 '2': CDS_PINID='\2\';
NET_NAME
'P5E_CPU1_P1_TX_DN<13>'
 '@T6G_MB_LIB.T6G(SCH_1):P5E_CPU1_P1_TX_DN'<13>:
 C_SIGNAL='@t6g_mb_lib.t6g(sch_1):p5e_cpu1_p1_tx_dn(13)';
NODE_NAME     U26 DB40
 '@T6G_MB_LIB.T6G(SCH_1):PAGE51_I148@PURE_QUANTA.GENOA_SP5(CHIPS)':
 'P1_TXN13': CDS_PINID='P1_TXN13';
NODE_NAME     C714 2
 '@T6G_MB_LIB.T6G(SCH_1):PAGE354_I295@PURE_QUANTA.Q_CAP_DIFFBUS(CHIPS)':
 '2': CDS_PINID='\2\';
NET_NAME
'P5E_CPU1_P1_TX_DN<14>'
 '@T6G_MB_LIB.T6G(SCH_1):P5E_CPU1_P1_TX_DN'<14>:
 C_SIGNAL='@t6g_mb_lib.t6g(sch_1):p5e_cpu1_p1_tx_dn(14)';
NODE_NAME     U26 CY40
 '@T6G_MB_LIB.T6G(SCH_1):PAGE51_I148@PURE_QUANTA.GENOA_SP5(CHIPS)':
 'P1_TXN14': CDS_PINID='P1_TXN14';
NODE_NAME     C712 2
 '@T6G_MB_LIB.T6G(SCH_1):PAGE354_I296@PURE_QUANTA.Q_CAP_DIFFBUS(CHIPS)':
 '2': CDS_PINID='\2\';
NET_NAME
'P5E_CPU1_P1_TX_DN<15>'
 '@T6G_MB_LIB.T6G(SCH_1):P5E_CPU1_P1_TX_DN'<15>:
 C_SIGNAL='@t6g_mb_lib.t6g(sch_1):p5e_cpu1_p1_tx_dn(15)';
NODE_NAME     U26 CV40
 '@T6G_MB_LIB.T6G(SCH_1):PAGE51_I148@PURE_QUANTA.GENOA_SP5(CHIPS)':
 'P1_TXN15': CDS_PINID='P1_TXN15';
NODE_NAME     C710 2
 '@T6G_MB_LIB.T6G(SCH_1):PAGE354_I299@PURE_QUANTA.Q_CAP_DIFFBUS(CHIPS)':
 '2': CDS_PINID='\2\';
NET_NAME
'P5E_CPU1_P1_TX_DN<1>'
 '@T6G_MB_LIB.T6G(SCH_1):P5E_CPU1_P1_TX_DN'<1>:
 C_SIGNAL='@t6g_mb_lib.t6g(sch_1):p5e_cpu1_p1_tx_dn(1)';
NODE_NAME     U26 DA52
 '@T6G_MB_LIB.T6G(SCH_1):PAGE51_I148@PURE_QUANTA.GENOA_SP5(CHIPS)':
 'P1_TXN1': CDS_PINID='P1_TXN1';
NODE_NAME     C738 2
 '@T6G_MB_LIB.T6G(SCH_1):PAGE354_I232@PURE_QUANTA.Q_CAP_DIFFBUS(CHIPS)':
 '2': CDS_PINID='\2\';
NET_NAME
'P5E_CPU1_P1_TX_DN<2>'
 '@T6G_MB_LIB.T6G(SCH_1):P5E_CPU1_P1_TX_DN'<2>:
 C_SIGNAL='@t6g_mb_lib.t6g(sch_1):p5e_cpu1_p1_tx_dn(2)';
NODE_NAME     U26 DC52
 '@T6G_MB_LIB.T6G(SCH_1):PAGE51_I148@PURE_QUANTA.GENOA_SP5(CHIPS)':
 'P1_TXN2': CDS_PINID='P1_TXN2';
NODE_NAME     C736 2
 '@T6G_MB_LIB.T6G(SCH_1):PAGE354_I234@PURE_QUANTA.Q_CAP_DIFFBUS(CHIPS)':
 '2': CDS_PINID='\2\';
NET_NAME
'P5E_CPU1_P1_TX_DN<3>'
 '@T6G_MB_LIB.T6G(SCH_1):P5E_CPU1_P1_TX_DN'<3>:
 C_SIGNAL='@t6g_mb_lib.t6g(sch_1):p5e_cpu1_p1_tx_dn(3)';
NODE_NAME     U26 CW52
 '@T6G_MB_LIB.T6G(SCH_1):PAGE51_I148@PURE_QUANTA.GENOA_SP5(CHIPS)':
 'P1_TXN3': CDS_PINID='P1_TXN3';
NODE_NAME     C734 2
 '@T6G_MB_LIB.T6G(SCH_1):PAGE354_I235@PURE_QUANTA.Q_CAP_DIFFBUS(CHIPS)':
 '2': CDS_PINID='\2\';
NET_NAME
'P5E_CPU1_P1_TX_DN<4>'
 '@T6G_MB_LIB.T6G(SCH_1):P5E_CPU1_P1_TX_DN'<4>:
 C_SIGNAL='@t6g_mb_lib.t6g(sch_1):p5e_cpu1_p1_tx_dn(4)';
NODE_NAME     U26 DA49
 '@T6G_MB_LIB.T6G(SCH_1):PAGE51_I148@PURE_QUANTA.GENOA_SP5(CHIPS)':
 'P1_TXN4': CDS_PINID='P1_TXN4';
NODE_NAME     C732 2
 '@T6G_MB_LIB.T6G(SCH_1):PAGE354_I246@PURE_QUANTA.Q_CAP_DIFFBUS(CHIPS)':
 '2': CDS_PINID='\2\';
NET_NAME
'P5E_CPU1_P1_TX_DN<5>'
 '@T6G_MB_LIB.T6G(SCH_1):P5E_CPU1_P1_TX_DN'<5>:
 C_SIGNAL='@t6g_mb_lib.t6g(sch_1):p5e_cpu1_p1_tx_dn(5)';
NODE_NAME     U26 DC49
 '@T6G_MB_LIB.T6G(SCH_1):PAGE51_I148@PURE_QUANTA.GENOA_SP5(CHIPS)':
 'P1_TXN5': CDS_PINID='P1_TXN5';
NODE_NAME     C730 2
 '@T6G_MB_LIB.T6G(SCH_1):PAGE354_I248@PURE_QUANTA.Q_CAP_DIFFBUS(CHIPS)':
 '2': CDS_PINID='\2\';
NET_NAME
'P5E_CPU1_P1_TX_DN<6>'
 '@T6G_MB_LIB.T6G(SCH_1):P5E_CPU1_P1_TX_DN'<6>:
 C_SIGNAL='@t6g_mb_lib.t6g(sch_1):p5e_cpu1_p1_tx_dn(6)';
NODE_NAME     U26 CW49
 '@T6G_MB_LIB.T6G(SCH_1):PAGE51_I148@PURE_QUANTA.GENOA_SP5(CHIPS)':
 'P1_TXN6': CDS_PINID='P1_TXN6';
NODE_NAME     C728 2
 '@T6G_MB_LIB.T6G(SCH_1):PAGE354_I250@PURE_QUANTA.Q_CAP_DIFFBUS(CHIPS)':
 '2': CDS_PINID='\2\';
NET_NAME
'P5E_CPU1_P1_TX_DN<7>'
 '@T6G_MB_LIB.T6G(SCH_1):P5E_CPU1_P1_TX_DN'<7>:
 C_SIGNAL='@t6g_mb_lib.t6g(sch_1):p5e_cpu1_p1_tx_dn(7)';
NODE_NAME     U26 DA46
 '@T6G_MB_LIB.T6G(SCH_1):PAGE51_I148@PURE_QUANTA.GENOA_SP5(CHIPS)':
 'P1_TXN7': CDS_PINID='P1_TXN7';
NODE_NAME     C726 2
 '@T6G_MB_LIB.T6G(SCH_1):PAGE354_I312@PURE_QUANTA.Q_CAP_DIFFBUS(CHIPS)':
 '2': CDS_PINID='\2\';
NET_NAME
'P5E_CPU1_P1_TX_DN<8>'
 '@T6G_MB_LIB.T6G(SCH_1):P5E_CPU1_P1_TX_DN'<8>:
 C_SIGNAL='@t6g_mb_lib.t6g(sch_1):p5e_cpu1_p1_tx_dn(8)';
NODE_NAME     U26 DC46
 '@T6G_MB_LIB.T6G(SCH_1):PAGE51_I148@PURE_QUANTA.GENOA_SP5(CHIPS)':
 'P1_TXN8': CDS_PINID='P1_TXN8';
NODE_NAME     C724 2
 '@T6G_MB_LIB.T6G(SCH_1):PAGE354_I275@PURE_QUANTA.Q_CAP_DIFFBUS(CHIPS)':
 '2': CDS_PINID='\2\';
NET_NAME
'P5E_CPU1_P1_TX_DN<9>'
 '@T6G_MB_LIB.T6G(SCH_1):P5E_CPU1_P1_TX_DN'<9>:
 C_SIGNAL='@t6g_mb_lib.t6g(sch_1):p5e_cpu1_p1_tx_dn(9)';
NODE_NAME     U26 CW46
 '@T6G_MB_LIB.T6G(SCH_1):PAGE51_I148@PURE_QUANTA.GENOA_SP5(CHIPS)':
 'P1_TXN9': CDS_PINID='P1_TXN9';
NODE_NAME     C722 2
 '@T6G_MB_LIB.T6G(SCH_1):PAGE354_I276@PURE_QUANTA.Q_CAP_DIFFBUS(CHIPS)':
 '2': CDS_PINID='\2\';
NET_NAME
'P5E_CPU1_P1_TX_DP<0>'
 '@T6G_MB_LIB.T6G(SCH_1):P5E_CPU1_P1_TX_DP'<0>:
 C_SIGNAL='@t6g_mb_lib.t6g(sch_1):p5e_cpu1_p1_tx_dp(0)';
NODE_NAME     U26 CU53
 '@T6G_MB_LIB.T6G(SCH_1):PAGE51_I148@PURE_QUANTA.GENOA_SP5(CHIPS)':
 'P1_TXP0': CDS_PINID='P1_TXP0';
NODE_NAME     C741 2
 '@T6G_MB_LIB.T6G(SCH_1):PAGE354_I230@PURE_QUANTA.Q_CAP_DIFFBUS(CHIPS)':
 '2': CDS_PINID='\2\';
NET_NAME
'P5E_CPU1_P1_TX_DP<10>'
 '@T6G_MB_LIB.T6G(SCH_1):P5E_CPU1_P1_TX_DP'<10>:
 C_SIGNAL='@t6g_mb_lib.t6g(sch_1):p5e_cpu1_p1_tx_dp(10)';
NODE_NAME     U26 DA44
 '@T6G_MB_LIB.T6G(SCH_1):PAGE51_I148@PURE_QUANTA.GENOA_SP5(CHIPS)':
 'P1_TXP10': CDS_PINID='P1_TXP10';
NODE_NAME     C721 2
 '@T6G_MB_LIB.T6G(SCH_1):PAGE354_I278@PURE_QUANTA.Q_CAP_DIFFBUS(CHIPS)':
 '2': CDS_PINID='\2\';
NET_NAME
'P5E_CPU1_P1_TX_DP<11>'
 '@T6G_MB_LIB.T6G(SCH_1):P5E_CPU1_P1_TX_DP'<11>:
 C_SIGNAL='@t6g_mb_lib.t6g(sch_1):p5e_cpu1_p1_tx_dp(11)';
NODE_NAME     U26 DC44
 '@T6G_MB_LIB.T6G(SCH_1):PAGE51_I148@PURE_QUANTA.GENOA_SP5(CHIPS)':
 'P1_TXP11': CDS_PINID='P1_TXP11';
NODE_NAME     C719 2
 '@T6G_MB_LIB.T6G(SCH_1):PAGE354_I280@PURE_QUANTA.Q_CAP_DIFFBUS(CHIPS)':
 '2': CDS_PINID='\2\';
NET_NAME
'P5E_CPU1_P1_TX_DP<12>'
 '@T6G_MB_LIB.T6G(SCH_1):P5E_CPU1_P1_TX_DP'<12>:
 C_SIGNAL='@t6g_mb_lib.t6g(sch_1):p5e_cpu1_p1_tx_dp(12)';
NODE_NAME     U26 CW44
 '@T6G_MB_LIB.T6G(SCH_1):PAGE51_I148@PURE_QUANTA.GENOA_SP5(CHIPS)':
 'P1_TXP12': CDS_PINID='P1_TXP12';
NODE_NAME     C717 2
 '@T6G_MB_LIB.T6G(SCH_1):PAGE354_I282@PURE_QUANTA.Q_CAP_DIFFBUS(CHIPS)':
 '2': CDS_PINID='\2\';
NET_NAME
'P5E_CPU1_P1_TX_DP<13>'
 '@T6G_MB_LIB.T6G(SCH_1):P5E_CPU1_P1_TX_DP'<13>:
 C_SIGNAL='@t6g_mb_lib.t6g(sch_1):p5e_cpu1_p1_tx_dp(13)';
NODE_NAME     U26 DB41
 '@T6G_MB_LIB.T6G(SCH_1):PAGE51_I148@PURE_QUANTA.GENOA_SP5(CHIPS)':
 'P1_TXP13': CDS_PINID='P1_TXP13';
NODE_NAME     C715 2
 '@T6G_MB_LIB.T6G(SCH_1):PAGE354_I294@PURE_QUANTA.Q_CAP_DIFFBUS(CHIPS)':
 '2': CDS_PINID='\2\';
NET_NAME
'P5E_CPU1_P1_TX_DP<14>'
 '@T6G_MB_LIB.T6G(SCH_1):P5E_CPU1_P1_TX_DP'<14>:
 C_SIGNAL='@t6g_mb_lib.t6g(sch_1):p5e_cpu1_p1_tx_dp(14)';
NODE_NAME     U26 CY41
 '@T6G_MB_LIB.T6G(SCH_1):PAGE51_I148@PURE_QUANTA.GENOA_SP5(CHIPS)':
 'P1_TXP14': CDS_PINID='P1_TXP14';
NODE_NAME     C713 2
 '@T6G_MB_LIB.T6G(SCH_1):PAGE354_I297@PURE_QUANTA.Q_CAP_DIFFBUS(CHIPS)':
 '2': CDS_PINID='\2\';
NET_NAME
'P5E_CPU1_P1_TX_DP<15>'
 '@T6G_MB_LIB.T6G(SCH_1):P5E_CPU1_P1_TX_DP'<15>:
 C_SIGNAL='@t6g_mb_lib.t6g(sch_1):p5e_cpu1_p1_tx_dp(15)';
NODE_NAME     U26 CV41
 '@T6G_MB_LIB.T6G(SCH_1):PAGE51_I148@PURE_QUANTA.GENOA_SP5(CHIPS)':
 'P1_TXP15': CDS_PINID='P1_TXP15';
NODE_NAME     C711 2
 '@T6G_MB_LIB.T6G(SCH_1):PAGE354_I298@PURE_QUANTA.Q_CAP_DIFFBUS(CHIPS)':
 '2': CDS_PINID='\2\';
NET_NAME
'P5E_CPU1_P1_TX_DP<1>'
 '@T6G_MB_LIB.T6G(SCH_1):P5E_CPU1_P1_TX_DP'<1>:
 C_SIGNAL='@t6g_mb_lib.t6g(sch_1):p5e_cpu1_p1_tx_dp(1)';
NODE_NAME     U26 DA53
 '@T6G_MB_LIB.T6G(SCH_1):PAGE51_I148@PURE_QUANTA.GENOA_SP5(CHIPS)':
 'P1_TXP1': CDS_PINID='P1_TXP1';
NODE_NAME     C739 2
 '@T6G_MB_LIB.T6G(SCH_1):PAGE354_I231@PURE_QUANTA.Q_CAP_DIFFBUS(CHIPS)':
 '2': CDS_PINID='\2\';
NET_NAME
'P5E_CPU1_P1_TX_DP<2>'
 '@T6G_MB_LIB.T6G(SCH_1):P5E_CPU1_P1_TX_DP'<2>:
 C_SIGNAL='@t6g_mb_lib.t6g(sch_1):p5e_cpu1_p1_tx_dp(2)';
NODE_NAME     U26 DC53
 '@T6G_MB_LIB.T6G(SCH_1):PAGE51_I148@PURE_QUANTA.GENOA_SP5(CHIPS)':
 'P1_TXP2': CDS_PINID='P1_TXP2';
NODE_NAME     C737 2
 '@T6G_MB_LIB.T6G(SCH_1):PAGE354_I233@PURE_QUANTA.Q_CAP_DIFFBUS(CHIPS)':
 '2': CDS_PINID='\2\';
NET_NAME
'P5E_CPU1_P1_TX_DP<3>'
 '@T6G_MB_LIB.T6G(SCH_1):P5E_CPU1_P1_TX_DP'<3>:
 C_SIGNAL='@t6g_mb_lib.t6g(sch_1):p5e_cpu1_p1_tx_dp(3)';
NODE_NAME     U26 CW53
 '@T6G_MB_LIB.T6G(SCH_1):PAGE51_I148@PURE_QUANTA.GENOA_SP5(CHIPS)':
 'P1_TXP3': CDS_PINID='P1_TXP3';
NODE_NAME     C735 2
 '@T6G_MB_LIB.T6G(SCH_1):PAGE354_I236@PURE_QUANTA.Q_CAP_DIFFBUS(CHIPS)':
 '2': CDS_PINID='\2\';
NET_NAME
'P5E_CPU1_P1_TX_DP<4>'
 '@T6G_MB_LIB.T6G(SCH_1):P5E_CPU1_P1_TX_DP'<4>:
 C_SIGNAL='@t6g_mb_lib.t6g(sch_1):p5e_cpu1_p1_tx_dp(4)';
NODE_NAME     U26 DA50
 '@T6G_MB_LIB.T6G(SCH_1):PAGE51_I148@PURE_QUANTA.GENOA_SP5(CHIPS)':
 'P1_TXP4': CDS_PINID='P1_TXP4';
NODE_NAME     C733 2
 '@T6G_MB_LIB.T6G(SCH_1):PAGE354_I237@PURE_QUANTA.Q_CAP_DIFFBUS(CHIPS)':
 '2': CDS_PINID='\2\';
NET_NAME
'P5E_CPU1_P1_TX_DP<5>'
 '@T6G_MB_LIB.T6G(SCH_1):P5E_CPU1_P1_TX_DP'<5>:
 C_SIGNAL='@t6g_mb_lib.t6g(sch_1):p5e_cpu1_p1_tx_dp(5)';
NODE_NAME     U26 DC50
 '@T6G_MB_LIB.T6G(SCH_1):PAGE51_I148@PURE_QUANTA.GENOA_SP5(CHIPS)':
 'P1_TXP5': CDS_PINID='P1_TXP5';
NODE_NAME     C731 2
 '@T6G_MB_LIB.T6G(SCH_1):PAGE354_I247@PURE_QUANTA.Q_CAP_DIFFBUS(CHIPS)':
 '2': CDS_PINID='\2\';
NET_NAME
'P5E_CPU1_P1_TX_DP<6>'
 '@T6G_MB_LIB.T6G(SCH_1):P5E_CPU1_P1_TX_DP'<6>:
 C_SIGNAL='@t6g_mb_lib.t6g(sch_1):p5e_cpu1_p1_tx_dp(6)';
NODE_NAME     U26 CW50
 '@T6G_MB_LIB.T6G(SCH_1):PAGE51_I148@PURE_QUANTA.GENOA_SP5(CHIPS)':
 'P1_TXP6': CDS_PINID='P1_TXP6';
NODE_NAME     C729 2
 '@T6G_MB_LIB.T6G(SCH_1):PAGE354_I249@PURE_QUANTA.Q_CAP_DIFFBUS(CHIPS)':
 '2': CDS_PINID='\2\';
NET_NAME
'P5E_CPU1_P1_TX_DP<7>'
 '@T6G_MB_LIB.T6G(SCH_1):P5E_CPU1_P1_TX_DP'<7>:
 C_SIGNAL='@t6g_mb_lib.t6g(sch_1):p5e_cpu1_p1_tx_dp(7)';
NODE_NAME     U26 DA47
 '@T6G_MB_LIB.T6G(SCH_1):PAGE51_I148@PURE_QUANTA.GENOA_SP5(CHIPS)':
 'P1_TXP7': CDS_PINID='P1_TXP7';
NODE_NAME     C727 2
 '@T6G_MB_LIB.T6G(SCH_1):PAGE354_I251@PURE_QUANTA.Q_CAP_DIFFBUS(CHIPS)':
 '2': CDS_PINID='\2\';
NET_NAME
'P5E_CPU1_P1_TX_DP<8>'
 '@T6G_MB_LIB.T6G(SCH_1):P5E_CPU1_P1_TX_DP'<8>:
 C_SIGNAL='@t6g_mb_lib.t6g(sch_1):p5e_cpu1_p1_tx_dp(8)';
NODE_NAME     U26 DC47
 '@T6G_MB_LIB.T6G(SCH_1):PAGE51_I148@PURE_QUANTA.GENOA_SP5(CHIPS)':
 'P1_TXP8': CDS_PINID='P1_TXP8';
NODE_NAME     C725 2
 '@T6G_MB_LIB.T6G(SCH_1):PAGE354_I274@PURE_QUANTA.Q_CAP_DIFFBUS(CHIPS)':
 '2': CDS_PINID='\2\';
NET_NAME
'P5E_CPU1_P1_TX_DP<9>'
 '@T6G_MB_LIB.T6G(SCH_1):P5E_CPU1_P1_TX_DP'<9>:
 C_SIGNAL='@t6g_mb_lib.t6g(sch_1):p5e_cpu1_p1_tx_dp(9)';
NODE_NAME     U26 CW47
 '@T6G_MB_LIB.T6G(SCH_1):PAGE51_I148@PURE_QUANTA.GENOA_SP5(CHIPS)':
 'P1_TXP9': CDS_PINID='P1_TXP9';
NODE_NAME     C723 2
 '@T6G_MB_LIB.T6G(SCH_1):PAGE354_I277@PURE_QUANTA.Q_CAP_DIFFBUS(CHIPS)':
 '2': CDS_PINID='\2\';
NET_NAME
'P5E_CPU1_P2_RX_BUF_DN<0>'
 '@T6G_MB_LIB.T6G(SCH_1):P5E_CPU1_P2_RX_BUF_DN'<0>:
 C_SIGNAL='@t6g_mb_lib.t6g(sch_1):p5e_cpu1_p2_rx_buf_dn(0)';
NODE_NAME     U6016 EV2
 '@T6G_MB_LIB.T6G(SCH_1):PAGE449_I38@PURE_QUANTA.PT5161LRS(CHIPS)':
 'A_PERN15': CDS_PINID='A_PERN15';
NODE_NAME     J110 C1
 '@T6G_MB_LIB.T6G(SCH_1):PAGE318_I76@PURE_QUANTA.CONN112_10137002101LF(CHIPS)':
 'C1': CDS_PINID='C1';
NET_NAME
'P5E_CPU1_P2_RX_BUF_DN<10>'
 '@T6G_MB_LIB.T6G(SCH_1):P5E_CPU1_P2_RX_BUF_DN'<10>:
 C_SIGNAL='@t6g_mb_lib.t6g(sch_1):p5e_cpu1_p2_rx_buf_dn(10)';
NODE_NAME     U6016 BH2
 '@T6G_MB_LIB.T6G(SCH_1):PAGE449_I1@PURE_QUANTA.PT5161LRS(CHIPS)':
 'A_PERN5': CDS_PINID='A_PERN5';
NODE_NAME     J109 C3
 '@T6G_MB_LIB.T6G(SCH_1):PAGE319_I76@PURE_QUANTA.CONN112_10137002101LF(CHIPS)':
 'C3': CDS_PINID='C3';
NET_NAME
'P5E_CPU1_P2_RX_BUF_DN<11>'
 '@T6G_MB_LIB.T6G(SCH_1):P5E_CPU1_P2_RX_BUF_DN'<11>:
 C_SIGNAL='@t6g_mb_lib.t6g(sch_1):p5e_cpu1_p2_rx_buf_dn(11)';
NODE_NAME     U6016 BA2
 '@T6G_MB_LIB.T6G(SCH_1):PAGE449_I1@PURE_QUANTA.PT5161LRS(CHIPS)':
 'A_PERN4': CDS_PINID='A_PERN4';
NODE_NAME     J109 B4
 '@T6G_MB_LIB.T6G(SCH_1):PAGE319_I76@PURE_QUANTA.CONN112_10137002101LF(CHIPS)':
 'B4': CDS_PINID='B4';
NET_NAME
'P5E_CPU1_P2_RX_BUF_DN<12>'
 '@T6G_MB_LIB.T6G(SCH_1):P5E_CPU1_P2_RX_BUF_DN'<12>:
 C_SIGNAL='@t6g_mb_lib.t6g(sch_1):p5e_cpu1_p2_rx_buf_dn(12)';
NODE_NAME     U6016 AP2
 '@T6G_MB_LIB.T6G(SCH_1):PAGE449_I1@PURE_QUANTA.PT5161LRS(CHIPS)':
 'A_PERN3': CDS_PINID='A_PERN3';
NODE_NAME     J109 C5
 '@T6G_MB_LIB.T6G(SCH_1):PAGE319_I16@PURE_QUANTA.CONN112_10137002101LF(CHIPS)':
 'C5': CDS_PINID='C5';
NET_NAME
'P5E_CPU1_P2_RX_BUF_DN<13>'
 '@T6G_MB_LIB.T6G(SCH_1):P5E_CPU1_P2_RX_BUF_DN'<13>:
 C_SIGNAL='@t6g_mb_lib.t6g(sch_1):p5e_cpu1_p2_rx_buf_dn(13)';
NODE_NAME     U6016 AG2
 '@T6G_MB_LIB.T6G(SCH_1):PAGE449_I1@PURE_QUANTA.PT5161LRS(CHIPS)':
 'A_PERN2': CDS_PINID='A_PERN2';
NODE_NAME     J109 B6
 '@T6G_MB_LIB.T6G(SCH_1):PAGE319_I16@PURE_QUANTA.CONN112_10137002101LF(CHIPS)':
 'B6': CDS_PINID='B6';
NET_NAME
'P5E_CPU1_P2_RX_BUF_DN<14>'
 '@T6G_MB_LIB.T6G(SCH_1):P5E_CPU1_P2_RX_BUF_DN'<14>:
 C_SIGNAL='@t6g_mb_lib.t6g(sch_1):p5e_cpu1_p2_rx_buf_dn(14)';
NODE_NAME     U6016 Y2
 '@T6G_MB_LIB.T6G(SCH_1):PAGE449_I1@PURE_QUANTA.PT5161LRS(CHIPS)':
 'A_PERN1': CDS_PINID='A_PERN1';
NODE_NAME     J109 C7
 '@T6G_MB_LIB.T6G(SCH_1):PAGE319_I16@PURE_QUANTA.CONN112_10137002101LF(CHIPS)':
 'C7': CDS_PINID='C7';
NET_NAME
'P5E_CPU1_P2_RX_BUF_DN<15>'
 '@T6G_MB_LIB.T6G(SCH_1):P5E_CPU1_P2_RX_BUF_DN'<15>:
 C_SIGNAL='@t6g_mb_lib.t6g(sch_1):p5e_cpu1_p2_rx_buf_dn(15)';
NODE_NAME     U6016 N2
 '@T6G_MB_LIB.T6G(SCH_1):PAGE449_I1@PURE_QUANTA.PT5161LRS(CHIPS)':
 'A_PERN0': CDS_PINID='A_PERN0';
NODE_NAME     J109 B8
 '@T6G_MB_LIB.T6G(SCH_1):PAGE319_I16@PURE_QUANTA.CONN112_10137002101LF(CHIPS)':
 'B8': CDS_PINID='B8';
NET_NAME
'P5E_CPU1_P2_RX_BUF_DN<1>'
 '@T6G_MB_LIB.T6G(SCH_1):P5E_CPU1_P2_RX_BUF_DN'<1>:
 C_SIGNAL='@t6g_mb_lib.t6g(sch_1):p5e_cpu1_p2_rx_buf_dn(1)';
NODE_NAME     U6016 EL2
 '@T6G_MB_LIB.T6G(SCH_1):PAGE449_I38@PURE_QUANTA.PT5161LRS(CHIPS)':
 'A_PERN14': CDS_PINID='A_PERN14';
NODE_NAME     J110 B2
 '@T6G_MB_LIB.T6G(SCH_1):PAGE318_I76@PURE_QUANTA.CONN112_10137002101LF(CHIPS)':
 'B2': CDS_PINID='B2';
NET_NAME
'P5E_CPU1_P2_RX_BUF_DN<2>'
 '@T6G_MB_LIB.T6G(SCH_1):P5E_CPU1_P2_RX_BUF_DN'<2>:
 C_SIGNAL='@t6g_mb_lib.t6g(sch_1):p5e_cpu1_p2_rx_buf_dn(2)';
NODE_NAME     U6016 ED2
 '@T6G_MB_LIB.T6G(SCH_1):PAGE449_I38@PURE_QUANTA.PT5161LRS(CHIPS)':
 'A_PERN13': CDS_PINID='A_PERN13';
NODE_NAME     J110 C3
 '@T6G_MB_LIB.T6G(SCH_1):PAGE318_I76@PURE_QUANTA.CONN112_10137002101LF(CHIPS)':
 'C3': CDS_PINID='C3';
NET_NAME
'P5E_CPU1_P2_RX_BUF_DN<3>'
 '@T6G_MB_LIB.T6G(SCH_1):P5E_CPU1_P2_RX_BUF_DN'<3>:
 C_SIGNAL='@t6g_mb_lib.t6g(sch_1):p5e_cpu1_p2_rx_buf_dn(3)';
NODE_NAME     U6016 DU2
 '@T6G_MB_LIB.T6G(SCH_1):PAGE449_I38@PURE_QUANTA.PT5161LRS(CHIPS)':
 'A_PERN12': CDS_PINID='A_PERN12';
NODE_NAME     J110 B4
 '@T6G_MB_LIB.T6G(SCH_1):PAGE318_I76@PURE_QUANTA.CONN112_10137002101LF(CHIPS)':
 'B4': CDS_PINID='B4';
NET_NAME
'P5E_CPU1_P2_RX_BUF_DN<4>'
 '@T6G_MB_LIB.T6G(SCH_1):P5E_CPU1_P2_RX_BUF_DN'<4>:
 C_SIGNAL='@t6g_mb_lib.t6g(sch_1):p5e_cpu1_p2_rx_buf_dn(4)';
NODE_NAME     U6016 DK2
 '@T6G_MB_LIB.T6G(SCH_1):PAGE449_I38@PURE_QUANTA.PT5161LRS(CHIPS)':
 'A_PERN11': CDS_PINID='A_PERN11';
NODE_NAME     J110 C5
 '@T6G_MB_LIB.T6G(SCH_1):PAGE318_I16@PURE_QUANTA.CONN112_10137002101LF(CHIPS)':
 'C5': CDS_PINID='C5';
NET_NAME
'P5E_CPU1_P2_RX_BUF_DN<5>'
 '@T6G_MB_LIB.T6G(SCH_1):P5E_CPU1_P2_RX_BUF_DN'<5>:
 C_SIGNAL='@t6g_mb_lib.t6g(sch_1):p5e_cpu1_p2_rx_buf_dn(5)';
NODE_NAME     U6016 DC2
 '@T6G_MB_LIB.T6G(SCH_1):PAGE449_I38@PURE_QUANTA.PT5161LRS(CHIPS)':
 'A_PERN10': CDS_PINID='A_PERN10';
NODE_NAME     J110 B6
 '@T6G_MB_LIB.T6G(SCH_1):PAGE318_I16@PURE_QUANTA.CONN112_10137002101LF(CHIPS)':
 'B6': CDS_PINID='B6';
NET_NAME
'P5E_CPU1_P2_RX_BUF_DN<6>'
 '@T6G_MB_LIB.T6G(SCH_1):P5E_CPU1_P2_RX_BUF_DN'<6>:
 C_SIGNAL='@t6g_mb_lib.t6g(sch_1):p5e_cpu1_p2_rx_buf_dn(6)';
NODE_NAME     U6016 CT2
 '@T6G_MB_LIB.T6G(SCH_1):PAGE449_I38@PURE_QUANTA.PT5161LRS(CHIPS)':
 'A_PERN9': CDS_PINID='A_PERN9';
NODE_NAME     J110 C7
 '@T6G_MB_LIB.T6G(SCH_1):PAGE318_I16@PURE_QUANTA.CONN112_10137002101LF(CHIPS)':
 'C7': CDS_PINID='C7';
NET_NAME
'P5E_CPU1_P2_RX_BUF_DN<7>'
 '@T6G_MB_LIB.T6G(SCH_1):P5E_CPU1_P2_RX_BUF_DN'<7>:
 C_SIGNAL='@t6g_mb_lib.t6g(sch_1):p5e_cpu1_p2_rx_buf_dn(7)';
NODE_NAME     U6016 CJ2
 '@T6G_MB_LIB.T6G(SCH_1):PAGE449_I38@PURE_QUANTA.PT5161LRS(CHIPS)':
 'A_PERN8': CDS_PINID='A_PERN8';
NODE_NAME     J110 B8
 '@T6G_MB_LIB.T6G(SCH_1):PAGE318_I16@PURE_QUANTA.CONN112_10137002101LF(CHIPS)':
 'B8': CDS_PINID='B8';
NET_NAME
'P5E_CPU1_P2_RX_BUF_DN<8>'
 '@T6G_MB_LIB.T6G(SCH_1):P5E_CPU1_P2_RX_BUF_DN'<8>:
 C_SIGNAL='@t6g_mb_lib.t6g(sch_1):p5e_cpu1_p2_rx_buf_dn(8)';
NODE_NAME     U6016 CB2
 '@T6G_MB_LIB.T6G(SCH_1):PAGE449_I1@PURE_QUANTA.PT5161LRS(CHIPS)':
 'A_PERN7': CDS_PINID='A_PERN7';
NODE_NAME     J109 C1
 '@T6G_MB_LIB.T6G(SCH_1):PAGE319_I76@PURE_QUANTA.CONN112_10137002101LF(CHIPS)':
 'C1': CDS_PINID='C1';
NET_NAME
'P5E_CPU1_P2_RX_BUF_DN<9>'
 '@T6G_MB_LIB.T6G(SCH_1):P5E_CPU1_P2_RX_BUF_DN'<9>:
 C_SIGNAL='@t6g_mb_lib.t6g(sch_1):p5e_cpu1_p2_rx_buf_dn(9)';
NODE_NAME     U6016 BR2
 '@T6G_MB_LIB.T6G(SCH_1):PAGE449_I1@PURE_QUANTA.PT5161LRS(CHIPS)':
 'A_PERN6': CDS_PINID='A_PERN6';
NODE_NAME     J109 B2
 '@T6G_MB_LIB.T6G(SCH_1):PAGE319_I76@PURE_QUANTA.CONN112_10137002101LF(CHIPS)':
 'B2': CDS_PINID='B2';
NET_NAME
'P5E_CPU1_P2_RX_BUF_DP<0>'
 '@T6G_MB_LIB.T6G(SCH_1):P5E_CPU1_P2_RX_BUF_DP'<0>:
 C_SIGNAL='@t6g_mb_lib.t6g(sch_1):p5e_cpu1_p2_rx_buf_dp(0)';
NODE_NAME     U6016 EY1
 '@T6G_MB_LIB.T6G(SCH_1):PAGE449_I38@PURE_QUANTA.PT5161LRS(CHIPS)':
 'A_PERP15': CDS_PINID='A_PERP15';
NODE_NAME     J110 D1
 '@T6G_MB_LIB.T6G(SCH_1):PAGE318_I76@PURE_QUANTA.CONN112_10137002101LF(CHIPS)':
 'D1': CDS_PINID='D1';
NET_NAME
'P5E_CPU1_P2_RX_BUF_DP<10>'
 '@T6G_MB_LIB.T6G(SCH_1):P5E_CPU1_P2_RX_BUF_DP'<10>:
 C_SIGNAL='@t6g_mb_lib.t6g(sch_1):p5e_cpu1_p2_rx_buf_dp(10)';
NODE_NAME     U6016 BK1
 '@T6G_MB_LIB.T6G(SCH_1):PAGE449_I1@PURE_QUANTA.PT5161LRS(CHIPS)':
 'A_PERP5': CDS_PINID='A_PERP5';
NODE_NAME     J109 D3
 '@T6G_MB_LIB.T6G(SCH_1):PAGE319_I76@PURE_QUANTA.CONN112_10137002101LF(CHIPS)':
 'D3': CDS_PINID='D3';
NET_NAME
'P5E_CPU1_P2_RX_BUF_DP<11>'
 '@T6G_MB_LIB.T6G(SCH_1):P5E_CPU1_P2_RX_BUF_DP'<11>:
 C_SIGNAL='@t6g_mb_lib.t6g(sch_1):p5e_cpu1_p2_rx_buf_dp(11)';
NODE_NAME     U6016 BC1
 '@T6G_MB_LIB.T6G(SCH_1):PAGE449_I1@PURE_QUANTA.PT5161LRS(CHIPS)':
 'A_PERP4': CDS_PINID='A_PERP4';
NODE_NAME     J109 C4
 '@T6G_MB_LIB.T6G(SCH_1):PAGE319_I76@PURE_QUANTA.CONN112_10137002101LF(CHIPS)':
 'C4': CDS_PINID='C4';
NET_NAME
'P5E_CPU1_P2_RX_BUF_DP<12>'
 '@T6G_MB_LIB.T6G(SCH_1):P5E_CPU1_P2_RX_BUF_DP'<12>:
 C_SIGNAL='@t6g_mb_lib.t6g(sch_1):p5e_cpu1_p2_rx_buf_dp(12)';
NODE_NAME     U6016 AT1
 '@T6G_MB_LIB.T6G(SCH_1):PAGE449_I1@PURE_QUANTA.PT5161LRS(CHIPS)':
 'A_PERP3': CDS_PINID='A_PERP3';
NODE_NAME     J109 D5
 '@T6G_MB_LIB.T6G(SCH_1):PAGE319_I16@PURE_QUANTA.CONN112_10137002101LF(CHIPS)':
 'D5': CDS_PINID='D5';
NET_NAME
'P5E_CPU1_P2_RX_BUF_DP<13>'
 '@T6G_MB_LIB.T6G(SCH_1):P5E_CPU1_P2_RX_BUF_DP'<13>:
 C_SIGNAL='@t6g_mb_lib.t6g(sch_1):p5e_cpu1_p2_rx_buf_dp(13)';
NODE_NAME     U6016 AJ1
 '@T6G_MB_LIB.T6G(SCH_1):PAGE449_I1@PURE_QUANTA.PT5161LRS(CHIPS)':
 'A_PERP2': CDS_PINID='A_PERP2';
NODE_NAME     J109 C6
 '@T6G_MB_LIB.T6G(SCH_1):PAGE319_I16@PURE_QUANTA.CONN112_10137002101LF(CHIPS)':
 'C6': CDS_PINID='C6';
NET_NAME
'P5E_CPU1_P2_RX_BUF_DP<14>'
 '@T6G_MB_LIB.T6G(SCH_1):P5E_CPU1_P2_RX_BUF_DP'<14>:
 C_SIGNAL='@t6g_mb_lib.t6g(sch_1):p5e_cpu1_p2_rx_buf_dp(14)';
NODE_NAME     U6016 AB1
 '@T6G_MB_LIB.T6G(SCH_1):PAGE449_I1@PURE_QUANTA.PT5161LRS(CHIPS)':
 'A_PERP1': CDS_PINID='A_PERP1';
NODE_NAME     J109 D7
 '@T6G_MB_LIB.T6G(SCH_1):PAGE319_I16@PURE_QUANTA.CONN112_10137002101LF(CHIPS)':
 'D7': CDS_PINID='D7';
NET_NAME
'P5E_CPU1_P2_RX_BUF_DP<15>'
 '@T6G_MB_LIB.T6G(SCH_1):P5E_CPU1_P2_RX_BUF_DP'<15>:
 C_SIGNAL='@t6g_mb_lib.t6g(sch_1):p5e_cpu1_p2_rx_buf_dp(15)';
NODE_NAME     U6016 R1
 '@T6G_MB_LIB.T6G(SCH_1):PAGE449_I1@PURE_QUANTA.PT5161LRS(CHIPS)':
 'A_PERP0': CDS_PINID='A_PERP0';
NODE_NAME     J109 C8
 '@T6G_MB_LIB.T6G(SCH_1):PAGE319_I16@PURE_QUANTA.CONN112_10137002101LF(CHIPS)':
 'C8': CDS_PINID='C8';
NET_NAME
'P5E_CPU1_P2_RX_BUF_DP<1>'
 '@T6G_MB_LIB.T6G(SCH_1):P5E_CPU1_P2_RX_BUF_DP'<1>:
 C_SIGNAL='@t6g_mb_lib.t6g(sch_1):p5e_cpu1_p2_rx_buf_dp(1)';
NODE_NAME     U6016 EN1
 '@T6G_MB_LIB.T6G(SCH_1):PAGE449_I38@PURE_QUANTA.PT5161LRS(CHIPS)':
 'A_PERP14': CDS_PINID='A_PERP14';
NODE_NAME     J110 C2
 '@T6G_MB_LIB.T6G(SCH_1):PAGE318_I76@PURE_QUANTA.CONN112_10137002101LF(CHIPS)':
 'C2': CDS_PINID='C2';
NET_NAME
'P5E_CPU1_P2_RX_BUF_DP<2>'
 '@T6G_MB_LIB.T6G(SCH_1):P5E_CPU1_P2_RX_BUF_DP'<2>:
 C_SIGNAL='@t6g_mb_lib.t6g(sch_1):p5e_cpu1_p2_rx_buf_dp(2)';
NODE_NAME     U6016 EF1
 '@T6G_MB_LIB.T6G(SCH_1):PAGE449_I38@PURE_QUANTA.PT5161LRS(CHIPS)':
 'A_PERP13': CDS_PINID='A_PERP13';
NODE_NAME     J110 D3
 '@T6G_MB_LIB.T6G(SCH_1):PAGE318_I76@PURE_QUANTA.CONN112_10137002101LF(CHIPS)':
 'D3': CDS_PINID='D3';
NET_NAME
'P5E_CPU1_P2_RX_BUF_DP<3>'
 '@T6G_MB_LIB.T6G(SCH_1):P5E_CPU1_P2_RX_BUF_DP'<3>:
 C_SIGNAL='@t6g_mb_lib.t6g(sch_1):p5e_cpu1_p2_rx_buf_dp(3)';
NODE_NAME     U6016 DW1
 '@T6G_MB_LIB.T6G(SCH_1):PAGE449_I38@PURE_QUANTA.PT5161LRS(CHIPS)':
 'A_PERP12': CDS_PINID='A_PERP12';
NODE_NAME     J110 C4
 '@T6G_MB_LIB.T6G(SCH_1):PAGE318_I76@PURE_QUANTA.CONN112_10137002101LF(CHIPS)':
 'C4': CDS_PINID='C4';
NET_NAME
'P5E_CPU1_P2_RX_BUF_DP<4>'
 '@T6G_MB_LIB.T6G(SCH_1):P5E_CPU1_P2_RX_BUF_DP'<4>:
 C_SIGNAL='@t6g_mb_lib.t6g(sch_1):p5e_cpu1_p2_rx_buf_dp(4)';
NODE_NAME     U6016 DM1
 '@T6G_MB_LIB.T6G(SCH_1):PAGE449_I38@PURE_QUANTA.PT5161LRS(CHIPS)':
 'A_PERP11': CDS_PINID='A_PERP11';
NODE_NAME     J110 D5
 '@T6G_MB_LIB.T6G(SCH_1):PAGE318_I16@PURE_QUANTA.CONN112_10137002101LF(CHIPS)':
 'D5': CDS_PINID='D5';
NET_NAME
'P5E_CPU1_P2_RX_BUF_DP<5>'
 '@T6G_MB_LIB.T6G(SCH_1):P5E_CPU1_P2_RX_BUF_DP'<5>:
 C_SIGNAL='@t6g_mb_lib.t6g(sch_1):p5e_cpu1_p2_rx_buf_dp(5)';
NODE_NAME     U6016 DE1
 '@T6G_MB_LIB.T6G(SCH_1):PAGE449_I38@PURE_QUANTA.PT5161LRS(CHIPS)':
 'A_PERP10': CDS_PINID='A_PERP10';
NODE_NAME     J110 C6
 '@T6G_MB_LIB.T6G(SCH_1):PAGE318_I16@PURE_QUANTA.CONN112_10137002101LF(CHIPS)':
 'C6': CDS_PINID='C6';
NET_NAME
'P5E_CPU1_P2_RX_BUF_DP<6>'
 '@T6G_MB_LIB.T6G(SCH_1):P5E_CPU1_P2_RX_BUF_DP'<6>:
 C_SIGNAL='@t6g_mb_lib.t6g(sch_1):p5e_cpu1_p2_rx_buf_dp(6)';
NODE_NAME     U6016 CV1
 '@T6G_MB_LIB.T6G(SCH_1):PAGE449_I38@PURE_QUANTA.PT5161LRS(CHIPS)':
 'A_PERP9': CDS_PINID='A_PERP9';
NODE_NAME     J110 D7
 '@T6G_MB_LIB.T6G(SCH_1):PAGE318_I16@PURE_QUANTA.CONN112_10137002101LF(CHIPS)':
 'D7': CDS_PINID='D7';
NET_NAME
'P5E_CPU1_P2_RX_BUF_DP<7>'
 '@T6G_MB_LIB.T6G(SCH_1):P5E_CPU1_P2_RX_BUF_DP'<7>:
 C_SIGNAL='@t6g_mb_lib.t6g(sch_1):p5e_cpu1_p2_rx_buf_dp(7)';
NODE_NAME     U6016 CL1
 '@T6G_MB_LIB.T6G(SCH_1):PAGE449_I38@PURE_QUANTA.PT5161LRS(CHIPS)':
 'A_PERP8': CDS_PINID='A_PERP8';
NODE_NAME     J110 C8
 '@T6G_MB_LIB.T6G(SCH_1):PAGE318_I16@PURE_QUANTA.CONN112_10137002101LF(CHIPS)':
 'C8': CDS_PINID='C8';
NET_NAME
'P5E_CPU1_P2_RX_BUF_DP<8>'
 '@T6G_MB_LIB.T6G(SCH_1):P5E_CPU1_P2_RX_BUF_DP'<8>:
 C_SIGNAL='@t6g_mb_lib.t6g(sch_1):p5e_cpu1_p2_rx_buf_dp(8)';
NODE_NAME     U6016 CD1
 '@T6G_MB_LIB.T6G(SCH_1):PAGE449_I1@PURE_QUANTA.PT5161LRS(CHIPS)':
 'A_PERP7': CDS_PINID='A_PERP7';
NODE_NAME     J109 D1
 '@T6G_MB_LIB.T6G(SCH_1):PAGE319_I76@PURE_QUANTA.CONN112_10137002101LF(CHIPS)':
 'D1': CDS_PINID='D1';
NET_NAME
'P5E_CPU1_P2_RX_BUF_DP<9>'
 '@T6G_MB_LIB.T6G(SCH_1):P5E_CPU1_P2_RX_BUF_DP'<9>:
 C_SIGNAL='@t6g_mb_lib.t6g(sch_1):p5e_cpu1_p2_rx_buf_dp(9)';
NODE_NAME     U6016 BU1
 '@T6G_MB_LIB.T6G(SCH_1):PAGE449_I1@PURE_QUANTA.PT5161LRS(CHIPS)':
 'A_PERP6': CDS_PINID='A_PERP6';
NODE_NAME     J109 C2
 '@T6G_MB_LIB.T6G(SCH_1):PAGE319_I76@PURE_QUANTA.CONN112_10137002101LF(CHIPS)':
 'C2': CDS_PINID='C2';
NET_NAME
'P5E_CPU1_P2_RX_DN<0>'
 '@T6G_MB_LIB.T6G(SCH_1):P5E_CPU1_P2_RX_DN'<0>:
 C_SIGNAL='@t6g_mb_lib.t6g(sch_1):p5e_cpu1_p2_rx_dn(0)';
NODE_NAME     U26 CM36
 '@T6G_MB_LIB.T6G(SCH_1):PAGE52_I148@PURE_QUANTA.GENOA_SP5(CHIPS)':
 'P2_RXN0': CDS_PINID='P2_RXN0';
NODE_NAME     U6016 EW29
 '@T6G_MB_LIB.T6G(SCH_1):PAGE448_I38@PURE_QUANTA.PT5161LRS(CHIPS)':
 'A_PETN15': CDS_PINID='A_PETN15';
NET_NAME
'P5E_CPU1_P2_RX_DN<10>'
 '@T6G_MB_LIB.T6G(SCH_1):P5E_CPU1_P2_RX_DN'<10>:
 C_SIGNAL='@t6g_mb_lib.t6g(sch_1):p5e_cpu1_p2_rx_dn(10)';
NODE_NAME     U26 CU27
 '@T6G_MB_LIB.T6G(SCH_1):PAGE52_I148@PURE_QUANTA.GENOA_SP5(CHIPS)':
 'P2_RXN10': CDS_PINID='P2_RXN10';
NODE_NAME     U6016 BJ29
 '@T6G_MB_LIB.T6G(SCH_1):PAGE448_I1@PURE_QUANTA.PT5161LRS(CHIPS)':
 'A_PETN5': CDS_PINID='A_PETN5';
NET_NAME
'P5E_CPU1_P2_RX_DN<11>'
 '@T6G_MB_LIB.T6G(SCH_1):P5E_CPU1_P2_RX_DN'<11>:
 C_SIGNAL='@t6g_mb_lib.t6g(sch_1):p5e_cpu1_p2_rx_dn(11)';
NODE_NAME     U26 CR27
 '@T6G_MB_LIB.T6G(SCH_1):PAGE52_I148@PURE_QUANTA.GENOA_SP5(CHIPS)':
 'P2_RXN11': CDS_PINID='P2_RXN11';
NODE_NAME     U6016 BB29
 '@T6G_MB_LIB.T6G(SCH_1):PAGE448_I1@PURE_QUANTA.PT5161LRS(CHIPS)':
 'A_PETN4': CDS_PINID='A_PETN4';
NET_NAME
'P5E_CPU1_P2_RX_DN<12>'
 '@T6G_MB_LIB.T6G(SCH_1):P5E_CPU1_P2_RX_DN'<12>:
 C_SIGNAL='@t6g_mb_lib.t6g(sch_1):p5e_cpu1_p2_rx_dn(12)';
NODE_NAME     U26 CN27
 '@T6G_MB_LIB.T6G(SCH_1):PAGE52_I148@PURE_QUANTA.GENOA_SP5(CHIPS)':
 'P2_RXN12': CDS_PINID='P2_RXN12';
NODE_NAME     U6016 AR29
 '@T6G_MB_LIB.T6G(SCH_1):PAGE448_I1@PURE_QUANTA.PT5161LRS(CHIPS)':
 'A_PETN3': CDS_PINID='A_PETN3';
NET_NAME
'P5E_CPU1_P2_RX_DN<13>'
 '@T6G_MB_LIB.T6G(SCH_1):P5E_CPU1_P2_RX_DN'<13>:
 C_SIGNAL='@t6g_mb_lib.t6g(sch_1):p5e_cpu1_p2_rx_dn(13)';
NODE_NAME     U26 CL24
 '@T6G_MB_LIB.T6G(SCH_1):PAGE52_I148@PURE_QUANTA.GENOA_SP5(CHIPS)':
 'P2_RXN13': CDS_PINID='P2_RXN13';
NODE_NAME     U6016 AH29
 '@T6G_MB_LIB.T6G(SCH_1):PAGE448_I1@PURE_QUANTA.PT5161LRS(CHIPS)':
 'A_PETN2': CDS_PINID='A_PETN2';
NET_NAME
'P5E_CPU1_P2_RX_DN<14>'
 '@T6G_MB_LIB.T6G(SCH_1):P5E_CPU1_P2_RX_DN'<14>:
 C_SIGNAL='@t6g_mb_lib.t6g(sch_1):p5e_cpu1_p2_rx_dn(14)';
NODE_NAME     U26 CR24
 '@T6G_MB_LIB.T6G(SCH_1):PAGE52_I148@PURE_QUANTA.GENOA_SP5(CHIPS)':
 'P2_RXN14': CDS_PINID='P2_RXN14';
NODE_NAME     U6016 AA29
 '@T6G_MB_LIB.T6G(SCH_1):PAGE448_I1@PURE_QUANTA.PT5161LRS(CHIPS)':
 'A_PETN1': CDS_PINID='A_PETN1';
NET_NAME
'P5E_CPU1_P2_RX_DN<15>'
 '@T6G_MB_LIB.T6G(SCH_1):P5E_CPU1_P2_RX_DN'<15>:
 C_SIGNAL='@t6g_mb_lib.t6g(sch_1):p5e_cpu1_p2_rx_dn(15)';
NODE_NAME     U26 CN24
 '@T6G_MB_LIB.T6G(SCH_1):PAGE52_I148@PURE_QUANTA.GENOA_SP5(CHIPS)':
 'P2_RXN15': CDS_PINID='P2_RXN15';
NODE_NAME     U6016 P29
 '@T6G_MB_LIB.T6G(SCH_1):PAGE448_I1@PURE_QUANTA.PT5161LRS(CHIPS)':
 'A_PETN0': CDS_PINID='A_PETN0';
NET_NAME
'P5E_CPU1_P2_RX_DN<1>'
 '@T6G_MB_LIB.T6G(SCH_1):P5E_CPU1_P2_RX_DN'<1>:
 C_SIGNAL='@t6g_mb_lib.t6g(sch_1):p5e_cpu1_p2_rx_dn(1)';
NODE_NAME     U26 CP36
 '@T6G_MB_LIB.T6G(SCH_1):PAGE52_I148@PURE_QUANTA.GENOA_SP5(CHIPS)':
 'P2_RXN1': CDS_PINID='P2_RXN1';
NODE_NAME     U6016 EM29
 '@T6G_MB_LIB.T6G(SCH_1):PAGE448_I38@PURE_QUANTA.PT5161LRS(CHIPS)':
 'A_PETN14': CDS_PINID='A_PETN14';
NET_NAME
'P5E_CPU1_P2_RX_DN<2>'
 '@T6G_MB_LIB.T6G(SCH_1):P5E_CPU1_P2_RX_DN'<2>:
 C_SIGNAL='@t6g_mb_lib.t6g(sch_1):p5e_cpu1_p2_rx_dn(2)';
NODE_NAME     U26 CT36
 '@T6G_MB_LIB.T6G(SCH_1):PAGE52_I148@PURE_QUANTA.GENOA_SP5(CHIPS)':
 'P2_RXN2': CDS_PINID='P2_RXN2';
NODE_NAME     U6016 EE29
 '@T6G_MB_LIB.T6G(SCH_1):PAGE448_I38@PURE_QUANTA.PT5161LRS(CHIPS)':
 'A_PETN13': CDS_PINID='A_PETN13';
NET_NAME
'P5E_CPU1_P2_RX_DN<3>'
 '@T6G_MB_LIB.T6G(SCH_1):P5E_CPU1_P2_RX_DN'<3>:
 C_SIGNAL='@t6g_mb_lib.t6g(sch_1):p5e_cpu1_p2_rx_dn(3)';
NODE_NAME     U26 CN33
 '@T6G_MB_LIB.T6G(SCH_1):PAGE52_I148@PURE_QUANTA.GENOA_SP5(CHIPS)':
 'P2_RXN3': CDS_PINID='P2_RXN3';
NODE_NAME     U6016 DV29
 '@T6G_MB_LIB.T6G(SCH_1):PAGE448_I38@PURE_QUANTA.PT5161LRS(CHIPS)':
 'A_PETN12': CDS_PINID='A_PETN12';
NET_NAME
'P5E_CPU1_P2_RX_DN<4>'
 '@T6G_MB_LIB.T6G(SCH_1):P5E_CPU1_P2_RX_DN'<4>:
 C_SIGNAL='@t6g_mb_lib.t6g(sch_1):p5e_cpu1_p2_rx_dn(4)';
NODE_NAME     U26 CU33
 '@T6G_MB_LIB.T6G(SCH_1):PAGE52_I148@PURE_QUANTA.GENOA_SP5(CHIPS)':
 'P2_RXN4': CDS_PINID='P2_RXN4';
NODE_NAME     U6016 DL29
 '@T6G_MB_LIB.T6G(SCH_1):PAGE448_I38@PURE_QUANTA.PT5161LRS(CHIPS)':
 'A_PETN11': CDS_PINID='A_PETN11';
NET_NAME
'P5E_CPU1_P2_RX_DN<5>'
 '@T6G_MB_LIB.T6G(SCH_1):P5E_CPU1_P2_RX_DN'<5>:
 C_SIGNAL='@t6g_mb_lib.t6g(sch_1):p5e_cpu1_p2_rx_dn(5)';
NODE_NAME     U26 CR33
 '@T6G_MB_LIB.T6G(SCH_1):PAGE52_I148@PURE_QUANTA.GENOA_SP5(CHIPS)':
 'P2_RXN5': CDS_PINID='P2_RXN5';
NODE_NAME     U6016 DD29
 '@T6G_MB_LIB.T6G(SCH_1):PAGE448_I38@PURE_QUANTA.PT5161LRS(CHIPS)':
 'A_PETN10': CDS_PINID='A_PETN10';
NET_NAME
'P5E_CPU1_P2_RX_DN<6>'
 '@T6G_MB_LIB.T6G(SCH_1):P5E_CPU1_P2_RX_DN'<6>:
 C_SIGNAL='@t6g_mb_lib.t6g(sch_1):p5e_cpu1_p2_rx_dn(6)';
NODE_NAME     U26 CN30
 '@T6G_MB_LIB.T6G(SCH_1):PAGE52_I148@PURE_QUANTA.GENOA_SP5(CHIPS)':
 'P2_RXN6': CDS_PINID='P2_RXN6';
NODE_NAME     U6016 CU29
 '@T6G_MB_LIB.T6G(SCH_1):PAGE448_I38@PURE_QUANTA.PT5161LRS(CHIPS)':
 'A_PETN9': CDS_PINID='A_PETN9';
NET_NAME
'P5E_CPU1_P2_RX_DN<7>'
 '@T6G_MB_LIB.T6G(SCH_1):P5E_CPU1_P2_RX_DN'<7>:
 C_SIGNAL='@t6g_mb_lib.t6g(sch_1):p5e_cpu1_p2_rx_dn(7)';
NODE_NAME     U26 CU30
 '@T6G_MB_LIB.T6G(SCH_1):PAGE52_I148@PURE_QUANTA.GENOA_SP5(CHIPS)':
 'P2_RXN7': CDS_PINID='P2_RXN7';
NODE_NAME     U6016 CK29
 '@T6G_MB_LIB.T6G(SCH_1):PAGE448_I38@PURE_QUANTA.PT5161LRS(CHIPS)':
 'A_PETN8': CDS_PINID='A_PETN8';
NET_NAME
'P5E_CPU1_P2_RX_DN<8>'
 '@T6G_MB_LIB.T6G(SCH_1):P5E_CPU1_P2_RX_DN'<8>:
 C_SIGNAL='@t6g_mb_lib.t6g(sch_1):p5e_cpu1_p2_rx_dn(8)';
NODE_NAME     U26 CR30
 '@T6G_MB_LIB.T6G(SCH_1):PAGE52_I148@PURE_QUANTA.GENOA_SP5(CHIPS)':
 'P2_RXN8': CDS_PINID='P2_RXN8';
NODE_NAME     U6016 CC29
 '@T6G_MB_LIB.T6G(SCH_1):PAGE448_I1@PURE_QUANTA.PT5161LRS(CHIPS)':
 'A_PETN7': CDS_PINID='A_PETN7';
NET_NAME
'P5E_CPU1_P2_RX_DN<9>'
 '@T6G_MB_LIB.T6G(SCH_1):P5E_CPU1_P2_RX_DN'<9>:
 C_SIGNAL='@t6g_mb_lib.t6g(sch_1):p5e_cpu1_p2_rx_dn(9)';
NODE_NAME     U26 CL27
 '@T6G_MB_LIB.T6G(SCH_1):PAGE52_I148@PURE_QUANTA.GENOA_SP5(CHIPS)':
 'P2_RXN9': CDS_PINID='P2_RXN9';
NODE_NAME     U6016 BT29
 '@T6G_MB_LIB.T6G(SCH_1):PAGE448_I1@PURE_QUANTA.PT5161LRS(CHIPS)':
 'A_PETN6': CDS_PINID='A_PETN6';
NET_NAME
'P5E_CPU1_P2_RX_DP<0>'
 '@T6G_MB_LIB.T6G(SCH_1):P5E_CPU1_P2_RX_DP'<0>:
 C_SIGNAL='@t6g_mb_lib.t6g(sch_1):p5e_cpu1_p2_rx_dp(0)';
NODE_NAME     U26 CM35
 '@T6G_MB_LIB.T6G(SCH_1):PAGE52_I148@PURE_QUANTA.GENOA_SP5(CHIPS)':
 'P2_RXP0': CDS_PINID='P2_RXP0';
NODE_NAME     U6016 EU26
 '@T6G_MB_LIB.T6G(SCH_1):PAGE448_I38@PURE_QUANTA.PT5161LRS(CHIPS)':
 'A_PETP15': CDS_PINID='A_PETP15';
NET_NAME
'P5E_CPU1_P2_RX_DP<10>'
 '@T6G_MB_LIB.T6G(SCH_1):P5E_CPU1_P2_RX_DP'<10>:
 C_SIGNAL='@t6g_mb_lib.t6g(sch_1):p5e_cpu1_p2_rx_dp(10)';
NODE_NAME     U26 CU26
 '@T6G_MB_LIB.T6G(SCH_1):PAGE52_I148@PURE_QUANTA.GENOA_SP5(CHIPS)':
 'P2_RXP10': CDS_PINID='P2_RXP10';
NODE_NAME     U6016 BG26
 '@T6G_MB_LIB.T6G(SCH_1):PAGE448_I1@PURE_QUANTA.PT5161LRS(CHIPS)':
 'A_PETP5': CDS_PINID='A_PETP5';
NET_NAME
'P5E_CPU1_P2_RX_DP<11>'
 '@T6G_MB_LIB.T6G(SCH_1):P5E_CPU1_P2_RX_DP'<11>:
 C_SIGNAL='@t6g_mb_lib.t6g(sch_1):p5e_cpu1_p2_rx_dp(11)';
NODE_NAME     U26 CR26
 '@T6G_MB_LIB.T6G(SCH_1):PAGE52_I148@PURE_QUANTA.GENOA_SP5(CHIPS)':
 'P2_RXP11': CDS_PINID='P2_RXP11';
NODE_NAME     U6016 AY26
 '@T6G_MB_LIB.T6G(SCH_1):PAGE448_I1@PURE_QUANTA.PT5161LRS(CHIPS)':
 'A_PETP4': CDS_PINID='A_PETP4';
NET_NAME
'P5E_CPU1_P2_RX_DP<12>'
 '@T6G_MB_LIB.T6G(SCH_1):P5E_CPU1_P2_RX_DP'<12>:
 C_SIGNAL='@t6g_mb_lib.t6g(sch_1):p5e_cpu1_p2_rx_dp(12)';
NODE_NAME     U26 CN26
 '@T6G_MB_LIB.T6G(SCH_1):PAGE52_I148@PURE_QUANTA.GENOA_SP5(CHIPS)':
 'P2_RXP12': CDS_PINID='P2_RXP12';
NODE_NAME     U6016 AN26
 '@T6G_MB_LIB.T6G(SCH_1):PAGE448_I1@PURE_QUANTA.PT5161LRS(CHIPS)':
 'A_PETP3': CDS_PINID='A_PETP3';
NET_NAME
'P5E_CPU1_P2_RX_DP<13>'
 '@T6G_MB_LIB.T6G(SCH_1):P5E_CPU1_P2_RX_DP'<13>:
 C_SIGNAL='@t6g_mb_lib.t6g(sch_1):p5e_cpu1_p2_rx_dp(13)';
NODE_NAME     U26 CL23
 '@T6G_MB_LIB.T6G(SCH_1):PAGE52_I148@PURE_QUANTA.GENOA_SP5(CHIPS)':
 'P2_RXP13': CDS_PINID='P2_RXP13';
NODE_NAME     U6016 AF26
 '@T6G_MB_LIB.T6G(SCH_1):PAGE448_I1@PURE_QUANTA.PT5161LRS(CHIPS)':
 'A_PETP2': CDS_PINID='A_PETP2';
NET_NAME
'P5E_CPU1_P2_RX_DP<14>'
 '@T6G_MB_LIB.T6G(SCH_1):P5E_CPU1_P2_RX_DP'<14>:
 C_SIGNAL='@t6g_mb_lib.t6g(sch_1):p5e_cpu1_p2_rx_dp(14)';
NODE_NAME     U26 CR23
 '@T6G_MB_LIB.T6G(SCH_1):PAGE52_I148@PURE_QUANTA.GENOA_SP5(CHIPS)':
 'P2_RXP14': CDS_PINID='P2_RXP14';
NODE_NAME     U6016 W26
 '@T6G_MB_LIB.T6G(SCH_1):PAGE448_I1@PURE_QUANTA.PT5161LRS(CHIPS)':
 'A_PETP1': CDS_PINID='A_PETP1';
NET_NAME
'P5E_CPU1_P2_RX_DP<15>'
 '@T6G_MB_LIB.T6G(SCH_1):P5E_CPU1_P2_RX_DP'<15>:
 C_SIGNAL='@t6g_mb_lib.t6g(sch_1):p5e_cpu1_p2_rx_dp(15)';
NODE_NAME     U26 CN23
 '@T6G_MB_LIB.T6G(SCH_1):PAGE52_I148@PURE_QUANTA.GENOA_SP5(CHIPS)':
 'P2_RXP15': CDS_PINID='P2_RXP15';
NODE_NAME     U6016 M26
 '@T6G_MB_LIB.T6G(SCH_1):PAGE448_I1@PURE_QUANTA.PT5161LRS(CHIPS)':
 'A_PETP0': CDS_PINID='A_PETP0';
NET_NAME
'P5E_CPU1_P2_RX_DP<1>'
 '@T6G_MB_LIB.T6G(SCH_1):P5E_CPU1_P2_RX_DP'<1>:
 C_SIGNAL='@t6g_mb_lib.t6g(sch_1):p5e_cpu1_p2_rx_dp(1)';
NODE_NAME     U26 CP35
 '@T6G_MB_LIB.T6G(SCH_1):PAGE52_I148@PURE_QUANTA.GENOA_SP5(CHIPS)':
 'P2_RXP1': CDS_PINID='P2_RXP1';
NODE_NAME     U6016 EK26
 '@T6G_MB_LIB.T6G(SCH_1):PAGE448_I38@PURE_QUANTA.PT5161LRS(CHIPS)':
 'A_PETP14': CDS_PINID='A_PETP14';
NET_NAME
'P5E_CPU1_P2_RX_DP<2>'
 '@T6G_MB_LIB.T6G(SCH_1):P5E_CPU1_P2_RX_DP'<2>:
 C_SIGNAL='@t6g_mb_lib.t6g(sch_1):p5e_cpu1_p2_rx_dp(2)';
NODE_NAME     U26 CT35
 '@T6G_MB_LIB.T6G(SCH_1):PAGE52_I148@PURE_QUANTA.GENOA_SP5(CHIPS)':
 'P2_RXP2': CDS_PINID='P2_RXP2';
NODE_NAME     U6016 EC26
 '@T6G_MB_LIB.T6G(SCH_1):PAGE448_I38@PURE_QUANTA.PT5161LRS(CHIPS)':
 'A_PETP13': CDS_PINID='A_PETP13';
NET_NAME
'P5E_CPU1_P2_RX_DP<3>'
 '@T6G_MB_LIB.T6G(SCH_1):P5E_CPU1_P2_RX_DP'<3>:
 C_SIGNAL='@t6g_mb_lib.t6g(sch_1):p5e_cpu1_p2_rx_dp(3)';
NODE_NAME     U26 CN32
 '@T6G_MB_LIB.T6G(SCH_1):PAGE52_I148@PURE_QUANTA.GENOA_SP5(CHIPS)':
 'P2_RXP3': CDS_PINID='P2_RXP3';
NODE_NAME     U6016 DT26
 '@T6G_MB_LIB.T6G(SCH_1):PAGE448_I38@PURE_QUANTA.PT5161LRS(CHIPS)':
 'A_PETP12': CDS_PINID='A_PETP12';
NET_NAME
'P5E_CPU1_P2_RX_DP<4>'
 '@T6G_MB_LIB.T6G(SCH_1):P5E_CPU1_P2_RX_DP'<4>:
 C_SIGNAL='@t6g_mb_lib.t6g(sch_1):p5e_cpu1_p2_rx_dp(4)';
NODE_NAME     U26 CU32
 '@T6G_MB_LIB.T6G(SCH_1):PAGE52_I148@PURE_QUANTA.GENOA_SP5(CHIPS)':
 'P2_RXP4': CDS_PINID='P2_RXP4';
NODE_NAME     U6016 DJ26
 '@T6G_MB_LIB.T6G(SCH_1):PAGE448_I38@PURE_QUANTA.PT5161LRS(CHIPS)':
 'A_PETP11': CDS_PINID='A_PETP11';
NET_NAME
'P5E_CPU1_P2_RX_DP<5>'
 '@T6G_MB_LIB.T6G(SCH_1):P5E_CPU1_P2_RX_DP'<5>:
 C_SIGNAL='@t6g_mb_lib.t6g(sch_1):p5e_cpu1_p2_rx_dp(5)';
NODE_NAME     U26 CR32
 '@T6G_MB_LIB.T6G(SCH_1):PAGE52_I148@PURE_QUANTA.GENOA_SP5(CHIPS)':
 'P2_RXP5': CDS_PINID='P2_RXP5';
NODE_NAME     U6016 DB26
 '@T6G_MB_LIB.T6G(SCH_1):PAGE448_I38@PURE_QUANTA.PT5161LRS(CHIPS)':
 'A_PETP10': CDS_PINID='A_PETP10';
NET_NAME
'P5E_CPU1_P2_RX_DP<6>'
 '@T6G_MB_LIB.T6G(SCH_1):P5E_CPU1_P2_RX_DP'<6>:
 C_SIGNAL='@t6g_mb_lib.t6g(sch_1):p5e_cpu1_p2_rx_dp(6)';
NODE_NAME     U26 CN29
 '@T6G_MB_LIB.T6G(SCH_1):PAGE52_I148@PURE_QUANTA.GENOA_SP5(CHIPS)':
 'P2_RXP6': CDS_PINID='P2_RXP6';
NODE_NAME     U6016 CR26
 '@T6G_MB_LIB.T6G(SCH_1):PAGE448_I38@PURE_QUANTA.PT5161LRS(CHIPS)':
 'A_PETP9': CDS_PINID='A_PETP9';
NET_NAME
'P5E_CPU1_P2_RX_DP<7>'
 '@T6G_MB_LIB.T6G(SCH_1):P5E_CPU1_P2_RX_DP'<7>:
 C_SIGNAL='@t6g_mb_lib.t6g(sch_1):p5e_cpu1_p2_rx_dp(7)';
NODE_NAME     U26 CU29
 '@T6G_MB_LIB.T6G(SCH_1):PAGE52_I148@PURE_QUANTA.GENOA_SP5(CHIPS)':
 'P2_RXP7': CDS_PINID='P2_RXP7';
NODE_NAME     U6016 CH26
 '@T6G_MB_LIB.T6G(SCH_1):PAGE448_I38@PURE_QUANTA.PT5161LRS(CHIPS)':
 'A_PETP8': CDS_PINID='A_PETP8';
NET_NAME
'P5E_CPU1_P2_RX_DP<8>'
 '@T6G_MB_LIB.T6G(SCH_1):P5E_CPU1_P2_RX_DP'<8>:
 C_SIGNAL='@t6g_mb_lib.t6g(sch_1):p5e_cpu1_p2_rx_dp(8)';
NODE_NAME     U26 CR29
 '@T6G_MB_LIB.T6G(SCH_1):PAGE52_I148@PURE_QUANTA.GENOA_SP5(CHIPS)':
 'P2_RXP8': CDS_PINID='P2_RXP8';
NODE_NAME     U6016 CA26
 '@T6G_MB_LIB.T6G(SCH_1):PAGE448_I1@PURE_QUANTA.PT5161LRS(CHIPS)':
 'A_PETP7': CDS_PINID='A_PETP7';
NET_NAME
'P5E_CPU1_P2_RX_DP<9>'
 '@T6G_MB_LIB.T6G(SCH_1):P5E_CPU1_P2_RX_DP'<9>:
 C_SIGNAL='@t6g_mb_lib.t6g(sch_1):p5e_cpu1_p2_rx_dp(9)';
NODE_NAME     U26 CL26
 '@T6G_MB_LIB.T6G(SCH_1):PAGE52_I148@PURE_QUANTA.GENOA_SP5(CHIPS)':
 'P2_RXP9': CDS_PINID='P2_RXP9';
NODE_NAME     U6016 BP26
 '@T6G_MB_LIB.T6G(SCH_1):PAGE448_I1@PURE_QUANTA.PT5161LRS(CHIPS)':
 'A_PETP6': CDS_PINID='A_PETP6';
NET_NAME
'P5E_CPU1_P2_TX_BUF_C_DN<0>'
 '@T6G_MB_LIB.T6G(SCH_1):P5E_CPU1_P2_TX_BUF_C_DN'<0>:
 C_SIGNAL='@t6g_mb_lib.t6g(sch_1):p5e_cpu1_p2_tx_buf_c_dn(0)';
NODE_NAME     C6694 1
 '@T6G_MB_LIB.T6G(SCH_1):PAGE450_I35@PURE_QUANTA.Q_CAP_DIFFBUS(CHIPS)':
 '1': CDS_PINID='\1\';
NODE_NAME     J110 I1
 '@T6G_MB_LIB.T6G(SCH_1):PAGE318_I76@PURE_QUANTA.CONN112_10137002101LF(CHIPS)':
 'I1': CDS_PINID='I1';
NET_NAME
'P5E_CPU1_P2_TX_BUF_C_DN<10>'
 '@T6G_MB_LIB.T6G(SCH_1):P5E_CPU1_P2_TX_BUF_C_DN'<10>:
 C_SIGNAL='@t6g_mb_lib.t6g(sch_1):p5e_cpu1_p2_tx_buf_c_dn(10)';
NODE_NAME     C6714 1
 '@T6G_MB_LIB.T6G(SCH_1):PAGE450_I96@PURE_QUANTA.Q_CAP_DIFFBUS(CHIPS)':
 '1': CDS_PINID='\1\';
NODE_NAME     J109 I3
 '@T6G_MB_LIB.T6G(SCH_1):PAGE319_I76@PURE_QUANTA.CONN112_10137002101LF(CHIPS)':
 'I3': CDS_PINID='I3';
NET_NAME
'P5E_CPU1_P2_TX_BUF_C_DN<11>'
 '@T6G_MB_LIB.T6G(SCH_1):P5E_CPU1_P2_TX_BUF_C_DN'<11>:
 C_SIGNAL='@t6g_mb_lib.t6g(sch_1):p5e_cpu1_p2_tx_buf_c_dn(11)';
NODE_NAME     C6716 1
 '@T6G_MB_LIB.T6G(SCH_1):PAGE450_I94@PURE_QUANTA.Q_CAP_DIFFBUS(CHIPS)':
 '1': CDS_PINID='\1\';
NODE_NAME     J109 H4
 '@T6G_MB_LIB.T6G(SCH_1):PAGE319_I76@PURE_QUANTA.CONN112_10137002101LF(CHIPS)':
 'H4': CDS_PINID='H4';
NET_NAME
'P5E_CPU1_P2_TX_BUF_C_DN<12>'
 '@T6G_MB_LIB.T6G(SCH_1):P5E_CPU1_P2_TX_BUF_C_DN'<12>:
 C_SIGNAL='@t6g_mb_lib.t6g(sch_1):p5e_cpu1_p2_tx_buf_c_dn(12)';
NODE_NAME     C6718 1
 '@T6G_MB_LIB.T6G(SCH_1):PAGE450_I92@PURE_QUANTA.Q_CAP_DIFFBUS(CHIPS)':
 '1': CDS_PINID='\1\';
NODE_NAME     J109 I5
 '@T6G_MB_LIB.T6G(SCH_1):PAGE319_I16@PURE_QUANTA.CONN112_10137002101LF(CHIPS)':
 'I5': CDS_PINID='I5';
NET_NAME
'P5E_CPU1_P2_TX_BUF_C_DN<13>'
 '@T6G_MB_LIB.T6G(SCH_1):P5E_CPU1_P2_TX_BUF_C_DN'<13>:
 C_SIGNAL='@t6g_mb_lib.t6g(sch_1):p5e_cpu1_p2_tx_buf_c_dn(13)';
NODE_NAME     C6720 1
 '@T6G_MB_LIB.T6G(SCH_1):PAGE450_I90@PURE_QUANTA.Q_CAP_DIFFBUS(CHIPS)':
 '1': CDS_PINID='\1\';
NODE_NAME     J109 H6
 '@T6G_MB_LIB.T6G(SCH_1):PAGE319_I16@PURE_QUANTA.CONN112_10137002101LF(CHIPS)':
 'H6': CDS_PINID='H6';
NET_NAME
'P5E_CPU1_P2_TX_BUF_C_DN<14>'
 '@T6G_MB_LIB.T6G(SCH_1):P5E_CPU1_P2_TX_BUF_C_DN'<14>:
 C_SIGNAL='@t6g_mb_lib.t6g(sch_1):p5e_cpu1_p2_tx_buf_c_dn(14)';
NODE_NAME     C6722 1
 '@T6G_MB_LIB.T6G(SCH_1):PAGE450_I83@PURE_QUANTA.Q_CAP_DIFFBUS(CHIPS)':
 '1': CDS_PINID='\1\';
NODE_NAME     J109 I7
 '@T6G_MB_LIB.T6G(SCH_1):PAGE319_I16@PURE_QUANTA.CONN112_10137002101LF(CHIPS)':
 'I7': CDS_PINID='I7';
NET_NAME
'P5E_CPU1_P2_TX_BUF_C_DN<15>'
 '@T6G_MB_LIB.T6G(SCH_1):P5E_CPU1_P2_TX_BUF_C_DN'<15>:
 C_SIGNAL='@t6g_mb_lib.t6g(sch_1):p5e_cpu1_p2_tx_buf_c_dn(15)';
NODE_NAME     C6724 1
 '@T6G_MB_LIB.T6G(SCH_1):PAGE450_I81@PURE_QUANTA.Q_CAP_DIFFBUS(CHIPS)':
 '1': CDS_PINID='\1\';
NODE_NAME     J109 H8
 '@T6G_MB_LIB.T6G(SCH_1):PAGE319_I16@PURE_QUANTA.CONN112_10137002101LF(CHIPS)':
 'H8': CDS_PINID='H8';
NET_NAME
'P5E_CPU1_P2_TX_BUF_C_DN<1>'
 '@T6G_MB_LIB.T6G(SCH_1):P5E_CPU1_P2_TX_BUF_C_DN'<1>:
 C_SIGNAL='@t6g_mb_lib.t6g(sch_1):p5e_cpu1_p2_tx_buf_c_dn(1)';
NODE_NAME     C6696 1
 '@T6G_MB_LIB.T6G(SCH_1):PAGE450_I28@PURE_QUANTA.Q_CAP_DIFFBUS(CHIPS)':
 '1': CDS_PINID='\1\';
NODE_NAME     J110 H2
 '@T6G_MB_LIB.T6G(SCH_1):PAGE318_I76@PURE_QUANTA.CONN112_10137002101LF(CHIPS)':
 'H2': CDS_PINID='H2';
NET_NAME
'P5E_CPU1_P2_TX_BUF_C_DN<2>'
 '@T6G_MB_LIB.T6G(SCH_1):P5E_CPU1_P2_TX_BUF_C_DN'<2>:
 C_SIGNAL='@t6g_mb_lib.t6g(sch_1):p5e_cpu1_p2_tx_buf_c_dn(2)';
NODE_NAME     C6698 1
 '@T6G_MB_LIB.T6G(SCH_1):PAGE450_I27@PURE_QUANTA.Q_CAP_DIFFBUS(CHIPS)':
 '1': CDS_PINID='\1\';
NODE_NAME     J110 I3
 '@T6G_MB_LIB.T6G(SCH_1):PAGE318_I76@PURE_QUANTA.CONN112_10137002101LF(CHIPS)':
 'I3': CDS_PINID='I3';
NET_NAME
'P5E_CPU1_P2_TX_BUF_C_DN<3>'
 '@T6G_MB_LIB.T6G(SCH_1):P5E_CPU1_P2_TX_BUF_C_DN'<3>:
 C_SIGNAL='@t6g_mb_lib.t6g(sch_1):p5e_cpu1_p2_tx_buf_c_dn(3)';
NODE_NAME     C6700 1
 '@T6G_MB_LIB.T6G(SCH_1):PAGE450_I26@PURE_QUANTA.Q_CAP_DIFFBUS(CHIPS)':
 '1': CDS_PINID='\1\';
NODE_NAME     J110 H4
 '@T6G_MB_LIB.T6G(SCH_1):PAGE318_I76@PURE_QUANTA.CONN112_10137002101LF(CHIPS)':
 'H4': CDS_PINID='H4';
NET_NAME
'P5E_CPU1_P2_TX_BUF_C_DN<4>'
 '@T6G_MB_LIB.T6G(SCH_1):P5E_CPU1_P2_TX_BUF_C_DN'<4>:
 C_SIGNAL='@t6g_mb_lib.t6g(sch_1):p5e_cpu1_p2_tx_buf_c_dn(4)';
NODE_NAME     C6702 1
 '@T6G_MB_LIB.T6G(SCH_1):PAGE450_I23@PURE_QUANTA.Q_CAP_DIFFBUS(CHIPS)':
 '1': CDS_PINID='\1\';
NODE_NAME     J110 I5
 '@T6G_MB_LIB.T6G(SCH_1):PAGE318_I16@PURE_QUANTA.CONN112_10137002101LF(CHIPS)':
 'I5': CDS_PINID='I5';
NET_NAME
'P5E_CPU1_P2_TX_BUF_C_DN<5>'
 '@T6G_MB_LIB.T6G(SCH_1):P5E_CPU1_P2_TX_BUF_C_DN'<5>:
 C_SIGNAL='@t6g_mb_lib.t6g(sch_1):p5e_cpu1_p2_tx_buf_c_dn(5)';
NODE_NAME     C6704 1
 '@T6G_MB_LIB.T6G(SCH_1):PAGE450_I21@PURE_QUANTA.Q_CAP_DIFFBUS(CHIPS)':
 '1': CDS_PINID='\1\';
NODE_NAME     J110 H6
 '@T6G_MB_LIB.T6G(SCH_1):PAGE318_I16@PURE_QUANTA.CONN112_10137002101LF(CHIPS)':
 'H6': CDS_PINID='H6';
NET_NAME
'P5E_CPU1_P2_TX_BUF_C_DN<6>'
 '@T6G_MB_LIB.T6G(SCH_1):P5E_CPU1_P2_TX_BUF_C_DN'<6>:
 C_SIGNAL='@t6g_mb_lib.t6g(sch_1):p5e_cpu1_p2_tx_buf_c_dn(6)';
NODE_NAME     C6706 1
 '@T6G_MB_LIB.T6G(SCH_1):PAGE450_I19@PURE_QUANTA.Q_CAP_DIFFBUS(CHIPS)':
 '1': CDS_PINID='\1\';
NODE_NAME     J110 I7
 '@T6G_MB_LIB.T6G(SCH_1):PAGE318_I16@PURE_QUANTA.CONN112_10137002101LF(CHIPS)':
 'I7': CDS_PINID='I7';
NET_NAME
'P5E_CPU1_P2_TX_BUF_C_DN<7>'
 '@T6G_MB_LIB.T6G(SCH_1):P5E_CPU1_P2_TX_BUF_C_DN'<7>:
 C_SIGNAL='@t6g_mb_lib.t6g(sch_1):p5e_cpu1_p2_tx_buf_c_dn(7)';
NODE_NAME     C6708 1
 '@T6G_MB_LIB.T6G(SCH_1):PAGE450_I17@PURE_QUANTA.Q_CAP_DIFFBUS(CHIPS)':
 '1': CDS_PINID='\1\';
NODE_NAME     J110 H8
 '@T6G_MB_LIB.T6G(SCH_1):PAGE318_I16@PURE_QUANTA.CONN112_10137002101LF(CHIPS)':
 'H8': CDS_PINID='H8';
NET_NAME
'P5E_CPU1_P2_TX_BUF_C_DN<8>'
 '@T6G_MB_LIB.T6G(SCH_1):P5E_CPU1_P2_TX_BUF_C_DN'<8>:
 C_SIGNAL='@t6g_mb_lib.t6g(sch_1):p5e_cpu1_p2_tx_buf_c_dn(8)';
NODE_NAME     C6710 1
 '@T6G_MB_LIB.T6G(SCH_1):PAGE450_I103@PURE_QUANTA.Q_CAP_DIFFBUS(CHIPS)':
 '1': CDS_PINID='\1\';
NODE_NAME     J109 I1
 '@T6G_MB_LIB.T6G(SCH_1):PAGE319_I76@PURE_QUANTA.CONN112_10137002101LF(CHIPS)':
 'I1': CDS_PINID='I1';
NET_NAME
'P5E_CPU1_P2_TX_BUF_C_DN<9>'
 '@T6G_MB_LIB.T6G(SCH_1):P5E_CPU1_P2_TX_BUF_C_DN'<9>:
 C_SIGNAL='@t6g_mb_lib.t6g(sch_1):p5e_cpu1_p2_tx_buf_c_dn(9)';
NODE_NAME     C6712 1
 '@T6G_MB_LIB.T6G(SCH_1):PAGE450_I98@PURE_QUANTA.Q_CAP_DIFFBUS(CHIPS)':
 '1': CDS_PINID='\1\';
NODE_NAME     J109 H2
 '@T6G_MB_LIB.T6G(SCH_1):PAGE319_I76@PURE_QUANTA.CONN112_10137002101LF(CHIPS)':
 'H2': CDS_PINID='H2';
NET_NAME
'P5E_CPU1_P2_TX_BUF_C_DP<0>'
 '@T6G_MB_LIB.T6G(SCH_1):P5E_CPU1_P2_TX_BUF_C_DP'<0>:
 C_SIGNAL='@t6g_mb_lib.t6g(sch_1):p5e_cpu1_p2_tx_buf_c_dp(0)';
NODE_NAME     C6693 1
 '@T6G_MB_LIB.T6G(SCH_1):PAGE450_I34@PURE_QUANTA.Q_CAP_DIFFBUS(CHIPS)':
 '1': CDS_PINID='\1\';
NODE_NAME     J110 J1
 '@T6G_MB_LIB.T6G(SCH_1):PAGE318_I76@PURE_QUANTA.CONN112_10137002101LF(CHIPS)':
 'J1': CDS_PINID='J1';
NET_NAME
'P5E_CPU1_P2_TX_BUF_C_DP<10>'
 '@T6G_MB_LIB.T6G(SCH_1):P5E_CPU1_P2_TX_BUF_C_DP'<10>:
 C_SIGNAL='@t6g_mb_lib.t6g(sch_1):p5e_cpu1_p2_tx_buf_c_dp(10)';
NODE_NAME     C6713 1
 '@T6G_MB_LIB.T6G(SCH_1):PAGE450_I97@PURE_QUANTA.Q_CAP_DIFFBUS(CHIPS)':
 '1': CDS_PINID='\1\';
NODE_NAME     J109 J3
 '@T6G_MB_LIB.T6G(SCH_1):PAGE319_I76@PURE_QUANTA.CONN112_10137002101LF(CHIPS)':
 'J3': CDS_PINID='J3';
NET_NAME
'P5E_CPU1_P2_TX_BUF_C_DP<11>'
 '@T6G_MB_LIB.T6G(SCH_1):P5E_CPU1_P2_TX_BUF_C_DP'<11>:
 C_SIGNAL='@t6g_mb_lib.t6g(sch_1):p5e_cpu1_p2_tx_buf_c_dp(11)';
NODE_NAME     C6715 1
 '@T6G_MB_LIB.T6G(SCH_1):PAGE450_I95@PURE_QUANTA.Q_CAP_DIFFBUS(CHIPS)':
 '1': CDS_PINID='\1\';
NODE_NAME     J109 I4
 '@T6G_MB_LIB.T6G(SCH_1):PAGE319_I76@PURE_QUANTA.CONN112_10137002101LF(CHIPS)':
 'I4': CDS_PINID='I4';
NET_NAME
'P5E_CPU1_P2_TX_BUF_C_DP<12>'
 '@T6G_MB_LIB.T6G(SCH_1):P5E_CPU1_P2_TX_BUF_C_DP'<12>:
 C_SIGNAL='@t6g_mb_lib.t6g(sch_1):p5e_cpu1_p2_tx_buf_c_dp(12)';
NODE_NAME     C6717 1
 '@T6G_MB_LIB.T6G(SCH_1):PAGE450_I93@PURE_QUANTA.Q_CAP_DIFFBUS(CHIPS)':
 '1': CDS_PINID='\1\';
NODE_NAME     J109 J5
 '@T6G_MB_LIB.T6G(SCH_1):PAGE319_I16@PURE_QUANTA.CONN112_10137002101LF(CHIPS)':
 'J5': CDS_PINID='J5';
NET_NAME
'P5E_CPU1_P2_TX_BUF_C_DP<13>'
 '@T6G_MB_LIB.T6G(SCH_1):P5E_CPU1_P2_TX_BUF_C_DP'<13>:
 C_SIGNAL='@t6g_mb_lib.t6g(sch_1):p5e_cpu1_p2_tx_buf_c_dp(13)';
NODE_NAME     C6719 1
 '@T6G_MB_LIB.T6G(SCH_1):PAGE450_I91@PURE_QUANTA.Q_CAP_DIFFBUS(CHIPS)':
 '1': CDS_PINID='\1\';
NODE_NAME     J109 I6
 '@T6G_MB_LIB.T6G(SCH_1):PAGE319_I16@PURE_QUANTA.CONN112_10137002101LF(CHIPS)':
 'I6': CDS_PINID='I6';
NET_NAME
'P5E_CPU1_P2_TX_BUF_C_DP<14>'
 '@T6G_MB_LIB.T6G(SCH_1):P5E_CPU1_P2_TX_BUF_C_DP'<14>:
 C_SIGNAL='@t6g_mb_lib.t6g(sch_1):p5e_cpu1_p2_tx_buf_c_dp(14)';
NODE_NAME     C6721 1
 '@T6G_MB_LIB.T6G(SCH_1):PAGE450_I84@PURE_QUANTA.Q_CAP_DIFFBUS(CHIPS)':
 '1': CDS_PINID='\1\';
NODE_NAME     J109 J7
 '@T6G_MB_LIB.T6G(SCH_1):PAGE319_I16@PURE_QUANTA.CONN112_10137002101LF(CHIPS)':
 'J7': CDS_PINID='J7';
NET_NAME
'P5E_CPU1_P2_TX_BUF_C_DP<15>'
 '@T6G_MB_LIB.T6G(SCH_1):P5E_CPU1_P2_TX_BUF_C_DP'<15>:
 C_SIGNAL='@t6g_mb_lib.t6g(sch_1):p5e_cpu1_p2_tx_buf_c_dp(15)';
NODE_NAME     C6723 1
 '@T6G_MB_LIB.T6G(SCH_1):PAGE450_I82@PURE_QUANTA.Q_CAP_DIFFBUS(CHIPS)':
 '1': CDS_PINID='\1\';
NODE_NAME     J109 I8
 '@T6G_MB_LIB.T6G(SCH_1):PAGE319_I16@PURE_QUANTA.CONN112_10137002101LF(CHIPS)':
 'I8': CDS_PINID='I8';
NET_NAME
'P5E_CPU1_P2_TX_BUF_C_DP<1>'
 '@T6G_MB_LIB.T6G(SCH_1):P5E_CPU1_P2_TX_BUF_C_DP'<1>:
 C_SIGNAL='@t6g_mb_lib.t6g(sch_1):p5e_cpu1_p2_tx_buf_c_dp(1)';
NODE_NAME     C6695 1
 '@T6G_MB_LIB.T6G(SCH_1):PAGE450_I29@PURE_QUANTA.Q_CAP_DIFFBUS(CHIPS)':
 '1': CDS_PINID='\1\';
NODE_NAME     J110 I2
 '@T6G_MB_LIB.T6G(SCH_1):PAGE318_I76@PURE_QUANTA.CONN112_10137002101LF(CHIPS)':
 'I2': CDS_PINID='I2';
NET_NAME
'P5E_CPU1_P2_TX_BUF_C_DP<2>'
 '@T6G_MB_LIB.T6G(SCH_1):P5E_CPU1_P2_TX_BUF_C_DP'<2>:
 C_SIGNAL='@t6g_mb_lib.t6g(sch_1):p5e_cpu1_p2_tx_buf_c_dp(2)';
NODE_NAME     C6697 1
 '@T6G_MB_LIB.T6G(SCH_1):PAGE450_I30@PURE_QUANTA.Q_CAP_DIFFBUS(CHIPS)':
 '1': CDS_PINID='\1\';
NODE_NAME     J110 J3
 '@T6G_MB_LIB.T6G(SCH_1):PAGE318_I76@PURE_QUANTA.CONN112_10137002101LF(CHIPS)':
 'J3': CDS_PINID='J3';
NET_NAME
'P5E_CPU1_P2_TX_BUF_C_DP<3>'
 '@T6G_MB_LIB.T6G(SCH_1):P5E_CPU1_P2_TX_BUF_C_DP'<3>:
 C_SIGNAL='@t6g_mb_lib.t6g(sch_1):p5e_cpu1_p2_tx_buf_c_dp(3)';
NODE_NAME     C6699 1
 '@T6G_MB_LIB.T6G(SCH_1):PAGE450_I25@PURE_QUANTA.Q_CAP_DIFFBUS(CHIPS)':
 '1': CDS_PINID='\1\';
NODE_NAME     J110 I4
 '@T6G_MB_LIB.T6G(SCH_1):PAGE318_I76@PURE_QUANTA.CONN112_10137002101LF(CHIPS)':
 'I4': CDS_PINID='I4';
NET_NAME
'P5E_CPU1_P2_TX_BUF_C_DP<4>'
 '@T6G_MB_LIB.T6G(SCH_1):P5E_CPU1_P2_TX_BUF_C_DP'<4>:
 C_SIGNAL='@t6g_mb_lib.t6g(sch_1):p5e_cpu1_p2_tx_buf_c_dp(4)';
NODE_NAME     C6701 1
 '@T6G_MB_LIB.T6G(SCH_1):PAGE450_I24@PURE_QUANTA.Q_CAP_DIFFBUS(CHIPS)':
 '1': CDS_PINID='\1\';
NODE_NAME     J110 J5
 '@T6G_MB_LIB.T6G(SCH_1):PAGE318_I16@PURE_QUANTA.CONN112_10137002101LF(CHIPS)':
 'J5': CDS_PINID='J5';
NET_NAME
'P5E_CPU1_P2_TX_BUF_C_DP<5>'
 '@T6G_MB_LIB.T6G(SCH_1):P5E_CPU1_P2_TX_BUF_C_DP'<5>:
 C_SIGNAL='@t6g_mb_lib.t6g(sch_1):p5e_cpu1_p2_tx_buf_c_dp(5)';
NODE_NAME     C6703 1
 '@T6G_MB_LIB.T6G(SCH_1):PAGE450_I22@PURE_QUANTA.Q_CAP_DIFFBUS(CHIPS)':
 '1': CDS_PINID='\1\';
NODE_NAME     J110 I6
 '@T6G_MB_LIB.T6G(SCH_1):PAGE318_I16@PURE_QUANTA.CONN112_10137002101LF(CHIPS)':
 'I6': CDS_PINID='I6';
NET_NAME
'P5E_CPU1_P2_TX_BUF_C_DP<6>'
 '@T6G_MB_LIB.T6G(SCH_1):P5E_CPU1_P2_TX_BUF_C_DP'<6>:
 C_SIGNAL='@t6g_mb_lib.t6g(sch_1):p5e_cpu1_p2_tx_buf_c_dp(6)';
NODE_NAME     C6705 1
 '@T6G_MB_LIB.T6G(SCH_1):PAGE450_I20@PURE_QUANTA.Q_CAP_DIFFBUS(CHIPS)':
 '1': CDS_PINID='\1\';
NODE_NAME     J110 J7
 '@T6G_MB_LIB.T6G(SCH_1):PAGE318_I16@PURE_QUANTA.CONN112_10137002101LF(CHIPS)':
 'J7': CDS_PINID='J7';
NET_NAME
'P5E_CPU1_P2_TX_BUF_C_DP<7>'
 '@T6G_MB_LIB.T6G(SCH_1):P5E_CPU1_P2_TX_BUF_C_DP'<7>:
 C_SIGNAL='@t6g_mb_lib.t6g(sch_1):p5e_cpu1_p2_tx_buf_c_dp(7)';
NODE_NAME     C6707 1
 '@T6G_MB_LIB.T6G(SCH_1):PAGE450_I18@PURE_QUANTA.Q_CAP_DIFFBUS(CHIPS)':
 '1': CDS_PINID='\1\';
NODE_NAME     J110 I8
 '@T6G_MB_LIB.T6G(SCH_1):PAGE318_I16@PURE_QUANTA.CONN112_10137002101LF(CHIPS)':
 'I8': CDS_PINID='I8';
NET_NAME
'P5E_CPU1_P2_TX_BUF_C_DP<8>'
 '@T6G_MB_LIB.T6G(SCH_1):P5E_CPU1_P2_TX_BUF_C_DP'<8>:
 C_SIGNAL='@t6g_mb_lib.t6g(sch_1):p5e_cpu1_p2_tx_buf_c_dp(8)';
NODE_NAME     C6709 1
 '@T6G_MB_LIB.T6G(SCH_1):PAGE450_I102@PURE_QUANTA.Q_CAP_DIFFBUS(CHIPS)':
 '1': CDS_PINID='\1\';
NODE_NAME     J109 J1
 '@T6G_MB_LIB.T6G(SCH_1):PAGE319_I76@PURE_QUANTA.CONN112_10137002101LF(CHIPS)':
 'J1': CDS_PINID='J1';
NET_NAME
'P5E_CPU1_P2_TX_BUF_C_DP<9>'
 '@T6G_MB_LIB.T6G(SCH_1):P5E_CPU1_P2_TX_BUF_C_DP'<9>:
 C_SIGNAL='@t6g_mb_lib.t6g(sch_1):p5e_cpu1_p2_tx_buf_c_dp(9)';
NODE_NAME     C6711 1
 '@T6G_MB_LIB.T6G(SCH_1):PAGE450_I99@PURE_QUANTA.Q_CAP_DIFFBUS(CHIPS)':
 '1': CDS_PINID='\1\';
NODE_NAME     J109 I2
 '@T6G_MB_LIB.T6G(SCH_1):PAGE319_I76@PURE_QUANTA.CONN112_10137002101LF(CHIPS)':
 'I2': CDS_PINID='I2';
NET_NAME
'P5E_CPU1_P2_TX_BUF_DN<0>'
 '@T6G_MB_LIB.T6G(SCH_1):P5E_CPU1_P2_TX_BUF_DN'<0>:
 C_SIGNAL='@t6g_mb_lib.t6g(sch_1):p5e_cpu1_p2_tx_buf_dn(0)';
NODE_NAME     C6694 2
 '@T6G_MB_LIB.T6G(SCH_1):PAGE450_I35@PURE_QUANTA.Q_CAP_DIFFBUS(CHIPS)':
 '2': CDS_PINID='\2\';
NODE_NAME     U6016 EW10
 '@T6G_MB_LIB.T6G(SCH_1):PAGE450_I142@PURE_QUANTA.PT5161LRS(CHIPS)':
 'B_PETN15': CDS_PINID='B_PETN15';
NET_NAME
'P5E_CPU1_P2_TX_BUF_DN<10>'
 '@T6G_MB_LIB.T6G(SCH_1):P5E_CPU1_P2_TX_BUF_DN'<10>:
 C_SIGNAL='@t6g_mb_lib.t6g(sch_1):p5e_cpu1_p2_tx_buf_dn(10)';
NODE_NAME     U6016 BJ10
 '@T6G_MB_LIB.T6G(SCH_1):PAGE450_I33@PURE_QUANTA.PT5161LRS(CHIPS)':
 'B_PETN5': CDS_PINID='B_PETN5';
NODE_NAME     C6714 2
 '@T6G_MB_LIB.T6G(SCH_1):PAGE450_I96@PURE_QUANTA.Q_CAP_DIFFBUS(CHIPS)':
 '2': CDS_PINID='\2\';
NET_NAME
'P5E_CPU1_P2_TX_BUF_DN<11>'
 '@T6G_MB_LIB.T6G(SCH_1):P5E_CPU1_P2_TX_BUF_DN'<11>:
 C_SIGNAL='@t6g_mb_lib.t6g(sch_1):p5e_cpu1_p2_tx_buf_dn(11)';
NODE_NAME     U6016 BB10
 '@T6G_MB_LIB.T6G(SCH_1):PAGE450_I33@PURE_QUANTA.PT5161LRS(CHIPS)':
 'B_PETN4': CDS_PINID='B_PETN4';
NODE_NAME     C6716 2
 '@T6G_MB_LIB.T6G(SCH_1):PAGE450_I94@PURE_QUANTA.Q_CAP_DIFFBUS(CHIPS)':
 '2': CDS_PINID='\2\';
NET_NAME
'P5E_CPU1_P2_TX_BUF_DN<12>'
 '@T6G_MB_LIB.T6G(SCH_1):P5E_CPU1_P2_TX_BUF_DN'<12>:
 C_SIGNAL='@t6g_mb_lib.t6g(sch_1):p5e_cpu1_p2_tx_buf_dn(12)';
NODE_NAME     U6016 AR10
 '@T6G_MB_LIB.T6G(SCH_1):PAGE450_I33@PURE_QUANTA.PT5161LRS(CHIPS)':
 'B_PETN3': CDS_PINID='B_PETN3';
NODE_NAME     C6718 2
 '@T6G_MB_LIB.T6G(SCH_1):PAGE450_I92@PURE_QUANTA.Q_CAP_DIFFBUS(CHIPS)':
 '2': CDS_PINID='\2\';
NET_NAME
'P5E_CPU1_P2_TX_BUF_DN<13>'
 '@T6G_MB_LIB.T6G(SCH_1):P5E_CPU1_P2_TX_BUF_DN'<13>:
 C_SIGNAL='@t6g_mb_lib.t6g(sch_1):p5e_cpu1_p2_tx_buf_dn(13)';
NODE_NAME     U6016 AH10
 '@T6G_MB_LIB.T6G(SCH_1):PAGE450_I33@PURE_QUANTA.PT5161LRS(CHIPS)':
 'B_PETN2': CDS_PINID='B_PETN2';
NODE_NAME     C6720 2
 '@T6G_MB_LIB.T6G(SCH_1):PAGE450_I90@PURE_QUANTA.Q_CAP_DIFFBUS(CHIPS)':
 '2': CDS_PINID='\2\';
NET_NAME
'P5E_CPU1_P2_TX_BUF_DN<14>'
 '@T6G_MB_LIB.T6G(SCH_1):P5E_CPU1_P2_TX_BUF_DN'<14>:
 C_SIGNAL='@t6g_mb_lib.t6g(sch_1):p5e_cpu1_p2_tx_buf_dn(14)';
NODE_NAME     U6016 AA10
 '@T6G_MB_LIB.T6G(SCH_1):PAGE450_I33@PURE_QUANTA.PT5161LRS(CHIPS)':
 'B_PETN1': CDS_PINID='B_PETN1';
NODE_NAME     C6722 2
 '@T6G_MB_LIB.T6G(SCH_1):PAGE450_I83@PURE_QUANTA.Q_CAP_DIFFBUS(CHIPS)':
 '2': CDS_PINID='\2\';
NET_NAME
'P5E_CPU1_P2_TX_BUF_DN<15>'
 '@T6G_MB_LIB.T6G(SCH_1):P5E_CPU1_P2_TX_BUF_DN'<15>:
 C_SIGNAL='@t6g_mb_lib.t6g(sch_1):p5e_cpu1_p2_tx_buf_dn(15)';
NODE_NAME     U6016 P10
 '@T6G_MB_LIB.T6G(SCH_1):PAGE450_I33@PURE_QUANTA.PT5161LRS(CHIPS)':
 'B_PETN0': CDS_PINID='B_PETN0';
NODE_NAME     C6724 2
 '@T6G_MB_LIB.T6G(SCH_1):PAGE450_I81@PURE_QUANTA.Q_CAP_DIFFBUS(CHIPS)':
 '2': CDS_PINID='\2\';
NET_NAME
'P5E_CPU1_P2_TX_BUF_DN<1>'
 '@T6G_MB_LIB.T6G(SCH_1):P5E_CPU1_P2_TX_BUF_DN'<1>:
 C_SIGNAL='@t6g_mb_lib.t6g(sch_1):p5e_cpu1_p2_tx_buf_dn(1)';
NODE_NAME     C6696 2
 '@T6G_MB_LIB.T6G(SCH_1):PAGE450_I28@PURE_QUANTA.Q_CAP_DIFFBUS(CHIPS)':
 '2': CDS_PINID='\2\';
NODE_NAME     U6016 EM10
 '@T6G_MB_LIB.T6G(SCH_1):PAGE450_I142@PURE_QUANTA.PT5161LRS(CHIPS)':
 'B_PETN14': CDS_PINID='B_PETN14';
NET_NAME
'P5E_CPU1_P2_TX_BUF_DN<2>'
 '@T6G_MB_LIB.T6G(SCH_1):P5E_CPU1_P2_TX_BUF_DN'<2>:
 C_SIGNAL='@t6g_mb_lib.t6g(sch_1):p5e_cpu1_p2_tx_buf_dn(2)';
NODE_NAME     C6698 2
 '@T6G_MB_LIB.T6G(SCH_1):PAGE450_I27@PURE_QUANTA.Q_CAP_DIFFBUS(CHIPS)':
 '2': CDS_PINID='\2\';
NODE_NAME     U6016 EE10
 '@T6G_MB_LIB.T6G(SCH_1):PAGE450_I142@PURE_QUANTA.PT5161LRS(CHIPS)':
 'B_PETN13': CDS_PINID='B_PETN13';
NET_NAME
'P5E_CPU1_P2_TX_BUF_DN<3>'
 '@T6G_MB_LIB.T6G(SCH_1):P5E_CPU1_P2_TX_BUF_DN'<3>:
 C_SIGNAL='@t6g_mb_lib.t6g(sch_1):p5e_cpu1_p2_tx_buf_dn(3)';
NODE_NAME     C6700 2
 '@T6G_MB_LIB.T6G(SCH_1):PAGE450_I26@PURE_QUANTA.Q_CAP_DIFFBUS(CHIPS)':
 '2': CDS_PINID='\2\';
NODE_NAME     U6016 DV10
 '@T6G_MB_LIB.T6G(SCH_1):PAGE450_I142@PURE_QUANTA.PT5161LRS(CHIPS)':
 'B_PETN12': CDS_PINID='B_PETN12';
NET_NAME
'P5E_CPU1_P2_TX_BUF_DN<4>'
 '@T6G_MB_LIB.T6G(SCH_1):P5E_CPU1_P2_TX_BUF_DN'<4>:
 C_SIGNAL='@t6g_mb_lib.t6g(sch_1):p5e_cpu1_p2_tx_buf_dn(4)';
NODE_NAME     C6702 2
 '@T6G_MB_LIB.T6G(SCH_1):PAGE450_I23@PURE_QUANTA.Q_CAP_DIFFBUS(CHIPS)':
 '2': CDS_PINID='\2\';
NODE_NAME     U6016 DL10
 '@T6G_MB_LIB.T6G(SCH_1):PAGE450_I142@PURE_QUANTA.PT5161LRS(CHIPS)':
 'B_PETN11': CDS_PINID='B_PETN11';
NET_NAME
'P5E_CPU1_P2_TX_BUF_DN<5>'
 '@T6G_MB_LIB.T6G(SCH_1):P5E_CPU1_P2_TX_BUF_DN'<5>:
 C_SIGNAL='@t6g_mb_lib.t6g(sch_1):p5e_cpu1_p2_tx_buf_dn(5)';
NODE_NAME     C6704 2
 '@T6G_MB_LIB.T6G(SCH_1):PAGE450_I21@PURE_QUANTA.Q_CAP_DIFFBUS(CHIPS)':
 '2': CDS_PINID='\2\';
NODE_NAME     U6016 DD10
 '@T6G_MB_LIB.T6G(SCH_1):PAGE450_I142@PURE_QUANTA.PT5161LRS(CHIPS)':
 'B_PETN10': CDS_PINID='B_PETN10';
NET_NAME
'P5E_CPU1_P2_TX_BUF_DN<6>'
 '@T6G_MB_LIB.T6G(SCH_1):P5E_CPU1_P2_TX_BUF_DN'<6>:
 C_SIGNAL='@t6g_mb_lib.t6g(sch_1):p5e_cpu1_p2_tx_buf_dn(6)';
NODE_NAME     C6706 2
 '@T6G_MB_LIB.T6G(SCH_1):PAGE450_I19@PURE_QUANTA.Q_CAP_DIFFBUS(CHIPS)':
 '2': CDS_PINID='\2\';
NODE_NAME     U6016 CU10
 '@T6G_MB_LIB.T6G(SCH_1):PAGE450_I142@PURE_QUANTA.PT5161LRS(CHIPS)':
 'B_PETN9': CDS_PINID='B_PETN9';
NET_NAME
'P5E_CPU1_P2_TX_BUF_DN<7>'
 '@T6G_MB_LIB.T6G(SCH_1):P5E_CPU1_P2_TX_BUF_DN'<7>:
 C_SIGNAL='@t6g_mb_lib.t6g(sch_1):p5e_cpu1_p2_tx_buf_dn(7)';
NODE_NAME     C6708 2
 '@T6G_MB_LIB.T6G(SCH_1):PAGE450_I17@PURE_QUANTA.Q_CAP_DIFFBUS(CHIPS)':
 '2': CDS_PINID='\2\';
NODE_NAME     U6016 CK10
 '@T6G_MB_LIB.T6G(SCH_1):PAGE450_I142@PURE_QUANTA.PT5161LRS(CHIPS)':
 'B_PETN8': CDS_PINID='B_PETN8';
NET_NAME
'P5E_CPU1_P2_TX_BUF_DN<8>'
 '@T6G_MB_LIB.T6G(SCH_1):P5E_CPU1_P2_TX_BUF_DN'<8>:
 C_SIGNAL='@t6g_mb_lib.t6g(sch_1):p5e_cpu1_p2_tx_buf_dn(8)';
NODE_NAME     U6016 CC10
 '@T6G_MB_LIB.T6G(SCH_1):PAGE450_I33@PURE_QUANTA.PT5161LRS(CHIPS)':
 'B_PETN7': CDS_PINID='B_PETN7';
NODE_NAME     C6710 2
 '@T6G_MB_LIB.T6G(SCH_1):PAGE450_I103@PURE_QUANTA.Q_CAP_DIFFBUS(CHIPS)':
 '2': CDS_PINID='\2\';
NET_NAME
'P5E_CPU1_P2_TX_BUF_DN<9>'
 '@T6G_MB_LIB.T6G(SCH_1):P5E_CPU1_P2_TX_BUF_DN'<9>:
 C_SIGNAL='@t6g_mb_lib.t6g(sch_1):p5e_cpu1_p2_tx_buf_dn(9)';
NODE_NAME     U6016 BT10
 '@T6G_MB_LIB.T6G(SCH_1):PAGE450_I33@PURE_QUANTA.PT5161LRS(CHIPS)':
 'B_PETN6': CDS_PINID='B_PETN6';
NODE_NAME     C6712 2
 '@T6G_MB_LIB.T6G(SCH_1):PAGE450_I98@PURE_QUANTA.Q_CAP_DIFFBUS(CHIPS)':
 '2': CDS_PINID='\2\';
NET_NAME
'P5E_CPU1_P2_TX_BUF_DP<0>'
 '@T6G_MB_LIB.T6G(SCH_1):P5E_CPU1_P2_TX_BUF_DP'<0>:
 C_SIGNAL='@t6g_mb_lib.t6g(sch_1):p5e_cpu1_p2_tx_buf_dp(0)';
NODE_NAME     C6693 2
 '@T6G_MB_LIB.T6G(SCH_1):PAGE450_I34@PURE_QUANTA.Q_CAP_DIFFBUS(CHIPS)':
 '2': CDS_PINID='\2\';
NODE_NAME     U6016 EU7
 '@T6G_MB_LIB.T6G(SCH_1):PAGE450_I142@PURE_QUANTA.PT5161LRS(CHIPS)':
 'B_PETP15': CDS_PINID='B_PETP15';
NET_NAME
'P5E_CPU1_P2_TX_BUF_DP<10>'
 '@T6G_MB_LIB.T6G(SCH_1):P5E_CPU1_P2_TX_BUF_DP'<10>:
 C_SIGNAL='@t6g_mb_lib.t6g(sch_1):p5e_cpu1_p2_tx_buf_dp(10)';
NODE_NAME     U6016 BG7
 '@T6G_MB_LIB.T6G(SCH_1):PAGE450_I33@PURE_QUANTA.PT5161LRS(CHIPS)':
 'B_PETP5': CDS_PINID='B_PETP5';
NODE_NAME     C6713 2
 '@T6G_MB_LIB.T6G(SCH_1):PAGE450_I97@PURE_QUANTA.Q_CAP_DIFFBUS(CHIPS)':
 '2': CDS_PINID='\2\';
NET_NAME
'P5E_CPU1_P2_TX_BUF_DP<11>'
 '@T6G_MB_LIB.T6G(SCH_1):P5E_CPU1_P2_TX_BUF_DP'<11>:
 C_SIGNAL='@t6g_mb_lib.t6g(sch_1):p5e_cpu1_p2_tx_buf_dp(11)';
NODE_NAME     U6016 AY7
 '@T6G_MB_LIB.T6G(SCH_1):PAGE450_I33@PURE_QUANTA.PT5161LRS(CHIPS)':
 'B_PETP4': CDS_PINID='B_PETP4';
NODE_NAME     C6715 2
 '@T6G_MB_LIB.T6G(SCH_1):PAGE450_I95@PURE_QUANTA.Q_CAP_DIFFBUS(CHIPS)':
 '2': CDS_PINID='\2\';
NET_NAME
'P5E_CPU1_P2_TX_BUF_DP<12>'
 '@T6G_MB_LIB.T6G(SCH_1):P5E_CPU1_P2_TX_BUF_DP'<12>:
 C_SIGNAL='@t6g_mb_lib.t6g(sch_1):p5e_cpu1_p2_tx_buf_dp(12)';
NODE_NAME     U6016 AN7
 '@T6G_MB_LIB.T6G(SCH_1):PAGE450_I33@PURE_QUANTA.PT5161LRS(CHIPS)':
 'B_PETP3': CDS_PINID='B_PETP3';
NODE_NAME     C6717 2
 '@T6G_MB_LIB.T6G(SCH_1):PAGE450_I93@PURE_QUANTA.Q_CAP_DIFFBUS(CHIPS)':
 '2': CDS_PINID='\2\';
NET_NAME
'P5E_CPU1_P2_TX_BUF_DP<13>'
 '@T6G_MB_LIB.T6G(SCH_1):P5E_CPU1_P2_TX_BUF_DP'<13>:
 C_SIGNAL='@t6g_mb_lib.t6g(sch_1):p5e_cpu1_p2_tx_buf_dp(13)';
NODE_NAME     U6016 AF7
 '@T6G_MB_LIB.T6G(SCH_1):PAGE450_I33@PURE_QUANTA.PT5161LRS(CHIPS)':
 'B_PETP2': CDS_PINID='B_PETP2';
NODE_NAME     C6719 2
 '@T6G_MB_LIB.T6G(SCH_1):PAGE450_I91@PURE_QUANTA.Q_CAP_DIFFBUS(CHIPS)':
 '2': CDS_PINID='\2\';
NET_NAME
'P5E_CPU1_P2_TX_BUF_DP<14>'
 '@T6G_MB_LIB.T6G(SCH_1):P5E_CPU1_P2_TX_BUF_DP'<14>:
 C_SIGNAL='@t6g_mb_lib.t6g(sch_1):p5e_cpu1_p2_tx_buf_dp(14)';
NODE_NAME     U6016 W7
 '@T6G_MB_LIB.T6G(SCH_1):PAGE450_I33@PURE_QUANTA.PT5161LRS(CHIPS)':
 'B_PETP1': CDS_PINID='B_PETP1';
NODE_NAME     C6721 2
 '@T6G_MB_LIB.T6G(SCH_1):PAGE450_I84@PURE_QUANTA.Q_CAP_DIFFBUS(CHIPS)':
 '2': CDS_PINID='\2\';
NET_NAME
'P5E_CPU1_P2_TX_BUF_DP<15>'
 '@T6G_MB_LIB.T6G(SCH_1):P5E_CPU1_P2_TX_BUF_DP'<15>:
 C_SIGNAL='@t6g_mb_lib.t6g(sch_1):p5e_cpu1_p2_tx_buf_dp(15)';
NODE_NAME     U6016 M7
 '@T6G_MB_LIB.T6G(SCH_1):PAGE450_I33@PURE_QUANTA.PT5161LRS(CHIPS)':
 'B_PETP0': CDS_PINID='B_PETP0';
NODE_NAME     C6723 2
 '@T6G_MB_LIB.T6G(SCH_1):PAGE450_I82@PURE_QUANTA.Q_CAP_DIFFBUS(CHIPS)':
 '2': CDS_PINID='\2\';
NET_NAME
'P5E_CPU1_P2_TX_BUF_DP<1>'
 '@T6G_MB_LIB.T6G(SCH_1):P5E_CPU1_P2_TX_BUF_DP'<1>:
 C_SIGNAL='@t6g_mb_lib.t6g(sch_1):p5e_cpu1_p2_tx_buf_dp(1)';
NODE_NAME     C6695 2
 '@T6G_MB_LIB.T6G(SCH_1):PAGE450_I29@PURE_QUANTA.Q_CAP_DIFFBUS(CHIPS)':
 '2': CDS_PINID='\2\';
NODE_NAME     U6016 EK7
 '@T6G_MB_LIB.T6G(SCH_1):PAGE450_I142@PURE_QUANTA.PT5161LRS(CHIPS)':
 'B_PETP14': CDS_PINID='B_PETP14';
NET_NAME
'P5E_CPU1_P2_TX_BUF_DP<2>'
 '@T6G_MB_LIB.T6G(SCH_1):P5E_CPU1_P2_TX_BUF_DP'<2>:
 C_SIGNAL='@t6g_mb_lib.t6g(sch_1):p5e_cpu1_p2_tx_buf_dp(2)';
NODE_NAME     C6697 2
 '@T6G_MB_LIB.T6G(SCH_1):PAGE450_I30@PURE_QUANTA.Q_CAP_DIFFBUS(CHIPS)':
 '2': CDS_PINID='\2\';
NODE_NAME     U6016 EC7
 '@T6G_MB_LIB.T6G(SCH_1):PAGE450_I142@PURE_QUANTA.PT5161LRS(CHIPS)':
 'B_PETP13': CDS_PINID='B_PETP13';
NET_NAME
'P5E_CPU1_P2_TX_BUF_DP<3>'
 '@T6G_MB_LIB.T6G(SCH_1):P5E_CPU1_P2_TX_BUF_DP'<3>:
 C_SIGNAL='@t6g_mb_lib.t6g(sch_1):p5e_cpu1_p2_tx_buf_dp(3)';
NODE_NAME     C6699 2
 '@T6G_MB_LIB.T6G(SCH_1):PAGE450_I25@PURE_QUANTA.Q_CAP_DIFFBUS(CHIPS)':
 '2': CDS_PINID='\2\';
NODE_NAME     U6016 DT7
 '@T6G_MB_LIB.T6G(SCH_1):PAGE450_I142@PURE_QUANTA.PT5161LRS(CHIPS)':
 'B_PETP12': CDS_PINID='B_PETP12';
NET_NAME
'P5E_CPU1_P2_TX_BUF_DP<4>'
 '@T6G_MB_LIB.T6G(SCH_1):P5E_CPU1_P2_TX_BUF_DP'<4>:
 C_SIGNAL='@t6g_mb_lib.t6g(sch_1):p5e_cpu1_p2_tx_buf_dp(4)';
NODE_NAME     C6701 2
 '@T6G_MB_LIB.T6G(SCH_1):PAGE450_I24@PURE_QUANTA.Q_CAP_DIFFBUS(CHIPS)':
 '2': CDS_PINID='\2\';
NODE_NAME     U6016 DJ7
 '@T6G_MB_LIB.T6G(SCH_1):PAGE450_I142@PURE_QUANTA.PT5161LRS(CHIPS)':
 'B_PETP11': CDS_PINID='B_PETP11';
NET_NAME
'P5E_CPU1_P2_TX_BUF_DP<5>'
 '@T6G_MB_LIB.T6G(SCH_1):P5E_CPU1_P2_TX_BUF_DP'<5>:
 C_SIGNAL='@t6g_mb_lib.t6g(sch_1):p5e_cpu1_p2_tx_buf_dp(5)';
NODE_NAME     C6703 2
 '@T6G_MB_LIB.T6G(SCH_1):PAGE450_I22@PURE_QUANTA.Q_CAP_DIFFBUS(CHIPS)':
 '2': CDS_PINID='\2\';
NODE_NAME     U6016 DB7
 '@T6G_MB_LIB.T6G(SCH_1):PAGE450_I142@PURE_QUANTA.PT5161LRS(CHIPS)':
 'B_PETP10': CDS_PINID='B_PETP10';
NET_NAME
'P5E_CPU1_P2_TX_BUF_DP<6>'
 '@T6G_MB_LIB.T6G(SCH_1):P5E_CPU1_P2_TX_BUF_DP'<6>:
 C_SIGNAL='@t6g_mb_lib.t6g(sch_1):p5e_cpu1_p2_tx_buf_dp(6)';
NODE_NAME     C6705 2
 '@T6G_MB_LIB.T6G(SCH_1):PAGE450_I20@PURE_QUANTA.Q_CAP_DIFFBUS(CHIPS)':
 '2': CDS_PINID='\2\';
NODE_NAME     U6016 CR7
 '@T6G_MB_LIB.T6G(SCH_1):PAGE450_I142@PURE_QUANTA.PT5161LRS(CHIPS)':
 'B_PETP9': CDS_PINID='B_PETP9';
NET_NAME
'P5E_CPU1_P2_TX_BUF_DP<7>'
 '@T6G_MB_LIB.T6G(SCH_1):P5E_CPU1_P2_TX_BUF_DP'<7>:
 C_SIGNAL='@t6g_mb_lib.t6g(sch_1):p5e_cpu1_p2_tx_buf_dp(7)';
NODE_NAME     C6707 2
 '@T6G_MB_LIB.T6G(SCH_1):PAGE450_I18@PURE_QUANTA.Q_CAP_DIFFBUS(CHIPS)':
 '2': CDS_PINID='\2\';
NODE_NAME     U6016 CH7
 '@T6G_MB_LIB.T6G(SCH_1):PAGE450_I142@PURE_QUANTA.PT5161LRS(CHIPS)':
 'B_PETP8': CDS_PINID='B_PETP8';
NET_NAME
'P5E_CPU1_P2_TX_BUF_DP<8>'
 '@T6G_MB_LIB.T6G(SCH_1):P5E_CPU1_P2_TX_BUF_DP'<8>:
 C_SIGNAL='@t6g_mb_lib.t6g(sch_1):p5e_cpu1_p2_tx_buf_dp(8)';
NODE_NAME     U6016 CA7
 '@T6G_MB_LIB.T6G(SCH_1):PAGE450_I33@PURE_QUANTA.PT5161LRS(CHIPS)':
 'B_PETP7': CDS_PINID='B_PETP7';
NODE_NAME     C6709 2
 '@T6G_MB_LIB.T6G(SCH_1):PAGE450_I102@PURE_QUANTA.Q_CAP_DIFFBUS(CHIPS)':
 '2': CDS_PINID='\2\';
NET_NAME
'P5E_CPU1_P2_TX_BUF_DP<9>'
 '@T6G_MB_LIB.T6G(SCH_1):P5E_CPU1_P2_TX_BUF_DP'<9>:
 C_SIGNAL='@t6g_mb_lib.t6g(sch_1):p5e_cpu1_p2_tx_buf_dp(9)';
NODE_NAME     U6016 BP7
 '@T6G_MB_LIB.T6G(SCH_1):PAGE450_I33@PURE_QUANTA.PT5161LRS(CHIPS)':
 'B_PETP6': CDS_PINID='B_PETP6';
NODE_NAME     C6711 2
 '@T6G_MB_LIB.T6G(SCH_1):PAGE450_I99@PURE_QUANTA.Q_CAP_DIFFBUS(CHIPS)':
 '2': CDS_PINID='\2\';
NET_NAME
'P5E_CPU1_P2_TX_C_DN<0>'
 '@T6G_MB_LIB.T6G(SCH_1):P5E_CPU1_P2_TX_C_DN'<0>:
 C_SIGNAL='@t6g_mb_lib.t6g(sch_1):p5e_cpu1_p2_tx_c_dn(0)';
NODE_NAME     C772 1
 '@T6G_MB_LIB.T6G(SCH_1):PAGE354_I123@PURE_QUANTA.Q_CAP_DIFFBUS(CHIPS)':
 '1': CDS_PINID='\1\';
NODE_NAME     U6016 EV34
 '@T6G_MB_LIB.T6G(SCH_1):PAGE447_I38@PURE_QUANTA.PT5161LRS(CHIPS)':
 'B_PERP15': CDS_PINID='B_PERP15';
NET_NAME
'P5E_CPU1_P2_TX_C_DN<10>'
 '@T6G_MB_LIB.T6G(SCH_1):P5E_CPU1_P2_TX_C_DN'<10>:
 C_SIGNAL='@t6g_mb_lib.t6g(sch_1):p5e_cpu1_p2_tx_c_dn(10)';
NODE_NAME     C752 1
 '@T6G_MB_LIB.T6G(SCH_1):PAGE354_I159@PURE_QUANTA.Q_CAP_DIFFBUS(CHIPS)':
 '1': CDS_PINID='\1\';
NODE_NAME     U6016 BH34
 '@T6G_MB_LIB.T6G(SCH_1):PAGE447_I1@PURE_QUANTA.PT5161LRS(CHIPS)':
 'B_PERP5': CDS_PINID='B_PERP5';
NET_NAME
'P5E_CPU1_P2_TX_C_DN<11>'
 '@T6G_MB_LIB.T6G(SCH_1):P5E_CPU1_P2_TX_C_DN'<11>:
 C_SIGNAL='@t6g_mb_lib.t6g(sch_1):p5e_cpu1_p2_tx_c_dn(11)';
NODE_NAME     C750 1
 '@T6G_MB_LIB.T6G(SCH_1):PAGE354_I160@PURE_QUANTA.Q_CAP_DIFFBUS(CHIPS)':
 '1': CDS_PINID='\1\';
NODE_NAME     U6016 BA34
 '@T6G_MB_LIB.T6G(SCH_1):PAGE447_I1@PURE_QUANTA.PT5161LRS(CHIPS)':
 'B_PERP4': CDS_PINID='B_PERP4';
NET_NAME
'P5E_CPU1_P2_TX_C_DN<12>'
 '@T6G_MB_LIB.T6G(SCH_1):P5E_CPU1_P2_TX_C_DN'<12>:
 C_SIGNAL='@t6g_mb_lib.t6g(sch_1):p5e_cpu1_p2_tx_c_dn(12)';
NODE_NAME     C748 1
 '@T6G_MB_LIB.T6G(SCH_1):PAGE354_I163@PURE_QUANTA.Q_CAP_DIFFBUS(CHIPS)':
 '1': CDS_PINID='\1\';
NODE_NAME     U6016 AP34
 '@T6G_MB_LIB.T6G(SCH_1):PAGE447_I1@PURE_QUANTA.PT5161LRS(CHIPS)':
 'B_PERP3': CDS_PINID='B_PERP3';
NET_NAME
'P5E_CPU1_P2_TX_C_DN<13>'
 '@T6G_MB_LIB.T6G(SCH_1):P5E_CPU1_P2_TX_C_DN'<13>:
 C_SIGNAL='@t6g_mb_lib.t6g(sch_1):p5e_cpu1_p2_tx_c_dn(13)';
NODE_NAME     C746 1
 '@T6G_MB_LIB.T6G(SCH_1):PAGE354_I168@PURE_QUANTA.Q_CAP_DIFFBUS(CHIPS)':
 '1': CDS_PINID='\1\';
NODE_NAME     U6016 AG34
 '@T6G_MB_LIB.T6G(SCH_1):PAGE447_I1@PURE_QUANTA.PT5161LRS(CHIPS)':
 'B_PERP2': CDS_PINID='B_PERP2';
NET_NAME
'P5E_CPU1_P2_TX_C_DN<14>'
 '@T6G_MB_LIB.T6G(SCH_1):P5E_CPU1_P2_TX_C_DN'<14>:
 C_SIGNAL='@t6g_mb_lib.t6g(sch_1):p5e_cpu1_p2_tx_c_dn(14)';
NODE_NAME     C744 1
 '@T6G_MB_LIB.T6G(SCH_1):PAGE354_I170@PURE_QUANTA.Q_CAP_DIFFBUS(CHIPS)':
 '1': CDS_PINID='\1\';
NODE_NAME     U6016 Y34
 '@T6G_MB_LIB.T6G(SCH_1):PAGE447_I1@PURE_QUANTA.PT5161LRS(CHIPS)':
 'B_PERP1': CDS_PINID='B_PERP1';
NET_NAME
'P5E_CPU1_P2_TX_C_DN<15>'
 '@T6G_MB_LIB.T6G(SCH_1):P5E_CPU1_P2_TX_C_DN'<15>:
 C_SIGNAL='@t6g_mb_lib.t6g(sch_1):p5e_cpu1_p2_tx_c_dn(15)';
NODE_NAME     C742 1
 '@T6G_MB_LIB.T6G(SCH_1):PAGE354_I172@PURE_QUANTA.Q_CAP_DIFFBUS(CHIPS)':
 '1': CDS_PINID='\1\';
NODE_NAME     U6016 N34
 '@T6G_MB_LIB.T6G(SCH_1):PAGE447_I1@PURE_QUANTA.PT5161LRS(CHIPS)':
 'B_PERP0': CDS_PINID='B_PERP0';
NET_NAME
'P5E_CPU1_P2_TX_C_DN<1>'
 '@T6G_MB_LIB.T6G(SCH_1):P5E_CPU1_P2_TX_C_DN'<1>:
 C_SIGNAL='@t6g_mb_lib.t6g(sch_1):p5e_cpu1_p2_tx_c_dn(1)';
NODE_NAME     C770 1
 '@T6G_MB_LIB.T6G(SCH_1):PAGE354_I125@PURE_QUANTA.Q_CAP_DIFFBUS(CHIPS)':
 '1': CDS_PINID='\1\';
NODE_NAME     U6016 EN35
 '@T6G_MB_LIB.T6G(SCH_1):PAGE447_I38@PURE_QUANTA.PT5161LRS(CHIPS)':
 'B_PERN14': CDS_PINID='B_PERN14';
NET_NAME
'P5E_CPU1_P2_TX_C_DN<2>'
 '@T6G_MB_LIB.T6G(SCH_1):P5E_CPU1_P2_TX_C_DN'<2>:
 C_SIGNAL='@t6g_mb_lib.t6g(sch_1):p5e_cpu1_p2_tx_c_dn(2)';
NODE_NAME     C768 1
 '@T6G_MB_LIB.T6G(SCH_1):PAGE354_I127@PURE_QUANTA.Q_CAP_DIFFBUS(CHIPS)':
 '1': CDS_PINID='\1\';
NODE_NAME     U6016 ED34
 '@T6G_MB_LIB.T6G(SCH_1):PAGE447_I38@PURE_QUANTA.PT5161LRS(CHIPS)':
 'B_PERP13': CDS_PINID='B_PERP13';
NET_NAME
'P5E_CPU1_P2_TX_C_DN<3>'
 '@T6G_MB_LIB.T6G(SCH_1):P5E_CPU1_P2_TX_C_DN'<3>:
 C_SIGNAL='@t6g_mb_lib.t6g(sch_1):p5e_cpu1_p2_tx_c_dn(3)';
NODE_NAME     C766 1
 '@T6G_MB_LIB.T6G(SCH_1):PAGE354_I129@PURE_QUANTA.Q_CAP_DIFFBUS(CHIPS)':
 '1': CDS_PINID='\1\';
NODE_NAME     U6016 DU34
 '@T6G_MB_LIB.T6G(SCH_1):PAGE447_I38@PURE_QUANTA.PT5161LRS(CHIPS)':
 'B_PERP12': CDS_PINID='B_PERP12';
NET_NAME
'P5E_CPU1_P2_TX_C_DN<4>'
 '@T6G_MB_LIB.T6G(SCH_1):P5E_CPU1_P2_TX_C_DN'<4>:
 C_SIGNAL='@t6g_mb_lib.t6g(sch_1):p5e_cpu1_p2_tx_c_dn(4)';
NODE_NAME     C764 1
 '@T6G_MB_LIB.T6G(SCH_1):PAGE354_I130@PURE_QUANTA.Q_CAP_DIFFBUS(CHIPS)':
 '1': CDS_PINID='\1\';
NODE_NAME     U6016 DK34
 '@T6G_MB_LIB.T6G(SCH_1):PAGE447_I38@PURE_QUANTA.PT5161LRS(CHIPS)':
 'B_PERP11': CDS_PINID='B_PERP11';
NET_NAME
'P5E_CPU1_P2_TX_C_DN<5>'
 '@T6G_MB_LIB.T6G(SCH_1):P5E_CPU1_P2_TX_C_DN'<5>:
 C_SIGNAL='@t6g_mb_lib.t6g(sch_1):p5e_cpu1_p2_tx_c_dn(5)';
NODE_NAME     C762 1
 '@T6G_MB_LIB.T6G(SCH_1):PAGE354_I136@PURE_QUANTA.Q_CAP_DIFFBUS(CHIPS)':
 '1': CDS_PINID='\1\';
NODE_NAME     U6016 DC34
 '@T6G_MB_LIB.T6G(SCH_1):PAGE447_I38@PURE_QUANTA.PT5161LRS(CHIPS)':
 'B_PERP10': CDS_PINID='B_PERP10';
NET_NAME
'P5E_CPU1_P2_TX_C_DN<6>'
 '@T6G_MB_LIB.T6G(SCH_1):P5E_CPU1_P2_TX_C_DN'<6>:
 C_SIGNAL='@t6g_mb_lib.t6g(sch_1):p5e_cpu1_p2_tx_c_dn(6)';
NODE_NAME     C760 1
 '@T6G_MB_LIB.T6G(SCH_1):PAGE354_I138@PURE_QUANTA.Q_CAP_DIFFBUS(CHIPS)':
 '1': CDS_PINID='\1\';
NODE_NAME     U6016 CT34
 '@T6G_MB_LIB.T6G(SCH_1):PAGE447_I38@PURE_QUANTA.PT5161LRS(CHIPS)':
 'B_PERP9': CDS_PINID='B_PERP9';
NET_NAME
'P5E_CPU1_P2_TX_C_DN<7>'
 '@T6G_MB_LIB.T6G(SCH_1):P5E_CPU1_P2_TX_C_DN'<7>:
 C_SIGNAL='@t6g_mb_lib.t6g(sch_1):p5e_cpu1_p2_tx_c_dn(7)';
NODE_NAME     C758 1
 '@T6G_MB_LIB.T6G(SCH_1):PAGE354_I140@PURE_QUANTA.Q_CAP_DIFFBUS(CHIPS)':
 '1': CDS_PINID='\1\';
NODE_NAME     U6016 CJ34
 '@T6G_MB_LIB.T6G(SCH_1):PAGE447_I38@PURE_QUANTA.PT5161LRS(CHIPS)':
 'B_PERP8': CDS_PINID='B_PERP8';
NET_NAME
'P5E_CPU1_P2_TX_C_DN<8>'
 '@T6G_MB_LIB.T6G(SCH_1):P5E_CPU1_P2_TX_C_DN'<8>:
 C_SIGNAL='@t6g_mb_lib.t6g(sch_1):p5e_cpu1_p2_tx_c_dn(8)';
NODE_NAME     C756 1
 '@T6G_MB_LIB.T6G(SCH_1):PAGE354_I154@PURE_QUANTA.Q_CAP_DIFFBUS(CHIPS)':
 '1': CDS_PINID='\1\';
NODE_NAME     U6016 CB34
 '@T6G_MB_LIB.T6G(SCH_1):PAGE447_I1@PURE_QUANTA.PT5161LRS(CHIPS)':
 'B_PERP7': CDS_PINID='B_PERP7';
NET_NAME
'P5E_CPU1_P2_TX_C_DN<9>'
 '@T6G_MB_LIB.T6G(SCH_1):P5E_CPU1_P2_TX_C_DN'<9>:
 C_SIGNAL='@t6g_mb_lib.t6g(sch_1):p5e_cpu1_p2_tx_c_dn(9)';
NODE_NAME     C754 1
 '@T6G_MB_LIB.T6G(SCH_1):PAGE354_I157@PURE_QUANTA.Q_CAP_DIFFBUS(CHIPS)':
 '1': CDS_PINID='\1\';
NODE_NAME     U6016 BR34
 '@T6G_MB_LIB.T6G(SCH_1):PAGE447_I1@PURE_QUANTA.PT5161LRS(CHIPS)':
 'B_PERP6': CDS_PINID='B_PERP6';
NET_NAME
'P5E_CPU1_P2_TX_C_DP<0>'
 '@T6G_MB_LIB.T6G(SCH_1):P5E_CPU1_P2_TX_C_DP'<0>:
 C_SIGNAL='@t6g_mb_lib.t6g(sch_1):p5e_cpu1_p2_tx_c_dp(0)';
NODE_NAME     C773 1
 '@T6G_MB_LIB.T6G(SCH_1):PAGE354_I122@PURE_QUANTA.Q_CAP_DIFFBUS(CHIPS)':
 '1': CDS_PINID='\1\';
NODE_NAME     U6016 EY35
 '@T6G_MB_LIB.T6G(SCH_1):PAGE447_I38@PURE_QUANTA.PT5161LRS(CHIPS)':
 'B_PERN15': CDS_PINID='B_PERN15';
NET_NAME
'P5E_CPU1_P2_TX_C_DP<10>'
 '@T6G_MB_LIB.T6G(SCH_1):P5E_CPU1_P2_TX_C_DP'<10>:
 C_SIGNAL='@t6g_mb_lib.t6g(sch_1):p5e_cpu1_p2_tx_c_dp(10)';
NODE_NAME     C753 1
 '@T6G_MB_LIB.T6G(SCH_1):PAGE354_I158@PURE_QUANTA.Q_CAP_DIFFBUS(CHIPS)':
 '1': CDS_PINID='\1\';
NODE_NAME     U6016 BK35
 '@T6G_MB_LIB.T6G(SCH_1):PAGE447_I1@PURE_QUANTA.PT5161LRS(CHIPS)':
 'B_PERN5': CDS_PINID='B_PERN5';
NET_NAME
'P5E_CPU1_P2_TX_C_DP<11>'
 '@T6G_MB_LIB.T6G(SCH_1):P5E_CPU1_P2_TX_C_DP'<11>:
 C_SIGNAL='@t6g_mb_lib.t6g(sch_1):p5e_cpu1_p2_tx_c_dp(11)';
NODE_NAME     C751 1
 '@T6G_MB_LIB.T6G(SCH_1):PAGE354_I161@PURE_QUANTA.Q_CAP_DIFFBUS(CHIPS)':
 '1': CDS_PINID='\1\';
NODE_NAME     U6016 BC35
 '@T6G_MB_LIB.T6G(SCH_1):PAGE447_I1@PURE_QUANTA.PT5161LRS(CHIPS)':
 'B_PERN4': CDS_PINID='B_PERN4';
NET_NAME
'P5E_CPU1_P2_TX_C_DP<12>'
 '@T6G_MB_LIB.T6G(SCH_1):P5E_CPU1_P2_TX_C_DP'<12>:
 C_SIGNAL='@t6g_mb_lib.t6g(sch_1):p5e_cpu1_p2_tx_c_dp(12)';
NODE_NAME     C749 1
 '@T6G_MB_LIB.T6G(SCH_1):PAGE354_I162@PURE_QUANTA.Q_CAP_DIFFBUS(CHIPS)':
 '1': CDS_PINID='\1\';
NODE_NAME     U6016 AT35
 '@T6G_MB_LIB.T6G(SCH_1):PAGE447_I1@PURE_QUANTA.PT5161LRS(CHIPS)':
 'B_PERN3': CDS_PINID='B_PERN3';
NET_NAME
'P5E_CPU1_P2_TX_C_DP<13>'
 '@T6G_MB_LIB.T6G(SCH_1):P5E_CPU1_P2_TX_C_DP'<13>:
 C_SIGNAL='@t6g_mb_lib.t6g(sch_1):p5e_cpu1_p2_tx_c_dp(13)';
NODE_NAME     C747 1
 '@T6G_MB_LIB.T6G(SCH_1):PAGE354_I167@PURE_QUANTA.Q_CAP_DIFFBUS(CHIPS)':
 '1': CDS_PINID='\1\';
NODE_NAME     U6016 AJ35
 '@T6G_MB_LIB.T6G(SCH_1):PAGE447_I1@PURE_QUANTA.PT5161LRS(CHIPS)':
 'B_PERN2': CDS_PINID='B_PERN2';
NET_NAME
'P5E_CPU1_P2_TX_C_DP<14>'
 '@T6G_MB_LIB.T6G(SCH_1):P5E_CPU1_P2_TX_C_DP'<14>:
 C_SIGNAL='@t6g_mb_lib.t6g(sch_1):p5e_cpu1_p2_tx_c_dp(14)';
NODE_NAME     C745 1
 '@T6G_MB_LIB.T6G(SCH_1):PAGE354_I169@PURE_QUANTA.Q_CAP_DIFFBUS(CHIPS)':
 '1': CDS_PINID='\1\';
NODE_NAME     U6016 AB35
 '@T6G_MB_LIB.T6G(SCH_1):PAGE447_I1@PURE_QUANTA.PT5161LRS(CHIPS)':
 'B_PERN1': CDS_PINID='B_PERN1';
NET_NAME
'P5E_CPU1_P2_TX_C_DP<15>'
 '@T6G_MB_LIB.T6G(SCH_1):P5E_CPU1_P2_TX_C_DP'<15>:
 C_SIGNAL='@t6g_mb_lib.t6g(sch_1):p5e_cpu1_p2_tx_c_dp(15)';
NODE_NAME     C743 1
 '@T6G_MB_LIB.T6G(SCH_1):PAGE354_I171@PURE_QUANTA.Q_CAP_DIFFBUS(CHIPS)':
 '1': CDS_PINID='\1\';
NODE_NAME     U6016 R35
 '@T6G_MB_LIB.T6G(SCH_1):PAGE447_I1@PURE_QUANTA.PT5161LRS(CHIPS)':
 'B_PERN0': CDS_PINID='B_PERN0';
NET_NAME
'P5E_CPU1_P2_TX_C_DP<1>'
 '@T6G_MB_LIB.T6G(SCH_1):P5E_CPU1_P2_TX_C_DP'<1>:
 C_SIGNAL='@t6g_mb_lib.t6g(sch_1):p5e_cpu1_p2_tx_c_dp(1)';
NODE_NAME     C771 1
 '@T6G_MB_LIB.T6G(SCH_1):PAGE354_I124@PURE_QUANTA.Q_CAP_DIFFBUS(CHIPS)':
 '1': CDS_PINID='\1\';
NODE_NAME     U6016 EL34
 '@T6G_MB_LIB.T6G(SCH_1):PAGE447_I38@PURE_QUANTA.PT5161LRS(CHIPS)':
 'B_PERP14': CDS_PINID='B_PERP14';
NET_NAME
'P5E_CPU1_P2_TX_C_DP<2>'
 '@T6G_MB_LIB.T6G(SCH_1):P5E_CPU1_P2_TX_C_DP'<2>:
 C_SIGNAL='@t6g_mb_lib.t6g(sch_1):p5e_cpu1_p2_tx_c_dp(2)';
NODE_NAME     C769 1
 '@T6G_MB_LIB.T6G(SCH_1):PAGE354_I126@PURE_QUANTA.Q_CAP_DIFFBUS(CHIPS)':
 '1': CDS_PINID='\1\';
NODE_NAME     U6016 EF35
 '@T6G_MB_LIB.T6G(SCH_1):PAGE447_I38@PURE_QUANTA.PT5161LRS(CHIPS)':
 'B_PERN13': CDS_PINID='B_PERN13';
NET_NAME
'P5E_CPU1_P2_TX_C_DP<3>'
 '@T6G_MB_LIB.T6G(SCH_1):P5E_CPU1_P2_TX_C_DP'<3>:
 C_SIGNAL='@t6g_mb_lib.t6g(sch_1):p5e_cpu1_p2_tx_c_dp(3)';
NODE_NAME     C767 1
 '@T6G_MB_LIB.T6G(SCH_1):PAGE354_I128@PURE_QUANTA.Q_CAP_DIFFBUS(CHIPS)':
 '1': CDS_PINID='\1\';
NODE_NAME     U6016 DW35
 '@T6G_MB_LIB.T6G(SCH_1):PAGE447_I38@PURE_QUANTA.PT5161LRS(CHIPS)':
 'B_PERN12': CDS_PINID='B_PERN12';
NET_NAME
'P5E_CPU1_P2_TX_C_DP<4>'
 '@T6G_MB_LIB.T6G(SCH_1):P5E_CPU1_P2_TX_C_DP'<4>:
 C_SIGNAL='@t6g_mb_lib.t6g(sch_1):p5e_cpu1_p2_tx_c_dp(4)';
NODE_NAME     C765 1
 '@T6G_MB_LIB.T6G(SCH_1):PAGE354_I131@PURE_QUANTA.Q_CAP_DIFFBUS(CHIPS)':
 '1': CDS_PINID='\1\';
NODE_NAME     U6016 DM35
 '@T6G_MB_LIB.T6G(SCH_1):PAGE447_I38@PURE_QUANTA.PT5161LRS(CHIPS)':
 'B_PERN11': CDS_PINID='B_PERN11';
NET_NAME
'P5E_CPU1_P2_TX_C_DP<5>'
 '@T6G_MB_LIB.T6G(SCH_1):P5E_CPU1_P2_TX_C_DP'<5>:
 C_SIGNAL='@t6g_mb_lib.t6g(sch_1):p5e_cpu1_p2_tx_c_dp(5)';
NODE_NAME     C763 1
 '@T6G_MB_LIB.T6G(SCH_1):PAGE354_I135@PURE_QUANTA.Q_CAP_DIFFBUS(CHIPS)':
 '1': CDS_PINID='\1\';
NODE_NAME     U6016 DE35
 '@T6G_MB_LIB.T6G(SCH_1):PAGE447_I38@PURE_QUANTA.PT5161LRS(CHIPS)':
 'B_PERN10': CDS_PINID='B_PERN10';
NET_NAME
'P5E_CPU1_P2_TX_C_DP<6>'
 '@T6G_MB_LIB.T6G(SCH_1):P5E_CPU1_P2_TX_C_DP'<6>:
 C_SIGNAL='@t6g_mb_lib.t6g(sch_1):p5e_cpu1_p2_tx_c_dp(6)';
NODE_NAME     C761 1
 '@T6G_MB_LIB.T6G(SCH_1):PAGE354_I137@PURE_QUANTA.Q_CAP_DIFFBUS(CHIPS)':
 '1': CDS_PINID='\1\';
NODE_NAME     U6016 CV35
 '@T6G_MB_LIB.T6G(SCH_1):PAGE447_I38@PURE_QUANTA.PT5161LRS(CHIPS)':
 'B_PERN9': CDS_PINID='B_PERN9';
NET_NAME
'P5E_CPU1_P2_TX_C_DP<7>'
 '@T6G_MB_LIB.T6G(SCH_1):P5E_CPU1_P2_TX_C_DP'<7>:
 C_SIGNAL='@t6g_mb_lib.t6g(sch_1):p5e_cpu1_p2_tx_c_dp(7)';
NODE_NAME     C759 1
 '@T6G_MB_LIB.T6G(SCH_1):PAGE354_I139@PURE_QUANTA.Q_CAP_DIFFBUS(CHIPS)':
 '1': CDS_PINID='\1\';
NODE_NAME     U6016 CL35
 '@T6G_MB_LIB.T6G(SCH_1):PAGE447_I38@PURE_QUANTA.PT5161LRS(CHIPS)':
 'B_PERN8': CDS_PINID='B_PERN8';
NET_NAME
'P5E_CPU1_P2_TX_C_DP<8>'
 '@T6G_MB_LIB.T6G(SCH_1):P5E_CPU1_P2_TX_C_DP'<8>:
 C_SIGNAL='@t6g_mb_lib.t6g(sch_1):p5e_cpu1_p2_tx_c_dp(8)';
NODE_NAME     C757 1
 '@T6G_MB_LIB.T6G(SCH_1):PAGE354_I155@PURE_QUANTA.Q_CAP_DIFFBUS(CHIPS)':
 '1': CDS_PINID='\1\';
NODE_NAME     U6016 CD35
 '@T6G_MB_LIB.T6G(SCH_1):PAGE447_I1@PURE_QUANTA.PT5161LRS(CHIPS)':
 'B_PERN7': CDS_PINID='B_PERN7';
NET_NAME
'P5E_CPU1_P2_TX_C_DP<9>'
 '@T6G_MB_LIB.T6G(SCH_1):P5E_CPU1_P2_TX_C_DP'<9>:
 C_SIGNAL='@t6g_mb_lib.t6g(sch_1):p5e_cpu1_p2_tx_c_dp(9)';
NODE_NAME     C755 1
 '@T6G_MB_LIB.T6G(SCH_1):PAGE354_I156@PURE_QUANTA.Q_CAP_DIFFBUS(CHIPS)':
 '1': CDS_PINID='\1\';
NODE_NAME     U6016 BU35
 '@T6G_MB_LIB.T6G(SCH_1):PAGE447_I1@PURE_QUANTA.PT5161LRS(CHIPS)':
 'B_PERN6': CDS_PINID='B_PERN6';
NET_NAME
'P5E_CPU1_P2_TX_DN<0>'
 '@T6G_MB_LIB.T6G(SCH_1):P5E_CPU1_P2_TX_DN'<0>:
 C_SIGNAL='@t6g_mb_lib.t6g(sch_1):p5e_cpu1_p2_tx_dn(0)';
NODE_NAME     U26 BT35
 '@T6G_MB_LIB.T6G(SCH_1):PAGE52_I148@PURE_QUANTA.GENOA_SP5(CHIPS)':
 'P2_TXN0': CDS_PINID='P2_TXN0';
NODE_NAME     C772 2
 '@T6G_MB_LIB.T6G(SCH_1):PAGE354_I123@PURE_QUANTA.Q_CAP_DIFFBUS(CHIPS)':
 '2': CDS_PINID='\2\';
NET_NAME
'P5E_CPU1_P2_TX_DN<10>'
 '@T6G_MB_LIB.T6G(SCH_1):P5E_CPU1_P2_TX_DN'<10>:
 C_SIGNAL='@t6g_mb_lib.t6g(sch_1):p5e_cpu1_p2_tx_dn(10)';
NODE_NAME     U26 BU26
 '@T6G_MB_LIB.T6G(SCH_1):PAGE52_I148@PURE_QUANTA.GENOA_SP5(CHIPS)':
 'P2_TXN10': CDS_PINID='P2_TXN10';
NODE_NAME     C752 2
 '@T6G_MB_LIB.T6G(SCH_1):PAGE354_I159@PURE_QUANTA.Q_CAP_DIFFBUS(CHIPS)':
 '2': CDS_PINID='\2\';
NET_NAME
'P5E_CPU1_P2_TX_DN<11>'
 '@T6G_MB_LIB.T6G(SCH_1):P5E_CPU1_P2_TX_DN'<11>:
 C_SIGNAL='@t6g_mb_lib.t6g(sch_1):p5e_cpu1_p2_tx_dn(11)';
NODE_NAME     U26 CA26
 '@T6G_MB_LIB.T6G(SCH_1):PAGE52_I148@PURE_QUANTA.GENOA_SP5(CHIPS)':
 'P2_TXN11': CDS_PINID='P2_TXN11';
NODE_NAME     C750 2
 '@T6G_MB_LIB.T6G(SCH_1):PAGE354_I160@PURE_QUANTA.Q_CAP_DIFFBUS(CHIPS)':
 '2': CDS_PINID='\2\';
NET_NAME
'P5E_CPU1_P2_TX_DN<12>'
 '@T6G_MB_LIB.T6G(SCH_1):P5E_CPU1_P2_TX_DN'<12>:
 C_SIGNAL='@t6g_mb_lib.t6g(sch_1):p5e_cpu1_p2_tx_dn(12)';
NODE_NAME     U26 BW26
 '@T6G_MB_LIB.T6G(SCH_1):PAGE52_I148@PURE_QUANTA.GENOA_SP5(CHIPS)':
 'P2_TXN12': CDS_PINID='P2_TXN12';
NODE_NAME     C748 2
 '@T6G_MB_LIB.T6G(SCH_1):PAGE354_I163@PURE_QUANTA.Q_CAP_DIFFBUS(CHIPS)':
 '2': CDS_PINID='\2\';
NET_NAME
'P5E_CPU1_P2_TX_DN<13>'
 '@T6G_MB_LIB.T6G(SCH_1):P5E_CPU1_P2_TX_DN'<13>:
 C_SIGNAL='@t6g_mb_lib.t6g(sch_1):p5e_cpu1_p2_tx_dn(13)';
NODE_NAME     U26 BU23
 '@T6G_MB_LIB.T6G(SCH_1):PAGE52_I148@PURE_QUANTA.GENOA_SP5(CHIPS)':
 'P2_TXN13': CDS_PINID='P2_TXN13';
NODE_NAME     C746 2
 '@T6G_MB_LIB.T6G(SCH_1):PAGE354_I168@PURE_QUANTA.Q_CAP_DIFFBUS(CHIPS)':
 '2': CDS_PINID='\2\';
NET_NAME
'P5E_CPU1_P2_TX_DN<14>'
 '@T6G_MB_LIB.T6G(SCH_1):P5E_CPU1_P2_TX_DN'<14>:
 C_SIGNAL='@t6g_mb_lib.t6g(sch_1):p5e_cpu1_p2_tx_dn(14)';
NODE_NAME     U26 CA23
 '@T6G_MB_LIB.T6G(SCH_1):PAGE52_I148@PURE_QUANTA.GENOA_SP5(CHIPS)':
 'P2_TXN14': CDS_PINID='P2_TXN14';
NODE_NAME     C744 2
 '@T6G_MB_LIB.T6G(SCH_1):PAGE354_I170@PURE_QUANTA.Q_CAP_DIFFBUS(CHIPS)':
 '2': CDS_PINID='\2\';
NET_NAME
'P5E_CPU1_P2_TX_DN<15>'
 '@T6G_MB_LIB.T6G(SCH_1):P5E_CPU1_P2_TX_DN'<15>:
 C_SIGNAL='@t6g_mb_lib.t6g(sch_1):p5e_cpu1_p2_tx_dn(15)';
NODE_NAME     U26 BW23
 '@T6G_MB_LIB.T6G(SCH_1):PAGE52_I148@PURE_QUANTA.GENOA_SP5(CHIPS)':
 'P2_TXN15': CDS_PINID='P2_TXN15';
NODE_NAME     C742 2
 '@T6G_MB_LIB.T6G(SCH_1):PAGE354_I172@PURE_QUANTA.Q_CAP_DIFFBUS(CHIPS)':
 '2': CDS_PINID='\2\';
NET_NAME
'P5E_CPU1_P2_TX_DN<1>'
 '@T6G_MB_LIB.T6G(SCH_1):P5E_CPU1_P2_TX_DN'<1>:
 C_SIGNAL='@t6g_mb_lib.t6g(sch_1):p5e_cpu1_p2_tx_dn(1)';
NODE_NAME     U26 BV35
 '@T6G_MB_LIB.T6G(SCH_1):PAGE52_I148@PURE_QUANTA.GENOA_SP5(CHIPS)':
 'P2_TXN1': CDS_PINID='P2_TXN1';
NODE_NAME     C770 2
 '@T6G_MB_LIB.T6G(SCH_1):PAGE354_I125@PURE_QUANTA.Q_CAP_DIFFBUS(CHIPS)':
 '2': CDS_PINID='\2\';
NET_NAME
'P5E_CPU1_P2_TX_DN<2>'
 '@T6G_MB_LIB.T6G(SCH_1):P5E_CPU1_P2_TX_DN'<2>:
 C_SIGNAL='@t6g_mb_lib.t6g(sch_1):p5e_cpu1_p2_tx_dn(2)';
NODE_NAME     U26 CB35
 '@T6G_MB_LIB.T6G(SCH_1):PAGE52_I148@PURE_QUANTA.GENOA_SP5(CHIPS)':
 'P2_TXN2': CDS_PINID='P2_TXN2';
NODE_NAME     C768 2
 '@T6G_MB_LIB.T6G(SCH_1):PAGE354_I127@PURE_QUANTA.Q_CAP_DIFFBUS(CHIPS)':
 '2': CDS_PINID='\2\';
NET_NAME
'P5E_CPU1_P2_TX_DN<3>'
 '@T6G_MB_LIB.T6G(SCH_1):P5E_CPU1_P2_TX_DN'<3>:
 C_SIGNAL='@t6g_mb_lib.t6g(sch_1):p5e_cpu1_p2_tx_dn(3)';
NODE_NAME     U26 BY35
 '@T6G_MB_LIB.T6G(SCH_1):PAGE52_I148@PURE_QUANTA.GENOA_SP5(CHIPS)':
 'P2_TXN3': CDS_PINID='P2_TXN3';
NODE_NAME     C766 2
 '@T6G_MB_LIB.T6G(SCH_1):PAGE354_I129@PURE_QUANTA.Q_CAP_DIFFBUS(CHIPS)':
 '2': CDS_PINID='\2\';
NET_NAME
'P5E_CPU1_P2_TX_DN<4>'
 '@T6G_MB_LIB.T6G(SCH_1):P5E_CPU1_P2_TX_DN'<4>:
 C_SIGNAL='@t6g_mb_lib.t6g(sch_1):p5e_cpu1_p2_tx_dn(4)';
NODE_NAME     U26 BU32
 '@T6G_MB_LIB.T6G(SCH_1):PAGE52_I148@PURE_QUANTA.GENOA_SP5(CHIPS)':
 'P2_TXN4': CDS_PINID='P2_TXN4';
NODE_NAME     C764 2
 '@T6G_MB_LIB.T6G(SCH_1):PAGE354_I130@PURE_QUANTA.Q_CAP_DIFFBUS(CHIPS)':
 '2': CDS_PINID='\2\';
NET_NAME
'P5E_CPU1_P2_TX_DN<5>'
 '@T6G_MB_LIB.T6G(SCH_1):P5E_CPU1_P2_TX_DN'<5>:
 C_SIGNAL='@t6g_mb_lib.t6g(sch_1):p5e_cpu1_p2_tx_dn(5)';
NODE_NAME     U26 CA32
 '@T6G_MB_LIB.T6G(SCH_1):PAGE52_I148@PURE_QUANTA.GENOA_SP5(CHIPS)':
 'P2_TXN5': CDS_PINID='P2_TXN5';
NODE_NAME     C762 2
 '@T6G_MB_LIB.T6G(SCH_1):PAGE354_I136@PURE_QUANTA.Q_CAP_DIFFBUS(CHIPS)':
 '2': CDS_PINID='\2\';
NET_NAME
'P5E_CPU1_P2_TX_DN<6>'
 '@T6G_MB_LIB.T6G(SCH_1):P5E_CPU1_P2_TX_DN'<6>:
 C_SIGNAL='@t6g_mb_lib.t6g(sch_1):p5e_cpu1_p2_tx_dn(6)';
NODE_NAME     U26 BW32
 '@T6G_MB_LIB.T6G(SCH_1):PAGE52_I148@PURE_QUANTA.GENOA_SP5(CHIPS)':
 'P2_TXN6': CDS_PINID='P2_TXN6';
NODE_NAME     C760 2
 '@T6G_MB_LIB.T6G(SCH_1):PAGE354_I138@PURE_QUANTA.Q_CAP_DIFFBUS(CHIPS)':
 '2': CDS_PINID='\2\';
NET_NAME
'P5E_CPU1_P2_TX_DN<7>'
 '@T6G_MB_LIB.T6G(SCH_1):P5E_CPU1_P2_TX_DN'<7>:
 C_SIGNAL='@t6g_mb_lib.t6g(sch_1):p5e_cpu1_p2_tx_dn(7)';
NODE_NAME     U26 BU29
 '@T6G_MB_LIB.T6G(SCH_1):PAGE52_I148@PURE_QUANTA.GENOA_SP5(CHIPS)':
 'P2_TXN7': CDS_PINID='P2_TXN7';
NODE_NAME     C758 2
 '@T6G_MB_LIB.T6G(SCH_1):PAGE354_I140@PURE_QUANTA.Q_CAP_DIFFBUS(CHIPS)':
 '2': CDS_PINID='\2\';
NET_NAME
'P5E_CPU1_P2_TX_DN<8>'
 '@T6G_MB_LIB.T6G(SCH_1):P5E_CPU1_P2_TX_DN'<8>:
 C_SIGNAL='@t6g_mb_lib.t6g(sch_1):p5e_cpu1_p2_tx_dn(8)';
NODE_NAME     U26 CA29
 '@T6G_MB_LIB.T6G(SCH_1):PAGE52_I148@PURE_QUANTA.GENOA_SP5(CHIPS)':
 'P2_TXN8': CDS_PINID='P2_TXN8';
NODE_NAME     C756 2
 '@T6G_MB_LIB.T6G(SCH_1):PAGE354_I154@PURE_QUANTA.Q_CAP_DIFFBUS(CHIPS)':
 '2': CDS_PINID='\2\';
NET_NAME
'P5E_CPU1_P2_TX_DN<9>'
 '@T6G_MB_LIB.T6G(SCH_1):P5E_CPU1_P2_TX_DN'<9>:
 C_SIGNAL='@t6g_mb_lib.t6g(sch_1):p5e_cpu1_p2_tx_dn(9)';
NODE_NAME     U26 BW29
 '@T6G_MB_LIB.T6G(SCH_1):PAGE52_I148@PURE_QUANTA.GENOA_SP5(CHIPS)':
 'P2_TXN9': CDS_PINID='P2_TXN9';
NODE_NAME     C754 2
 '@T6G_MB_LIB.T6G(SCH_1):PAGE354_I157@PURE_QUANTA.Q_CAP_DIFFBUS(CHIPS)':
 '2': CDS_PINID='\2\';
NET_NAME
'P5E_CPU1_P2_TX_DP<0>'
 '@T6G_MB_LIB.T6G(SCH_1):P5E_CPU1_P2_TX_DP'<0>:
 C_SIGNAL='@t6g_mb_lib.t6g(sch_1):p5e_cpu1_p2_tx_dp(0)';
NODE_NAME     U26 BT36
 '@T6G_MB_LIB.T6G(SCH_1):PAGE52_I148@PURE_QUANTA.GENOA_SP5(CHIPS)':
 'P2_TXP0': CDS_PINID='P2_TXP0';
NODE_NAME     C773 2
 '@T6G_MB_LIB.T6G(SCH_1):PAGE354_I122@PURE_QUANTA.Q_CAP_DIFFBUS(CHIPS)':
 '2': CDS_PINID='\2\';
NET_NAME
'P5E_CPU1_P2_TX_DP<10>'
 '@T6G_MB_LIB.T6G(SCH_1):P5E_CPU1_P2_TX_DP'<10>:
 C_SIGNAL='@t6g_mb_lib.t6g(sch_1):p5e_cpu1_p2_tx_dp(10)';
NODE_NAME     U26 BU27
 '@T6G_MB_LIB.T6G(SCH_1):PAGE52_I148@PURE_QUANTA.GENOA_SP5(CHIPS)':
 'P2_TXP10': CDS_PINID='P2_TXP10';
NODE_NAME     C753 2
 '@T6G_MB_LIB.T6G(SCH_1):PAGE354_I158@PURE_QUANTA.Q_CAP_DIFFBUS(CHIPS)':
 '2': CDS_PINID='\2\';
NET_NAME
'P5E_CPU1_P2_TX_DP<11>'
 '@T6G_MB_LIB.T6G(SCH_1):P5E_CPU1_P2_TX_DP'<11>:
 C_SIGNAL='@t6g_mb_lib.t6g(sch_1):p5e_cpu1_p2_tx_dp(11)';
NODE_NAME     U26 CA27
 '@T6G_MB_LIB.T6G(SCH_1):PAGE52_I148@PURE_QUANTA.GENOA_SP5(CHIPS)':
 'P2_TXP11': CDS_PINID='P2_TXP11';
NODE_NAME     C751 2
 '@T6G_MB_LIB.T6G(SCH_1):PAGE354_I161@PURE_QUANTA.Q_CAP_DIFFBUS(CHIPS)':
 '2': CDS_PINID='\2\';
NET_NAME
'P5E_CPU1_P2_TX_DP<12>'
 '@T6G_MB_LIB.T6G(SCH_1):P5E_CPU1_P2_TX_DP'<12>:
 C_SIGNAL='@t6g_mb_lib.t6g(sch_1):p5e_cpu1_p2_tx_dp(12)';
NODE_NAME     U26 BW27
 '@T6G_MB_LIB.T6G(SCH_1):PAGE52_I148@PURE_QUANTA.GENOA_SP5(CHIPS)':
 'P2_TXP12': CDS_PINID='P2_TXP12';
NODE_NAME     C749 2
 '@T6G_MB_LIB.T6G(SCH_1):PAGE354_I162@PURE_QUANTA.Q_CAP_DIFFBUS(CHIPS)':
 '2': CDS_PINID='\2\';
NET_NAME
'P5E_CPU1_P2_TX_DP<13>'
 '@T6G_MB_LIB.T6G(SCH_1):P5E_CPU1_P2_TX_DP'<13>:
 C_SIGNAL='@t6g_mb_lib.t6g(sch_1):p5e_cpu1_p2_tx_dp(13)';
NODE_NAME     U26 BU24
 '@T6G_MB_LIB.T6G(SCH_1):PAGE52_I148@PURE_QUANTA.GENOA_SP5(CHIPS)':
 'P2_TXP13': CDS_PINID='P2_TXP13';
NODE_NAME     C747 2
 '@T6G_MB_LIB.T6G(SCH_1):PAGE354_I167@PURE_QUANTA.Q_CAP_DIFFBUS(CHIPS)':
 '2': CDS_PINID='\2\';
NET_NAME
'P5E_CPU1_P2_TX_DP<14>'
 '@T6G_MB_LIB.T6G(SCH_1):P5E_CPU1_P2_TX_DP'<14>:
 C_SIGNAL='@t6g_mb_lib.t6g(sch_1):p5e_cpu1_p2_tx_dp(14)';
NODE_NAME     U26 CA24
 '@T6G_MB_LIB.T6G(SCH_1):PAGE52_I148@PURE_QUANTA.GENOA_SP5(CHIPS)':
 'P2_TXP14': CDS_PINID='P2_TXP14';
NODE_NAME     C745 2
 '@T6G_MB_LIB.T6G(SCH_1):PAGE354_I169@PURE_QUANTA.Q_CAP_DIFFBUS(CHIPS)':
 '2': CDS_PINID='\2\';
NET_NAME
'P5E_CPU1_P2_TX_DP<15>'
 '@T6G_MB_LIB.T6G(SCH_1):P5E_CPU1_P2_TX_DP'<15>:
 C_SIGNAL='@t6g_mb_lib.t6g(sch_1):p5e_cpu1_p2_tx_dp(15)';
NODE_NAME     U26 BW24
 '@T6G_MB_LIB.T6G(SCH_1):PAGE52_I148@PURE_QUANTA.GENOA_SP5(CHIPS)':
 'P2_TXP15': CDS_PINID='P2_TXP15';
NODE_NAME     C743 2
 '@T6G_MB_LIB.T6G(SCH_1):PAGE354_I171@PURE_QUANTA.Q_CAP_DIFFBUS(CHIPS)':
 '2': CDS_PINID='\2\';
NET_NAME
'P5E_CPU1_P2_TX_DP<1>'
 '@T6G_MB_LIB.T6G(SCH_1):P5E_CPU1_P2_TX_DP'<1>:
 C_SIGNAL='@t6g_mb_lib.t6g(sch_1):p5e_cpu1_p2_tx_dp(1)';
NODE_NAME     U26 BV36
 '@T6G_MB_LIB.T6G(SCH_1):PAGE52_I148@PURE_QUANTA.GENOA_SP5(CHIPS)':
 'P2_TXP1': CDS_PINID='P2_TXP1';
NODE_NAME     C771 2
 '@T6G_MB_LIB.T6G(SCH_1):PAGE354_I124@PURE_QUANTA.Q_CAP_DIFFBUS(CHIPS)':
 '2': CDS_PINID='\2\';
NET_NAME
'P5E_CPU1_P2_TX_DP<2>'
 '@T6G_MB_LIB.T6G(SCH_1):P5E_CPU1_P2_TX_DP'<2>:
 C_SIGNAL='@t6g_mb_lib.t6g(sch_1):p5e_cpu1_p2_tx_dp(2)';
NODE_NAME     U26 CB36
 '@T6G_MB_LIB.T6G(SCH_1):PAGE52_I148@PURE_QUANTA.GENOA_SP5(CHIPS)':
 'P2_TXP2': CDS_PINID='P2_TXP2';
NODE_NAME     C769 2
 '@T6G_MB_LIB.T6G(SCH_1):PAGE354_I126@PURE_QUANTA.Q_CAP_DIFFBUS(CHIPS)':
 '2': CDS_PINID='\2\';
NET_NAME
'P5E_CPU1_P2_TX_DP<3>'
 '@T6G_MB_LIB.T6G(SCH_1):P5E_CPU1_P2_TX_DP'<3>:
 C_SIGNAL='@t6g_mb_lib.t6g(sch_1):p5e_cpu1_p2_tx_dp(3)';
NODE_NAME     U26 BY36
 '@T6G_MB_LIB.T6G(SCH_1):PAGE52_I148@PURE_QUANTA.GENOA_SP5(CHIPS)':
 'P2_TXP3': CDS_PINID='P2_TXP3';
NODE_NAME     C767 2
 '@T6G_MB_LIB.T6G(SCH_1):PAGE354_I128@PURE_QUANTA.Q_CAP_DIFFBUS(CHIPS)':
 '2': CDS_PINID='\2\';
NET_NAME
'P5E_CPU1_P2_TX_DP<4>'
 '@T6G_MB_LIB.T6G(SCH_1):P5E_CPU1_P2_TX_DP'<4>:
 C_SIGNAL='@t6g_mb_lib.t6g(sch_1):p5e_cpu1_p2_tx_dp(4)';
NODE_NAME     U26 BU33
 '@T6G_MB_LIB.T6G(SCH_1):PAGE52_I148@PURE_QUANTA.GENOA_SP5(CHIPS)':
 'P2_TXP4': CDS_PINID='P2_TXP4';
NODE_NAME     C765 2
 '@T6G_MB_LIB.T6G(SCH_1):PAGE354_I131@PURE_QUANTA.Q_CAP_DIFFBUS(CHIPS)':
 '2': CDS_PINID='\2\';
NET_NAME
'P5E_CPU1_P2_TX_DP<5>'
 '@T6G_MB_LIB.T6G(SCH_1):P5E_CPU1_P2_TX_DP'<5>:
 C_SIGNAL='@t6g_mb_lib.t6g(sch_1):p5e_cpu1_p2_tx_dp(5)';
NODE_NAME     U26 CA33
 '@T6G_MB_LIB.T6G(SCH_1):PAGE52_I148@PURE_QUANTA.GENOA_SP5(CHIPS)':
 'P2_TXP5': CDS_PINID='P2_TXP5';
NODE_NAME     C763 2
 '@T6G_MB_LIB.T6G(SCH_1):PAGE354_I135@PURE_QUANTA.Q_CAP_DIFFBUS(CHIPS)':
 '2': CDS_PINID='\2\';
NET_NAME
'P5E_CPU1_P2_TX_DP<6>'
 '@T6G_MB_LIB.T6G(SCH_1):P5E_CPU1_P2_TX_DP'<6>:
 C_SIGNAL='@t6g_mb_lib.t6g(sch_1):p5e_cpu1_p2_tx_dp(6)';
NODE_NAME     U26 BW33
 '@T6G_MB_LIB.T6G(SCH_1):PAGE52_I148@PURE_QUANTA.GENOA_SP5(CHIPS)':
 'P2_TXP6': CDS_PINID='P2_TXP6';
NODE_NAME     C761 2
 '@T6G_MB_LIB.T6G(SCH_1):PAGE354_I137@PURE_QUANTA.Q_CAP_DIFFBUS(CHIPS)':
 '2': CDS_PINID='\2\';
NET_NAME
'P5E_CPU1_P2_TX_DP<7>'
 '@T6G_MB_LIB.T6G(SCH_1):P5E_CPU1_P2_TX_DP'<7>:
 C_SIGNAL='@t6g_mb_lib.t6g(sch_1):p5e_cpu1_p2_tx_dp(7)';
NODE_NAME     U26 BU30
 '@T6G_MB_LIB.T6G(SCH_1):PAGE52_I148@PURE_QUANTA.GENOA_SP5(CHIPS)':
 'P2_TXP7': CDS_PINID='P2_TXP7';
NODE_NAME     C759 2
 '@T6G_MB_LIB.T6G(SCH_1):PAGE354_I139@PURE_QUANTA.Q_CAP_DIFFBUS(CHIPS)':
 '2': CDS_PINID='\2\';
NET_NAME
'P5E_CPU1_P2_TX_DP<8>'
 '@T6G_MB_LIB.T6G(SCH_1):P5E_CPU1_P2_TX_DP'<8>:
 C_SIGNAL='@t6g_mb_lib.t6g(sch_1):p5e_cpu1_p2_tx_dp(8)';
NODE_NAME     U26 CA30
 '@T6G_MB_LIB.T6G(SCH_1):PAGE52_I148@PURE_QUANTA.GENOA_SP5(CHIPS)':
 'P2_TXP8': CDS_PINID='P2_TXP8';
NODE_NAME     C757 2
 '@T6G_MB_LIB.T6G(SCH_1):PAGE354_I155@PURE_QUANTA.Q_CAP_DIFFBUS(CHIPS)':
 '2': CDS_PINID='\2\';
NET_NAME
'P5E_CPU1_P2_TX_DP<9>'
 '@T6G_MB_LIB.T6G(SCH_1):P5E_CPU1_P2_TX_DP'<9>:
 C_SIGNAL='@t6g_mb_lib.t6g(sch_1):p5e_cpu1_p2_tx_dp(9)';
NODE_NAME     U26 BW30
 '@T6G_MB_LIB.T6G(SCH_1):PAGE52_I148@PURE_QUANTA.GENOA_SP5(CHIPS)':
 'P2_TXP9': CDS_PINID='P2_TXP9';
NODE_NAME     C755 2
 '@T6G_MB_LIB.T6G(SCH_1):PAGE354_I156@PURE_QUANTA.Q_CAP_DIFFBUS(CHIPS)':
 '2': CDS_PINID='\2\';
NET_NAME
'P5E_CPU1_P3_RX_BUF_DN<0>'
 '@T6G_MB_LIB.T6G(SCH_1):P5E_CPU1_P3_RX_BUF_DN'<0>:
 C_SIGNAL='@t6g_mb_lib.t6g(sch_1):p5e_cpu1_p3_rx_buf_dn(0)';
NODE_NAME     U6017 EV2
 '@T6G_MB_LIB.T6G(SCH_1):PAGE460_I38@PURE_QUANTA.PT5161LRS(CHIPS)':
 'A_PERN15': CDS_PINID='A_PERN15';
NODE_NAME     J110 F1
 '@T6G_MB_LIB.T6G(SCH_1):PAGE318_I76@PURE_QUANTA.CONN112_10137002101LF(CHIPS)':
 'F1': CDS_PINID='F1';
NET_NAME
'P5E_CPU1_P3_RX_BUF_DN<10>'
 '@T6G_MB_LIB.T6G(SCH_1):P5E_CPU1_P3_RX_BUF_DN'<10>:
 C_SIGNAL='@t6g_mb_lib.t6g(sch_1):p5e_cpu1_p3_rx_buf_dn(10)';
NODE_NAME     U6017 BH2
 '@T6G_MB_LIB.T6G(SCH_1):PAGE460_I1@PURE_QUANTA.PT5161LRS(CHIPS)':
 'A_PERN5': CDS_PINID='A_PERN5';
NODE_NAME     J109 F3
 '@T6G_MB_LIB.T6G(SCH_1):PAGE319_I76@PURE_QUANTA.CONN112_10137002101LF(CHIPS)':
 'F3': CDS_PINID='F3';
NET_NAME
'P5E_CPU1_P3_RX_BUF_DN<11>'
 '@T6G_MB_LIB.T6G(SCH_1):P5E_CPU1_P3_RX_BUF_DN'<11>:
 C_SIGNAL='@t6g_mb_lib.t6g(sch_1):p5e_cpu1_p3_rx_buf_dn(11)';
NODE_NAME     U6017 BA2
 '@T6G_MB_LIB.T6G(SCH_1):PAGE460_I1@PURE_QUANTA.PT5161LRS(CHIPS)':
 'A_PERN4': CDS_PINID='A_PERN4';
NODE_NAME     J109 E4
 '@T6G_MB_LIB.T6G(SCH_1):PAGE319_I76@PURE_QUANTA.CONN112_10137002101LF(CHIPS)':
 'E4': CDS_PINID='E4';
NET_NAME
'P5E_CPU1_P3_RX_BUF_DN<12>'
 '@T6G_MB_LIB.T6G(SCH_1):P5E_CPU1_P3_RX_BUF_DN'<12>:
 C_SIGNAL='@t6g_mb_lib.t6g(sch_1):p5e_cpu1_p3_rx_buf_dn(12)';
NODE_NAME     U6017 AP2
 '@T6G_MB_LIB.T6G(SCH_1):PAGE460_I1@PURE_QUANTA.PT5161LRS(CHIPS)':
 'A_PERN3': CDS_PINID='A_PERN3';
NODE_NAME     J109 F5
 '@T6G_MB_LIB.T6G(SCH_1):PAGE319_I16@PURE_QUANTA.CONN112_10137002101LF(CHIPS)':
 'F5': CDS_PINID='F5';
NET_NAME
'P5E_CPU1_P3_RX_BUF_DN<13>'
 '@T6G_MB_LIB.T6G(SCH_1):P5E_CPU1_P3_RX_BUF_DN'<13>:
 C_SIGNAL='@t6g_mb_lib.t6g(sch_1):p5e_cpu1_p3_rx_buf_dn(13)';
NODE_NAME     U6017 AG2
 '@T6G_MB_LIB.T6G(SCH_1):PAGE460_I1@PURE_QUANTA.PT5161LRS(CHIPS)':
 'A_PERN2': CDS_PINID='A_PERN2';
NODE_NAME     J109 E6
 '@T6G_MB_LIB.T6G(SCH_1):PAGE319_I16@PURE_QUANTA.CONN112_10137002101LF(CHIPS)':
 'E6': CDS_PINID='E6';
NET_NAME
'P5E_CPU1_P3_RX_BUF_DN<14>'
 '@T6G_MB_LIB.T6G(SCH_1):P5E_CPU1_P3_RX_BUF_DN'<14>:
 C_SIGNAL='@t6g_mb_lib.t6g(sch_1):p5e_cpu1_p3_rx_buf_dn(14)';
NODE_NAME     U6017 Y2
 '@T6G_MB_LIB.T6G(SCH_1):PAGE460_I1@PURE_QUANTA.PT5161LRS(CHIPS)':
 'A_PERN1': CDS_PINID='A_PERN1';
NODE_NAME     J109 F7
 '@T6G_MB_LIB.T6G(SCH_1):PAGE319_I16@PURE_QUANTA.CONN112_10137002101LF(CHIPS)':
 'F7': CDS_PINID='F7';
NET_NAME
'P5E_CPU1_P3_RX_BUF_DN<15>'
 '@T6G_MB_LIB.T6G(SCH_1):P5E_CPU1_P3_RX_BUF_DN'<15>:
 C_SIGNAL='@t6g_mb_lib.t6g(sch_1):p5e_cpu1_p3_rx_buf_dn(15)';
NODE_NAME     U6017 N2
 '@T6G_MB_LIB.T6G(SCH_1):PAGE460_I1@PURE_QUANTA.PT5161LRS(CHIPS)':
 'A_PERN0': CDS_PINID='A_PERN0';
NODE_NAME     J109 E8
 '@T6G_MB_LIB.T6G(SCH_1):PAGE319_I16@PURE_QUANTA.CONN112_10137002101LF(CHIPS)':
 'E8': CDS_PINID='E8';
NET_NAME
'P5E_CPU1_P3_RX_BUF_DN<1>'
 '@T6G_MB_LIB.T6G(SCH_1):P5E_CPU1_P3_RX_BUF_DN'<1>:
 C_SIGNAL='@t6g_mb_lib.t6g(sch_1):p5e_cpu1_p3_rx_buf_dn(1)';
NODE_NAME     U6017 EL2
 '@T6G_MB_LIB.T6G(SCH_1):PAGE460_I38@PURE_QUANTA.PT5161LRS(CHIPS)':
 'A_PERN14': CDS_PINID='A_PERN14';
NODE_NAME     J110 E2
 '@T6G_MB_LIB.T6G(SCH_1):PAGE318_I76@PURE_QUANTA.CONN112_10137002101LF(CHIPS)':
 'E2': CDS_PINID='E2';
NET_NAME
'P5E_CPU1_P3_RX_BUF_DN<2>'
 '@T6G_MB_LIB.T6G(SCH_1):P5E_CPU1_P3_RX_BUF_DN'<2>:
 C_SIGNAL='@t6g_mb_lib.t6g(sch_1):p5e_cpu1_p3_rx_buf_dn(2)';
NODE_NAME     U6017 ED2
 '@T6G_MB_LIB.T6G(SCH_1):PAGE460_I38@PURE_QUANTA.PT5161LRS(CHIPS)':
 'A_PERN13': CDS_PINID='A_PERN13';
NODE_NAME     J110 F3
 '@T6G_MB_LIB.T6G(SCH_1):PAGE318_I76@PURE_QUANTA.CONN112_10137002101LF(CHIPS)':
 'F3': CDS_PINID='F3';
NET_NAME
'P5E_CPU1_P3_RX_BUF_DN<3>'
 '@T6G_MB_LIB.T6G(SCH_1):P5E_CPU1_P3_RX_BUF_DN'<3>:
 C_SIGNAL='@t6g_mb_lib.t6g(sch_1):p5e_cpu1_p3_rx_buf_dn(3)';
NODE_NAME     U6017 DU2
 '@T6G_MB_LIB.T6G(SCH_1):PAGE460_I38@PURE_QUANTA.PT5161LRS(CHIPS)':
 'A_PERN12': CDS_PINID='A_PERN12';
NODE_NAME     J110 E4
 '@T6G_MB_LIB.T6G(SCH_1):PAGE318_I76@PURE_QUANTA.CONN112_10137002101LF(CHIPS)':
 'E4': CDS_PINID='E4';
NET_NAME
'P5E_CPU1_P3_RX_BUF_DN<4>'
 '@T6G_MB_LIB.T6G(SCH_1):P5E_CPU1_P3_RX_BUF_DN'<4>:
 C_SIGNAL='@t6g_mb_lib.t6g(sch_1):p5e_cpu1_p3_rx_buf_dn(4)';
NODE_NAME     U6017 DK2
 '@T6G_MB_LIB.T6G(SCH_1):PAGE460_I38@PURE_QUANTA.PT5161LRS(CHIPS)':
 'A_PERN11': CDS_PINID='A_PERN11';
NODE_NAME     J110 F5
 '@T6G_MB_LIB.T6G(SCH_1):PAGE318_I16@PURE_QUANTA.CONN112_10137002101LF(CHIPS)':
 'F5': CDS_PINID='F5';
NET_NAME
'P5E_CPU1_P3_RX_BUF_DN<5>'
 '@T6G_MB_LIB.T6G(SCH_1):P5E_CPU1_P3_RX_BUF_DN'<5>:
 C_SIGNAL='@t6g_mb_lib.t6g(sch_1):p5e_cpu1_p3_rx_buf_dn(5)';
NODE_NAME     U6017 DC2
 '@T6G_MB_LIB.T6G(SCH_1):PAGE460_I38@PURE_QUANTA.PT5161LRS(CHIPS)':
 'A_PERN10': CDS_PINID='A_PERN10';
NODE_NAME     J110 E6
 '@T6G_MB_LIB.T6G(SCH_1):PAGE318_I16@PURE_QUANTA.CONN112_10137002101LF(CHIPS)':
 'E6': CDS_PINID='E6';
NET_NAME
'P5E_CPU1_P3_RX_BUF_DN<6>'
 '@T6G_MB_LIB.T6G(SCH_1):P5E_CPU1_P3_RX_BUF_DN'<6>:
 C_SIGNAL='@t6g_mb_lib.t6g(sch_1):p5e_cpu1_p3_rx_buf_dn(6)';
NODE_NAME     U6017 CT2
 '@T6G_MB_LIB.T6G(SCH_1):PAGE460_I38@PURE_QUANTA.PT5161LRS(CHIPS)':
 'A_PERN9': CDS_PINID='A_PERN9';
NODE_NAME     J110 F7
 '@T6G_MB_LIB.T6G(SCH_1):PAGE318_I16@PURE_QUANTA.CONN112_10137002101LF(CHIPS)':
 'F7': CDS_PINID='F7';
NET_NAME
'P5E_CPU1_P3_RX_BUF_DN<7>'
 '@T6G_MB_LIB.T6G(SCH_1):P5E_CPU1_P3_RX_BUF_DN'<7>:
 C_SIGNAL='@t6g_mb_lib.t6g(sch_1):p5e_cpu1_p3_rx_buf_dn(7)';
NODE_NAME     U6017 CJ2
 '@T6G_MB_LIB.T6G(SCH_1):PAGE460_I38@PURE_QUANTA.PT5161LRS(CHIPS)':
 'A_PERN8': CDS_PINID='A_PERN8';
NODE_NAME     J110 E8
 '@T6G_MB_LIB.T6G(SCH_1):PAGE318_I16@PURE_QUANTA.CONN112_10137002101LF(CHIPS)':
 'E8': CDS_PINID='E8';
NET_NAME
'P5E_CPU1_P3_RX_BUF_DN<8>'
 '@T6G_MB_LIB.T6G(SCH_1):P5E_CPU1_P3_RX_BUF_DN'<8>:
 C_SIGNAL='@t6g_mb_lib.t6g(sch_1):p5e_cpu1_p3_rx_buf_dn(8)';
NODE_NAME     U6017 CB2
 '@T6G_MB_LIB.T6G(SCH_1):PAGE460_I1@PURE_QUANTA.PT5161LRS(CHIPS)':
 'A_PERN7': CDS_PINID='A_PERN7';
NODE_NAME     J109 F1
 '@T6G_MB_LIB.T6G(SCH_1):PAGE319_I76@PURE_QUANTA.CONN112_10137002101LF(CHIPS)':
 'F1': CDS_PINID='F1';
NET_NAME
'P5E_CPU1_P3_RX_BUF_DN<9>'
 '@T6G_MB_LIB.T6G(SCH_1):P5E_CPU1_P3_RX_BUF_DN'<9>:
 C_SIGNAL='@t6g_mb_lib.t6g(sch_1):p5e_cpu1_p3_rx_buf_dn(9)';
NODE_NAME     U6017 BR2
 '@T6G_MB_LIB.T6G(SCH_1):PAGE460_I1@PURE_QUANTA.PT5161LRS(CHIPS)':
 'A_PERN6': CDS_PINID='A_PERN6';
NODE_NAME     J109 E2
 '@T6G_MB_LIB.T6G(SCH_1):PAGE319_I76@PURE_QUANTA.CONN112_10137002101LF(CHIPS)':
 'E2': CDS_PINID='E2';
NET_NAME
'P5E_CPU1_P3_RX_BUF_DP<0>'
 '@T6G_MB_LIB.T6G(SCH_1):P5E_CPU1_P3_RX_BUF_DP'<0>:
 C_SIGNAL='@t6g_mb_lib.t6g(sch_1):p5e_cpu1_p3_rx_buf_dp(0)';
NODE_NAME     U6017 EY1
 '@T6G_MB_LIB.T6G(SCH_1):PAGE460_I38@PURE_QUANTA.PT5161LRS(CHIPS)':
 'A_PERP15': CDS_PINID='A_PERP15';
NODE_NAME     J110 G1
 '@T6G_MB_LIB.T6G(SCH_1):PAGE318_I76@PURE_QUANTA.CONN112_10137002101LF(CHIPS)':
 'G1': CDS_PINID='G1';
NET_NAME
'P5E_CPU1_P3_RX_BUF_DP<10>'
 '@T6G_MB_LIB.T6G(SCH_1):P5E_CPU1_P3_RX_BUF_DP'<10>:
 C_SIGNAL='@t6g_mb_lib.t6g(sch_1):p5e_cpu1_p3_rx_buf_dp(10)';
NODE_NAME     U6017 BK1
 '@T6G_MB_LIB.T6G(SCH_1):PAGE460_I1@PURE_QUANTA.PT5161LRS(CHIPS)':
 'A_PERP5': CDS_PINID='A_PERP5';
NODE_NAME     J109 G3
 '@T6G_MB_LIB.T6G(SCH_1):PAGE319_I76@PURE_QUANTA.CONN112_10137002101LF(CHIPS)':
 'G3': CDS_PINID='G3';
NET_NAME
'P5E_CPU1_P3_RX_BUF_DP<11>'
 '@T6G_MB_LIB.T6G(SCH_1):P5E_CPU1_P3_RX_BUF_DP'<11>:
 C_SIGNAL='@t6g_mb_lib.t6g(sch_1):p5e_cpu1_p3_rx_buf_dp(11)';
NODE_NAME     U6017 BC1
 '@T6G_MB_LIB.T6G(SCH_1):PAGE460_I1@PURE_QUANTA.PT5161LRS(CHIPS)':
 'A_PERP4': CDS_PINID='A_PERP4';
NODE_NAME     J109 F4
 '@T6G_MB_LIB.T6G(SCH_1):PAGE319_I76@PURE_QUANTA.CONN112_10137002101LF(CHIPS)':
 'F4': CDS_PINID='F4';
NET_NAME
'P5E_CPU1_P3_RX_BUF_DP<12>'
 '@T6G_MB_LIB.T6G(SCH_1):P5E_CPU1_P3_RX_BUF_DP'<12>:
 C_SIGNAL='@t6g_mb_lib.t6g(sch_1):p5e_cpu1_p3_rx_buf_dp(12)';
NODE_NAME     U6017 AT1
 '@T6G_MB_LIB.T6G(SCH_1):PAGE460_I1@PURE_QUANTA.PT5161LRS(CHIPS)':
 'A_PERP3': CDS_PINID='A_PERP3';
NODE_NAME     J109 G5
 '@T6G_MB_LIB.T6G(SCH_1):PAGE319_I16@PURE_QUANTA.CONN112_10137002101LF(CHIPS)':
 'G5': CDS_PINID='G5';
NET_NAME
'P5E_CPU1_P3_RX_BUF_DP<13>'
 '@T6G_MB_LIB.T6G(SCH_1):P5E_CPU1_P3_RX_BUF_DP'<13>:
 C_SIGNAL='@t6g_mb_lib.t6g(sch_1):p5e_cpu1_p3_rx_buf_dp(13)';
NODE_NAME     U6017 AJ1
 '@T6G_MB_LIB.T6G(SCH_1):PAGE460_I1@PURE_QUANTA.PT5161LRS(CHIPS)':
 'A_PERP2': CDS_PINID='A_PERP2';
NODE_NAME     J109 F6
 '@T6G_MB_LIB.T6G(SCH_1):PAGE319_I16@PURE_QUANTA.CONN112_10137002101LF(CHIPS)':
 'F6': CDS_PINID='F6';
NET_NAME
'P5E_CPU1_P3_RX_BUF_DP<14>'
 '@T6G_MB_LIB.T6G(SCH_1):P5E_CPU1_P3_RX_BUF_DP'<14>:
 C_SIGNAL='@t6g_mb_lib.t6g(sch_1):p5e_cpu1_p3_rx_buf_dp(14)';
NODE_NAME     U6017 AB1
 '@T6G_MB_LIB.T6G(SCH_1):PAGE460_I1@PURE_QUANTA.PT5161LRS(CHIPS)':
 'A_PERP1': CDS_PINID='A_PERP1';
NODE_NAME     J109 G7
 '@T6G_MB_LIB.T6G(SCH_1):PAGE319_I16@PURE_QUANTA.CONN112_10137002101LF(CHIPS)':
 'G7': CDS_PINID='G7';
NET_NAME
'P5E_CPU1_P3_RX_BUF_DP<15>'
 '@T6G_MB_LIB.T6G(SCH_1):P5E_CPU1_P3_RX_BUF_DP'<15>:
 C_SIGNAL='@t6g_mb_lib.t6g(sch_1):p5e_cpu1_p3_rx_buf_dp(15)';
NODE_NAME     U6017 R1
 '@T6G_MB_LIB.T6G(SCH_1):PAGE460_I1@PURE_QUANTA.PT5161LRS(CHIPS)':
 'A_PERP0': CDS_PINID='A_PERP0';
NODE_NAME     J109 F8
 '@T6G_MB_LIB.T6G(SCH_1):PAGE319_I16@PURE_QUANTA.CONN112_10137002101LF(CHIPS)':
 'F8': CDS_PINID='F8';
NET_NAME
'P5E_CPU1_P3_RX_BUF_DP<1>'
 '@T6G_MB_LIB.T6G(SCH_1):P5E_CPU1_P3_RX_BUF_DP'<1>:
 C_SIGNAL='@t6g_mb_lib.t6g(sch_1):p5e_cpu1_p3_rx_buf_dp(1)';
NODE_NAME     U6017 EN1
 '@T6G_MB_LIB.T6G(SCH_1):PAGE460_I38@PURE_QUANTA.PT5161LRS(CHIPS)':
 'A_PERP14': CDS_PINID='A_PERP14';
NODE_NAME     J110 F2
 '@T6G_MB_LIB.T6G(SCH_1):PAGE318_I76@PURE_QUANTA.CONN112_10137002101LF(CHIPS)':
 'F2': CDS_PINID='F2';
NET_NAME
'P5E_CPU1_P3_RX_BUF_DP<2>'
 '@T6G_MB_LIB.T6G(SCH_1):P5E_CPU1_P3_RX_BUF_DP'<2>:
 C_SIGNAL='@t6g_mb_lib.t6g(sch_1):p5e_cpu1_p3_rx_buf_dp(2)';
NODE_NAME     U6017 EF1
 '@T6G_MB_LIB.T6G(SCH_1):PAGE460_I38@PURE_QUANTA.PT5161LRS(CHIPS)':
 'A_PERP13': CDS_PINID='A_PERP13';
NODE_NAME     J110 G3
 '@T6G_MB_LIB.T6G(SCH_1):PAGE318_I76@PURE_QUANTA.CONN112_10137002101LF(CHIPS)':
 'G3': CDS_PINID='G3';
NET_NAME
'P5E_CPU1_P3_RX_BUF_DP<3>'
 '@T6G_MB_LIB.T6G(SCH_1):P5E_CPU1_P3_RX_BUF_DP'<3>:
 C_SIGNAL='@t6g_mb_lib.t6g(sch_1):p5e_cpu1_p3_rx_buf_dp(3)';
NODE_NAME     U6017 DW1
 '@T6G_MB_LIB.T6G(SCH_1):PAGE460_I38@PURE_QUANTA.PT5161LRS(CHIPS)':
 'A_PERP12': CDS_PINID='A_PERP12';
NODE_NAME     J110 F4
 '@T6G_MB_LIB.T6G(SCH_1):PAGE318_I76@PURE_QUANTA.CONN112_10137002101LF(CHIPS)':
 'F4': CDS_PINID='F4';
NET_NAME
'P5E_CPU1_P3_RX_BUF_DP<4>'
 '@T6G_MB_LIB.T6G(SCH_1):P5E_CPU1_P3_RX_BUF_DP'<4>:
 C_SIGNAL='@t6g_mb_lib.t6g(sch_1):p5e_cpu1_p3_rx_buf_dp(4)';
NODE_NAME     U6017 DM1
 '@T6G_MB_LIB.T6G(SCH_1):PAGE460_I38@PURE_QUANTA.PT5161LRS(CHIPS)':
 'A_PERP11': CDS_PINID='A_PERP11';
NODE_NAME     J110 G5
 '@T6G_MB_LIB.T6G(SCH_1):PAGE318_I16@PURE_QUANTA.CONN112_10137002101LF(CHIPS)':
 'G5': CDS_PINID='G5';
NET_NAME
'P5E_CPU1_P3_RX_BUF_DP<5>'
 '@T6G_MB_LIB.T6G(SCH_1):P5E_CPU1_P3_RX_BUF_DP'<5>:
 C_SIGNAL='@t6g_mb_lib.t6g(sch_1):p5e_cpu1_p3_rx_buf_dp(5)';
NODE_NAME     U6017 DE1
 '@T6G_MB_LIB.T6G(SCH_1):PAGE460_I38@PURE_QUANTA.PT5161LRS(CHIPS)':
 'A_PERP10': CDS_PINID='A_PERP10';
NODE_NAME     J110 F6
 '@T6G_MB_LIB.T6G(SCH_1):PAGE318_I16@PURE_QUANTA.CONN112_10137002101LF(CHIPS)':
 'F6': CDS_PINID='F6';
NET_NAME
'P5E_CPU1_P3_RX_BUF_DP<6>'
 '@T6G_MB_LIB.T6G(SCH_1):P5E_CPU1_P3_RX_BUF_DP'<6>:
 C_SIGNAL='@t6g_mb_lib.t6g(sch_1):p5e_cpu1_p3_rx_buf_dp(6)';
NODE_NAME     U6017 CV1
 '@T6G_MB_LIB.T6G(SCH_1):PAGE460_I38@PURE_QUANTA.PT5161LRS(CHIPS)':
 'A_PERP9': CDS_PINID='A_PERP9';
NODE_NAME     J110 G7
 '@T6G_MB_LIB.T6G(SCH_1):PAGE318_I16@PURE_QUANTA.CONN112_10137002101LF(CHIPS)':
 'G7': CDS_PINID='G7';
NET_NAME
'P5E_CPU1_P3_RX_BUF_DP<7>'
 '@T6G_MB_LIB.T6G(SCH_1):P5E_CPU1_P3_RX_BUF_DP'<7>:
 C_SIGNAL='@t6g_mb_lib.t6g(sch_1):p5e_cpu1_p3_rx_buf_dp(7)';
NODE_NAME     U6017 CL1
 '@T6G_MB_LIB.T6G(SCH_1):PAGE460_I38@PURE_QUANTA.PT5161LRS(CHIPS)':
 'A_PERP8': CDS_PINID='A_PERP8';
NODE_NAME     J110 F8
 '@T6G_MB_LIB.T6G(SCH_1):PAGE318_I16@PURE_QUANTA.CONN112_10137002101LF(CHIPS)':
 'F8': CDS_PINID='F8';
NET_NAME
'P5E_CPU1_P3_RX_BUF_DP<8>'
 '@T6G_MB_LIB.T6G(SCH_1):P5E_CPU1_P3_RX_BUF_DP'<8>:
 C_SIGNAL='@t6g_mb_lib.t6g(sch_1):p5e_cpu1_p3_rx_buf_dp(8)';
NODE_NAME     U6017 CD1
 '@T6G_MB_LIB.T6G(SCH_1):PAGE460_I1@PURE_QUANTA.PT5161LRS(CHIPS)':
 'A_PERP7': CDS_PINID='A_PERP7';
NODE_NAME     J109 G1
 '@T6G_MB_LIB.T6G(SCH_1):PAGE319_I76@PURE_QUANTA.CONN112_10137002101LF(CHIPS)':
 'G1': CDS_PINID='G1';
NET_NAME
'P5E_CPU1_P3_RX_BUF_DP<9>'
 '@T6G_MB_LIB.T6G(SCH_1):P5E_CPU1_P3_RX_BUF_DP'<9>:
 C_SIGNAL='@t6g_mb_lib.t6g(sch_1):p5e_cpu1_p3_rx_buf_dp(9)';
NODE_NAME     U6017 BU1
 '@T6G_MB_LIB.T6G(SCH_1):PAGE460_I1@PURE_QUANTA.PT5161LRS(CHIPS)':
 'A_PERP6': CDS_PINID='A_PERP6';
NODE_NAME     J109 F2
 '@T6G_MB_LIB.T6G(SCH_1):PAGE319_I76@PURE_QUANTA.CONN112_10137002101LF(CHIPS)':
 'F2': CDS_PINID='F2';
NET_NAME
'P5E_CPU1_P3_RX_DN<0>'
 '@T6G_MB_LIB.T6G(SCH_1):P5E_CPU1_P3_RX_DN'<0>:
 C_SIGNAL='@t6g_mb_lib.t6g(sch_1):p5e_cpu1_p3_rx_dn(0)';
NODE_NAME     U26 CV36
 '@T6G_MB_LIB.T6G(SCH_1):PAGE52_I147@PURE_QUANTA.GENOA_SP5(CHIPS)':
 'P3_RXN0': CDS_PINID='P3_RXN0';
NODE_NAME     U6017 EW29
 '@T6G_MB_LIB.T6G(SCH_1):PAGE459_I38@PURE_QUANTA.PT5161LRS(CHIPS)':
 'A_PETN15': CDS_PINID='A_PETN15';
NET_NAME
'P5E_CPU1_P3_RX_DN<10>'
 '@T6G_MB_LIB.T6G(SCH_1):P5E_CPU1_P3_RX_DN'<10>:
 C_SIGNAL='@t6g_mb_lib.t6g(sch_1):p5e_cpu1_p3_rx_dn(10)';
NODE_NAME     U26 DC27
 '@T6G_MB_LIB.T6G(SCH_1):PAGE52_I147@PURE_QUANTA.GENOA_SP5(CHIPS)':
 'P3_RXN10': CDS_PINID='P3_RXN10';
NODE_NAME     U6017 BJ29
 '@T6G_MB_LIB.T6G(SCH_1):PAGE459_I1@PURE_QUANTA.PT5161LRS(CHIPS)':
 'A_PETN5': CDS_PINID='A_PETN5';
NET_NAME
'P5E_CPU1_P3_RX_DN<11>'
 '@T6G_MB_LIB.T6G(SCH_1):P5E_CPU1_P3_RX_DN'<11>:
 C_SIGNAL='@t6g_mb_lib.t6g(sch_1):p5e_cpu1_p3_rx_dn(11)';
NODE_NAME     U26 DA27
 '@T6G_MB_LIB.T6G(SCH_1):PAGE52_I147@PURE_QUANTA.GENOA_SP5(CHIPS)':
 'P3_RXN11': CDS_PINID='P3_RXN11';
NODE_NAME     U6017 BB29
 '@T6G_MB_LIB.T6G(SCH_1):PAGE459_I1@PURE_QUANTA.PT5161LRS(CHIPS)':
 'A_PETN4': CDS_PINID='A_PETN4';
NET_NAME
'P5E_CPU1_P3_RX_DN<12>'
 '@T6G_MB_LIB.T6G(SCH_1):P5E_CPU1_P3_RX_DN'<12>:
 C_SIGNAL='@t6g_mb_lib.t6g(sch_1):p5e_cpu1_p3_rx_dn(12)';
NODE_NAME     U26 CW24
 '@T6G_MB_LIB.T6G(SCH_1):PAGE52_I147@PURE_QUANTA.GENOA_SP5(CHIPS)':
 'P3_RXN12': CDS_PINID='P3_RXN12';
NODE_NAME     U6017 AR29
 '@T6G_MB_LIB.T6G(SCH_1):PAGE459_I1@PURE_QUANTA.PT5161LRS(CHIPS)':
 'A_PETN3': CDS_PINID='A_PETN3';
NET_NAME
'P5E_CPU1_P3_RX_DN<13>'
 '@T6G_MB_LIB.T6G(SCH_1):P5E_CPU1_P3_RX_DN'<13>:
 C_SIGNAL='@t6g_mb_lib.t6g(sch_1):p5e_cpu1_p3_rx_dn(13)';
NODE_NAME     U26 DC24
 '@T6G_MB_LIB.T6G(SCH_1):PAGE52_I147@PURE_QUANTA.GENOA_SP5(CHIPS)':
 'P3_RXN13': CDS_PINID='P3_RXN13';
NODE_NAME     U6017 AH29
 '@T6G_MB_LIB.T6G(SCH_1):PAGE459_I1@PURE_QUANTA.PT5161LRS(CHIPS)':
 'A_PETN2': CDS_PINID='A_PETN2';
NET_NAME
'P5E_CPU1_P3_RX_DN<14>'
 '@T6G_MB_LIB.T6G(SCH_1):P5E_CPU1_P3_RX_DN'<14>:
 C_SIGNAL='@t6g_mb_lib.t6g(sch_1):p5e_cpu1_p3_rx_dn(14)';
NODE_NAME     U26 DA24
 '@T6G_MB_LIB.T6G(SCH_1):PAGE52_I147@PURE_QUANTA.GENOA_SP5(CHIPS)':
 'P3_RXN14': CDS_PINID='P3_RXN14';
NODE_NAME     U6017 AA29
 '@T6G_MB_LIB.T6G(SCH_1):PAGE459_I1@PURE_QUANTA.PT5161LRS(CHIPS)':
 'A_PETN1': CDS_PINID='A_PETN1';
NET_NAME
'P5E_CPU1_P3_RX_DN<15>'
 '@T6G_MB_LIB.T6G(SCH_1):P5E_CPU1_P3_RX_DN'<15>:
 C_SIGNAL='@t6g_mb_lib.t6g(sch_1):p5e_cpu1_p3_rx_dn(15)';
NODE_NAME     U26 CU24
 '@T6G_MB_LIB.T6G(SCH_1):PAGE52_I147@PURE_QUANTA.GENOA_SP5(CHIPS)':
 'P3_RXN15': CDS_PINID='P3_RXN15';
NODE_NAME     U6017 P29
 '@T6G_MB_LIB.T6G(SCH_1):PAGE459_I1@PURE_QUANTA.PT5161LRS(CHIPS)':
 'A_PETN0': CDS_PINID='A_PETN0';
NET_NAME
'P5E_CPU1_P3_RX_DN<1>'
 '@T6G_MB_LIB.T6G(SCH_1):P5E_CPU1_P3_RX_DN'<1>:
 C_SIGNAL='@t6g_mb_lib.t6g(sch_1):p5e_cpu1_p3_rx_dn(1)';
NODE_NAME     U26 CY36
 '@T6G_MB_LIB.T6G(SCH_1):PAGE52_I147@PURE_QUANTA.GENOA_SP5(CHIPS)':
 'P3_RXN1': CDS_PINID='P3_RXN1';
NODE_NAME     U6017 EM29
 '@T6G_MB_LIB.T6G(SCH_1):PAGE459_I38@PURE_QUANTA.PT5161LRS(CHIPS)':
 'A_PETN14': CDS_PINID='A_PETN14';
NET_NAME
'P5E_CPU1_P3_RX_DN<2>'
 '@T6G_MB_LIB.T6G(SCH_1):P5E_CPU1_P3_RX_DN'<2>:
 C_SIGNAL='@t6g_mb_lib.t6g(sch_1):p5e_cpu1_p3_rx_dn(2)';
NODE_NAME     U26 DB36
 '@T6G_MB_LIB.T6G(SCH_1):PAGE52_I147@PURE_QUANTA.GENOA_SP5(CHIPS)':
 'P3_RXN2': CDS_PINID='P3_RXN2';
NODE_NAME     U6017 EE29
 '@T6G_MB_LIB.T6G(SCH_1):PAGE459_I38@PURE_QUANTA.PT5161LRS(CHIPS)':
 'A_PETN13': CDS_PINID='A_PETN13';
NET_NAME
'P5E_CPU1_P3_RX_DN<3>'
 '@T6G_MB_LIB.T6G(SCH_1):P5E_CPU1_P3_RX_DN'<3>:
 C_SIGNAL='@t6g_mb_lib.t6g(sch_1):p5e_cpu1_p3_rx_dn(3)';
NODE_NAME     U26 CW33
 '@T6G_MB_LIB.T6G(SCH_1):PAGE52_I147@PURE_QUANTA.GENOA_SP5(CHIPS)':
 'P3_RXN3': CDS_PINID='P3_RXN3';
NODE_NAME     U6017 DV29
 '@T6G_MB_LIB.T6G(SCH_1):PAGE459_I38@PURE_QUANTA.PT5161LRS(CHIPS)':
 'A_PETN12': CDS_PINID='A_PETN12';
NET_NAME
'P5E_CPU1_P3_RX_DN<4>'
 '@T6G_MB_LIB.T6G(SCH_1):P5E_CPU1_P3_RX_DN'<4>:
 C_SIGNAL='@t6g_mb_lib.t6g(sch_1):p5e_cpu1_p3_rx_dn(4)';
NODE_NAME     U26 DC33
 '@T6G_MB_LIB.T6G(SCH_1):PAGE52_I147@PURE_QUANTA.GENOA_SP5(CHIPS)':
 'P3_RXN4': CDS_PINID='P3_RXN4';
NODE_NAME     U6017 DL29
 '@T6G_MB_LIB.T6G(SCH_1):PAGE459_I38@PURE_QUANTA.PT5161LRS(CHIPS)':
 'A_PETN11': CDS_PINID='A_PETN11';
NET_NAME
'P5E_CPU1_P3_RX_DN<5>'
 '@T6G_MB_LIB.T6G(SCH_1):P5E_CPU1_P3_RX_DN'<5>:
 C_SIGNAL='@t6g_mb_lib.t6g(sch_1):p5e_cpu1_p3_rx_dn(5)';
NODE_NAME     U26 DA33
 '@T6G_MB_LIB.T6G(SCH_1):PAGE52_I147@PURE_QUANTA.GENOA_SP5(CHIPS)':
 'P3_RXN5': CDS_PINID='P3_RXN5';
NODE_NAME     U6017 DD29
 '@T6G_MB_LIB.T6G(SCH_1):PAGE459_I38@PURE_QUANTA.PT5161LRS(CHIPS)':
 'A_PETN10': CDS_PINID='A_PETN10';
NET_NAME
'P5E_CPU1_P3_RX_DN<6>'
 '@T6G_MB_LIB.T6G(SCH_1):P5E_CPU1_P3_RX_DN'<6>:
 C_SIGNAL='@t6g_mb_lib.t6g(sch_1):p5e_cpu1_p3_rx_dn(6)';
NODE_NAME     U26 CW30
 '@T6G_MB_LIB.T6G(SCH_1):PAGE52_I147@PURE_QUANTA.GENOA_SP5(CHIPS)':
 'P3_RXN6': CDS_PINID='P3_RXN6';
NODE_NAME     U6017 CU29
 '@T6G_MB_LIB.T6G(SCH_1):PAGE459_I38@PURE_QUANTA.PT5161LRS(CHIPS)':
 'A_PETN9': CDS_PINID='A_PETN9';
NET_NAME
'P5E_CPU1_P3_RX_DN<7>'
 '@T6G_MB_LIB.T6G(SCH_1):P5E_CPU1_P3_RX_DN'<7>:
 C_SIGNAL='@t6g_mb_lib.t6g(sch_1):p5e_cpu1_p3_rx_dn(7)';
NODE_NAME     U26 DC30
 '@T6G_MB_LIB.T6G(SCH_1):PAGE52_I147@PURE_QUANTA.GENOA_SP5(CHIPS)':
 'P3_RXN7': CDS_PINID='P3_RXN7';
NODE_NAME     U6017 CK29
 '@T6G_MB_LIB.T6G(SCH_1):PAGE459_I38@PURE_QUANTA.PT5161LRS(CHIPS)':
 'A_PETN8': CDS_PINID='A_PETN8';
NET_NAME
'P5E_CPU1_P3_RX_DN<8>'
 '@T6G_MB_LIB.T6G(SCH_1):P5E_CPU1_P3_RX_DN'<8>:
 C_SIGNAL='@t6g_mb_lib.t6g(sch_1):p5e_cpu1_p3_rx_dn(8)';
NODE_NAME     U26 DA30
 '@T6G_MB_LIB.T6G(SCH_1):PAGE52_I147@PURE_QUANTA.GENOA_SP5(CHIPS)':
 'P3_RXN8': CDS_PINID='P3_RXN8';
NODE_NAME     U6017 CC29
 '@T6G_MB_LIB.T6G(SCH_1):PAGE459_I1@PURE_QUANTA.PT5161LRS(CHIPS)':
 'A_PETN7': CDS_PINID='A_PETN7';
NET_NAME
'P5E_CPU1_P3_RX_DN<9>'
 '@T6G_MB_LIB.T6G(SCH_1):P5E_CPU1_P3_RX_DN'<9>:
 C_SIGNAL='@t6g_mb_lib.t6g(sch_1):p5e_cpu1_p3_rx_dn(9)';
NODE_NAME     U26 CW27
 '@T6G_MB_LIB.T6G(SCH_1):PAGE52_I147@PURE_QUANTA.GENOA_SP5(CHIPS)':
 'P3_RXN9': CDS_PINID='P3_RXN9';
NODE_NAME     U6017 BT29
 '@T6G_MB_LIB.T6G(SCH_1):PAGE459_I1@PURE_QUANTA.PT5161LRS(CHIPS)':
 'A_PETN6': CDS_PINID='A_PETN6';
NET_NAME
'P5E_CPU1_P3_RX_DP<0>'
 '@T6G_MB_LIB.T6G(SCH_1):P5E_CPU1_P3_RX_DP'<0>:
 C_SIGNAL='@t6g_mb_lib.t6g(sch_1):p5e_cpu1_p3_rx_dp(0)';
NODE_NAME     U26 CV35
 '@T6G_MB_LIB.T6G(SCH_1):PAGE52_I147@PURE_QUANTA.GENOA_SP5(CHIPS)':
 'P3_RXP0': CDS_PINID='P3_RXP0';
NODE_NAME     U6017 EU26
 '@T6G_MB_LIB.T6G(SCH_1):PAGE459_I38@PURE_QUANTA.PT5161LRS(CHIPS)':
 'A_PETP15': CDS_PINID='A_PETP15';
NET_NAME
'P5E_CPU1_P3_RX_DP<10>'
 '@T6G_MB_LIB.T6G(SCH_1):P5E_CPU1_P3_RX_DP'<10>:
 C_SIGNAL='@t6g_mb_lib.t6g(sch_1):p5e_cpu1_p3_rx_dp(10)';
NODE_NAME     U26 DC26
 '@T6G_MB_LIB.T6G(SCH_1):PAGE52_I147@PURE_QUANTA.GENOA_SP5(CHIPS)':
 'P3_RXP10': CDS_PINID='P3_RXP10';
NODE_NAME     U6017 BG26
 '@T6G_MB_LIB.T6G(SCH_1):PAGE459_I1@PURE_QUANTA.PT5161LRS(CHIPS)':
 'A_PETP5': CDS_PINID='A_PETP5';
NET_NAME
'P5E_CPU1_P3_RX_DP<11>'
 '@T6G_MB_LIB.T6G(SCH_1):P5E_CPU1_P3_RX_DP'<11>:
 C_SIGNAL='@t6g_mb_lib.t6g(sch_1):p5e_cpu1_p3_rx_dp(11)';
NODE_NAME     U26 DA26
 '@T6G_MB_LIB.T6G(SCH_1):PAGE52_I147@PURE_QUANTA.GENOA_SP5(CHIPS)':
 'P3_RXP11': CDS_PINID='P3_RXP11';
NODE_NAME     U6017 AY26
 '@T6G_MB_LIB.T6G(SCH_1):PAGE459_I1@PURE_QUANTA.PT5161LRS(CHIPS)':
 'A_PETP4': CDS_PINID='A_PETP4';
NET_NAME
'P5E_CPU1_P3_RX_DP<12>'
 '@T6G_MB_LIB.T6G(SCH_1):P5E_CPU1_P3_RX_DP'<12>:
 C_SIGNAL='@t6g_mb_lib.t6g(sch_1):p5e_cpu1_p3_rx_dp(12)';
NODE_NAME     U26 CW23
 '@T6G_MB_LIB.T6G(SCH_1):PAGE52_I147@PURE_QUANTA.GENOA_SP5(CHIPS)':
 'P3_RXP12': CDS_PINID='P3_RXP12';
NODE_NAME     U6017 AN26
 '@T6G_MB_LIB.T6G(SCH_1):PAGE459_I1@PURE_QUANTA.PT5161LRS(CHIPS)':
 'A_PETP3': CDS_PINID='A_PETP3';
NET_NAME
'P5E_CPU1_P3_RX_DP<13>'
 '@T6G_MB_LIB.T6G(SCH_1):P5E_CPU1_P3_RX_DP'<13>:
 C_SIGNAL='@t6g_mb_lib.t6g(sch_1):p5e_cpu1_p3_rx_dp(13)';
NODE_NAME     U26 DC23
 '@T6G_MB_LIB.T6G(SCH_1):PAGE52_I147@PURE_QUANTA.GENOA_SP5(CHIPS)':
 'P3_RXP13': CDS_PINID='P3_RXP13';
NODE_NAME     U6017 AF26
 '@T6G_MB_LIB.T6G(SCH_1):PAGE459_I1@PURE_QUANTA.PT5161LRS(CHIPS)':
 'A_PETP2': CDS_PINID='A_PETP2';
NET_NAME
'P5E_CPU1_P3_RX_DP<14>'
 '@T6G_MB_LIB.T6G(SCH_1):P5E_CPU1_P3_RX_DP'<14>:
 C_SIGNAL='@t6g_mb_lib.t6g(sch_1):p5e_cpu1_p3_rx_dp(14)';
NODE_NAME     U26 DA23
 '@T6G_MB_LIB.T6G(SCH_1):PAGE52_I147@PURE_QUANTA.GENOA_SP5(CHIPS)':
 'P3_RXP14': CDS_PINID='P3_RXP14';
NODE_NAME     U6017 W26
 '@T6G_MB_LIB.T6G(SCH_1):PAGE459_I1@PURE_QUANTA.PT5161LRS(CHIPS)':
 'A_PETP1': CDS_PINID='A_PETP1';
NET_NAME
'P5E_CPU1_P3_RX_DP<15>'
 '@T6G_MB_LIB.T6G(SCH_1):P5E_CPU1_P3_RX_DP'<15>:
 C_SIGNAL='@t6g_mb_lib.t6g(sch_1):p5e_cpu1_p3_rx_dp(15)';
NODE_NAME     U26 CU23
 '@T6G_MB_LIB.T6G(SCH_1):PAGE52_I147@PURE_QUANTA.GENOA_SP5(CHIPS)':
 'P3_RXP15': CDS_PINID='P3_RXP15';
NODE_NAME     U6017 M26
 '@T6G_MB_LIB.T6G(SCH_1):PAGE459_I1@PURE_QUANTA.PT5161LRS(CHIPS)':
 'A_PETP0': CDS_PINID='A_PETP0';
NET_NAME
'P5E_CPU1_P3_RX_DP<1>'
 '@T6G_MB_LIB.T6G(SCH_1):P5E_CPU1_P3_RX_DP'<1>:
 C_SIGNAL='@t6g_mb_lib.t6g(sch_1):p5e_cpu1_p3_rx_dp(1)';
NODE_NAME     U26 CY35
 '@T6G_MB_LIB.T6G(SCH_1):PAGE52_I147@PURE_QUANTA.GENOA_SP5(CHIPS)':
 'P3_RXP1': CDS_PINID='P3_RXP1';
NODE_NAME     U6017 EK26
 '@T6G_MB_LIB.T6G(SCH_1):PAGE459_I38@PURE_QUANTA.PT5161LRS(CHIPS)':
 'A_PETP14': CDS_PINID='A_PETP14';
NET_NAME
'P5E_CPU1_P3_RX_DP<2>'
 '@T6G_MB_LIB.T6G(SCH_1):P5E_CPU1_P3_RX_DP'<2>:
 C_SIGNAL='@t6g_mb_lib.t6g(sch_1):p5e_cpu1_p3_rx_dp(2)';
NODE_NAME     U26 DB35
 '@T6G_MB_LIB.T6G(SCH_1):PAGE52_I147@PURE_QUANTA.GENOA_SP5(CHIPS)':
 'P3_RXP2': CDS_PINID='P3_RXP2';
NODE_NAME     U6017 EC26
 '@T6G_MB_LIB.T6G(SCH_1):PAGE459_I38@PURE_QUANTA.PT5161LRS(CHIPS)':
 'A_PETP13': CDS_PINID='A_PETP13';
NET_NAME
'P5E_CPU1_P3_RX_DP<3>'
 '@T6G_MB_LIB.T6G(SCH_1):P5E_CPU1_P3_RX_DP'<3>:
 C_SIGNAL='@t6g_mb_lib.t6g(sch_1):p5e_cpu1_p3_rx_dp(3)';
NODE_NAME     U26 CW32
 '@T6G_MB_LIB.T6G(SCH_1):PAGE52_I147@PURE_QUANTA.GENOA_SP5(CHIPS)':
 'P3_RXP3': CDS_PINID='P3_RXP3';
NODE_NAME     U6017 DT26
 '@T6G_MB_LIB.T6G(SCH_1):PAGE459_I38@PURE_QUANTA.PT5161LRS(CHIPS)':
 'A_PETP12': CDS_PINID='A_PETP12';
NET_NAME
'P5E_CPU1_P3_RX_DP<4>'
 '@T6G_MB_LIB.T6G(SCH_1):P5E_CPU1_P3_RX_DP'<4>:
 C_SIGNAL='@t6g_mb_lib.t6g(sch_1):p5e_cpu1_p3_rx_dp(4)';
NODE_NAME     U26 DC32
 '@T6G_MB_LIB.T6G(SCH_1):PAGE52_I147@PURE_QUANTA.GENOA_SP5(CHIPS)':
 'P3_RXP4': CDS_PINID='P3_RXP4';
NODE_NAME     U6017 DJ26
 '@T6G_MB_LIB.T6G(SCH_1):PAGE459_I38@PURE_QUANTA.PT5161LRS(CHIPS)':
 'A_PETP11': CDS_PINID='A_PETP11';
NET_NAME
'P5E_CPU1_P3_RX_DP<5>'
 '@T6G_MB_LIB.T6G(SCH_1):P5E_CPU1_P3_RX_DP'<5>:
 C_SIGNAL='@t6g_mb_lib.t6g(sch_1):p5e_cpu1_p3_rx_dp(5)';
NODE_NAME     U26 DA32
 '@T6G_MB_LIB.T6G(SCH_1):PAGE52_I147@PURE_QUANTA.GENOA_SP5(CHIPS)':
 'P3_RXP5': CDS_PINID='P3_RXP5';
NODE_NAME     U6017 DB26
 '@T6G_MB_LIB.T6G(SCH_1):PAGE459_I38@PURE_QUANTA.PT5161LRS(CHIPS)':
 'A_PETP10': CDS_PINID='A_PETP10';
NET_NAME
'P5E_CPU1_P3_RX_DP<6>'
 '@T6G_MB_LIB.T6G(SCH_1):P5E_CPU1_P3_RX_DP'<6>:
 C_SIGNAL='@t6g_mb_lib.t6g(sch_1):p5e_cpu1_p3_rx_dp(6)';
NODE_NAME     U26 CW29
 '@T6G_MB_LIB.T6G(SCH_1):PAGE52_I147@PURE_QUANTA.GENOA_SP5(CHIPS)':
 'P3_RXP6': CDS_PINID='P3_RXP6';
NODE_NAME     U6017 CR26
 '@T6G_MB_LIB.T6G(SCH_1):PAGE459_I38@PURE_QUANTA.PT5161LRS(CHIPS)':
 'A_PETP9': CDS_PINID='A_PETP9';
NET_NAME
'P5E_CPU1_P3_RX_DP<7>'
 '@T6G_MB_LIB.T6G(SCH_1):P5E_CPU1_P3_RX_DP'<7>:
 C_SIGNAL='@t6g_mb_lib.t6g(sch_1):p5e_cpu1_p3_rx_dp(7)';
NODE_NAME     U26 DC29
 '@T6G_MB_LIB.T6G(SCH_1):PAGE52_I147@PURE_QUANTA.GENOA_SP5(CHIPS)':
 'P3_RXP7': CDS_PINID='P3_RXP7';
NODE_NAME     U6017 CH26
 '@T6G_MB_LIB.T6G(SCH_1):PAGE459_I38@PURE_QUANTA.PT5161LRS(CHIPS)':
 'A_PETP8': CDS_PINID='A_PETP8';
NET_NAME
'P5E_CPU1_P3_RX_DP<8>'
 '@T6G_MB_LIB.T6G(SCH_1):P5E_CPU1_P3_RX_DP'<8>:
 C_SIGNAL='@t6g_mb_lib.t6g(sch_1):p5e_cpu1_p3_rx_dp(8)';
NODE_NAME     U26 DA29
 '@T6G_MB_LIB.T6G(SCH_1):PAGE52_I147@PURE_QUANTA.GENOA_SP5(CHIPS)':
 'P3_RXP8': CDS_PINID='P3_RXP8';
NODE_NAME     U6017 CA26
 '@T6G_MB_LIB.T6G(SCH_1):PAGE459_I1@PURE_QUANTA.PT5161LRS(CHIPS)':
 'A_PETP7': CDS_PINID='A_PETP7';
NET_NAME
'P5E_CPU1_P3_RX_DP<9>'
 '@T6G_MB_LIB.T6G(SCH_1):P5E_CPU1_P3_RX_DP'<9>:
 C_SIGNAL='@t6g_mb_lib.t6g(sch_1):p5e_cpu1_p3_rx_dp(9)';
NODE_NAME     U26 CW26
 '@T6G_MB_LIB.T6G(SCH_1):PAGE52_I147@PURE_QUANTA.GENOA_SP5(CHIPS)':
 'P3_RXP9': CDS_PINID='P3_RXP9';
NODE_NAME     U6017 BP26
 '@T6G_MB_LIB.T6G(SCH_1):PAGE459_I1@PURE_QUANTA.PT5161LRS(CHIPS)':
 'A_PETP6': CDS_PINID='A_PETP6';
NET_NAME
'P5E_CPU1_P3_TX_BUF_C_DN<0>'
 '@T6G_MB_LIB.T6G(SCH_1):P5E_CPU1_P3_TX_BUF_C_DN'<0>:
 C_SIGNAL='@t6g_mb_lib.t6g(sch_1):p5e_cpu1_p3_tx_buf_c_dn(0)';
NODE_NAME     C6726 1
 '@T6G_MB_LIB.T6G(SCH_1):PAGE461_I47@PURE_QUANTA.Q_CAP_DIFFBUS(CHIPS)':
 '1': CDS_PINID='\1\';
NODE_NAME     J110 L1
 '@T6G_MB_LIB.T6G(SCH_1):PAGE318_I76@PURE_QUANTA.CONN112_10137002101LF(CHIPS)':
 'L1': CDS_PINID='L1';
NET_NAME
'P5E_CPU1_P3_TX_BUF_C_DN<10>'
 '@T6G_MB_LIB.T6G(SCH_1):P5E_CPU1_P3_TX_BUF_C_DN'<10>:
 C_SIGNAL='@t6g_mb_lib.t6g(sch_1):p5e_cpu1_p3_tx_buf_c_dn(10)';
NODE_NAME     C6746 1
 '@T6G_MB_LIB.T6G(SCH_1):PAGE461_I98@PURE_QUANTA.Q_CAP_DIFFBUS(CHIPS)':
 '1': CDS_PINID='\1\';
NODE_NAME     J109 L3
 '@T6G_MB_LIB.T6G(SCH_1):PAGE319_I76@PURE_QUANTA.CONN112_10137002101LF(CHIPS)':
 'L3': CDS_PINID='L3';
NET_NAME
'P5E_CPU1_P3_TX_BUF_C_DN<11>'
 '@T6G_MB_LIB.T6G(SCH_1):P5E_CPU1_P3_TX_BUF_C_DN'<11>:
 C_SIGNAL='@t6g_mb_lib.t6g(sch_1):p5e_cpu1_p3_tx_buf_c_dn(11)';
NODE_NAME     C6748 1
 '@T6G_MB_LIB.T6G(SCH_1):PAGE461_I96@PURE_QUANTA.Q_CAP_DIFFBUS(CHIPS)':
 '1': CDS_PINID='\1\';
NODE_NAME     J109 K4
 '@T6G_MB_LIB.T6G(SCH_1):PAGE319_I76@PURE_QUANTA.CONN112_10137002101LF(CHIPS)':
 'K4': CDS_PINID='K4';
NET_NAME
'P5E_CPU1_P3_TX_BUF_C_DN<12>'
 '@T6G_MB_LIB.T6G(SCH_1):P5E_CPU1_P3_TX_BUF_C_DN'<12>:
 C_SIGNAL='@t6g_mb_lib.t6g(sch_1):p5e_cpu1_p3_tx_buf_c_dn(12)';
NODE_NAME     C6750 1
 '@T6G_MB_LIB.T6G(SCH_1):PAGE461_I94@PURE_QUANTA.Q_CAP_DIFFBUS(CHIPS)':
 '1': CDS_PINID='\1\';
NODE_NAME     J109 L5
 '@T6G_MB_LIB.T6G(SCH_1):PAGE319_I16@PURE_QUANTA.CONN112_10137002101LF(CHIPS)':
 'L5': CDS_PINID='L5';
NET_NAME
'P5E_CPU1_P3_TX_BUF_C_DN<13>'
 '@T6G_MB_LIB.T6G(SCH_1):P5E_CPU1_P3_TX_BUF_C_DN'<13>:
 C_SIGNAL='@t6g_mb_lib.t6g(sch_1):p5e_cpu1_p3_tx_buf_c_dn(13)';
NODE_NAME     C6752 1
 '@T6G_MB_LIB.T6G(SCH_1):PAGE461_I92@PURE_QUANTA.Q_CAP_DIFFBUS(CHIPS)':
 '1': CDS_PINID='\1\';
NODE_NAME     J109 K6
 '@T6G_MB_LIB.T6G(SCH_1):PAGE319_I16@PURE_QUANTA.CONN112_10137002101LF(CHIPS)':
 'K6': CDS_PINID='K6';
NET_NAME
'P5E_CPU1_P3_TX_BUF_C_DN<14>'
 '@T6G_MB_LIB.T6G(SCH_1):P5E_CPU1_P3_TX_BUF_C_DN'<14>:
 C_SIGNAL='@t6g_mb_lib.t6g(sch_1):p5e_cpu1_p3_tx_buf_c_dn(14)';
NODE_NAME     C6754 1
 '@T6G_MB_LIB.T6G(SCH_1):PAGE461_I90@PURE_QUANTA.Q_CAP_DIFFBUS(CHIPS)':
 '1': CDS_PINID='\1\';
NODE_NAME     J109 L7
 '@T6G_MB_LIB.T6G(SCH_1):PAGE319_I16@PURE_QUANTA.CONN112_10137002101LF(CHIPS)':
 'L7': CDS_PINID='L7';
NET_NAME
'P5E_CPU1_P3_TX_BUF_C_DN<15>'
 '@T6G_MB_LIB.T6G(SCH_1):P5E_CPU1_P3_TX_BUF_C_DN'<15>:
 C_SIGNAL='@t6g_mb_lib.t6g(sch_1):p5e_cpu1_p3_tx_buf_c_dn(15)';
NODE_NAME     C6756 1
 '@T6G_MB_LIB.T6G(SCH_1):PAGE461_I88@PURE_QUANTA.Q_CAP_DIFFBUS(CHIPS)':
 '1': CDS_PINID='\1\';
NODE_NAME     J109 K8
 '@T6G_MB_LIB.T6G(SCH_1):PAGE319_I16@PURE_QUANTA.CONN112_10137002101LF(CHIPS)':
 'K8': CDS_PINID='K8';
NET_NAME
'P5E_CPU1_P3_TX_BUF_C_DN<1>'
 '@T6G_MB_LIB.T6G(SCH_1):P5E_CPU1_P3_TX_BUF_C_DN'<1>:
 C_SIGNAL='@t6g_mb_lib.t6g(sch_1):p5e_cpu1_p3_tx_buf_c_dn(1)';
NODE_NAME     C6728 1
 '@T6G_MB_LIB.T6G(SCH_1):PAGE461_I30@PURE_QUANTA.Q_CAP_DIFFBUS(CHIPS)':
 '1': CDS_PINID='\1\';
NODE_NAME     J110 K2
 '@T6G_MB_LIB.T6G(SCH_1):PAGE318_I76@PURE_QUANTA.CONN112_10137002101LF(CHIPS)':
 'K2': CDS_PINID='K2';
NET_NAME
'P5E_CPU1_P3_TX_BUF_C_DN<2>'
 '@T6G_MB_LIB.T6G(SCH_1):P5E_CPU1_P3_TX_BUF_C_DN'<2>:
 C_SIGNAL='@t6g_mb_lib.t6g(sch_1):p5e_cpu1_p3_tx_buf_c_dn(2)';
NODE_NAME     C6730 1
 '@T6G_MB_LIB.T6G(SCH_1):PAGE461_I29@PURE_QUANTA.Q_CAP_DIFFBUS(CHIPS)':
 '1': CDS_PINID='\1\';
NODE_NAME     J110 L3
 '@T6G_MB_LIB.T6G(SCH_1):PAGE318_I76@PURE_QUANTA.CONN112_10137002101LF(CHIPS)':
 'L3': CDS_PINID='L3';
NET_NAME
'P5E_CPU1_P3_TX_BUF_C_DN<3>'
 '@T6G_MB_LIB.T6G(SCH_1):P5E_CPU1_P3_TX_BUF_C_DN'<3>:
 C_SIGNAL='@t6g_mb_lib.t6g(sch_1):p5e_cpu1_p3_tx_buf_c_dn(3)';
NODE_NAME     C6732 1
 '@T6G_MB_LIB.T6G(SCH_1):PAGE461_I28@PURE_QUANTA.Q_CAP_DIFFBUS(CHIPS)':
 '1': CDS_PINID='\1\';
NODE_NAME     J110 K4
 '@T6G_MB_LIB.T6G(SCH_1):PAGE318_I76@PURE_QUANTA.CONN112_10137002101LF(CHIPS)':
 'K4': CDS_PINID='K4';
NET_NAME
'P5E_CPU1_P3_TX_BUF_C_DN<4>'
 '@T6G_MB_LIB.T6G(SCH_1):P5E_CPU1_P3_TX_BUF_C_DN'<4>:
 C_SIGNAL='@t6g_mb_lib.t6g(sch_1):p5e_cpu1_p3_tx_buf_c_dn(4)';
NODE_NAME     C6734 1
 '@T6G_MB_LIB.T6G(SCH_1):PAGE461_I25@PURE_QUANTA.Q_CAP_DIFFBUS(CHIPS)':
 '1': CDS_PINID='\1\';
NODE_NAME     J110 L5
 '@T6G_MB_LIB.T6G(SCH_1):PAGE318_I16@PURE_QUANTA.CONN112_10137002101LF(CHIPS)':
 'L5': CDS_PINID='L5';
NET_NAME
'P5E_CPU1_P3_TX_BUF_C_DN<5>'
 '@T6G_MB_LIB.T6G(SCH_1):P5E_CPU1_P3_TX_BUF_C_DN'<5>:
 C_SIGNAL='@t6g_mb_lib.t6g(sch_1):p5e_cpu1_p3_tx_buf_c_dn(5)';
NODE_NAME     C6736 1
 '@T6G_MB_LIB.T6G(SCH_1):PAGE461_I23@PURE_QUANTA.Q_CAP_DIFFBUS(CHIPS)':
 '1': CDS_PINID='\1\';
NODE_NAME     J110 K6
 '@T6G_MB_LIB.T6G(SCH_1):PAGE318_I16@PURE_QUANTA.CONN112_10137002101LF(CHIPS)':
 'K6': CDS_PINID='K6';
NET_NAME
'P5E_CPU1_P3_TX_BUF_C_DN<6>'
 '@T6G_MB_LIB.T6G(SCH_1):P5E_CPU1_P3_TX_BUF_C_DN'<6>:
 C_SIGNAL='@t6g_mb_lib.t6g(sch_1):p5e_cpu1_p3_tx_buf_c_dn(6)';
NODE_NAME     C6738 1
 '@T6G_MB_LIB.T6G(SCH_1):PAGE461_I16@PURE_QUANTA.Q_CAP_DIFFBUS(CHIPS)':
 '1': CDS_PINID='\1\';
NODE_NAME     J110 L7
 '@T6G_MB_LIB.T6G(SCH_1):PAGE318_I16@PURE_QUANTA.CONN112_10137002101LF(CHIPS)':
 'L7': CDS_PINID='L7';
NET_NAME
'P5E_CPU1_P3_TX_BUF_C_DN<7>'
 '@T6G_MB_LIB.T6G(SCH_1):P5E_CPU1_P3_TX_BUF_C_DN'<7>:
 C_SIGNAL='@t6g_mb_lib.t6g(sch_1):p5e_cpu1_p3_tx_buf_c_dn(7)';
NODE_NAME     C6740 1
 '@T6G_MB_LIB.T6G(SCH_1):PAGE461_I18@PURE_QUANTA.Q_CAP_DIFFBUS(CHIPS)':
 '1': CDS_PINID='\1\';
NODE_NAME     J110 K8
 '@T6G_MB_LIB.T6G(SCH_1):PAGE318_I16@PURE_QUANTA.CONN112_10137002101LF(CHIPS)':
 'K8': CDS_PINID='K8';
NET_NAME
'P5E_CPU1_P3_TX_BUF_C_DN<8>'
 '@T6G_MB_LIB.T6G(SCH_1):P5E_CPU1_P3_TX_BUF_C_DN'<8>:
 C_SIGNAL='@t6g_mb_lib.t6g(sch_1):p5e_cpu1_p3_tx_buf_c_dn(8)';
NODE_NAME     C6742 1
 '@T6G_MB_LIB.T6G(SCH_1):PAGE461_I104@PURE_QUANTA.Q_CAP_DIFFBUS(CHIPS)':
 '1': CDS_PINID='\1\';
NODE_NAME     J109 L1
 '@T6G_MB_LIB.T6G(SCH_1):PAGE319_I76@PURE_QUANTA.CONN112_10137002101LF(CHIPS)':
 'L1': CDS_PINID='L1';
NET_NAME
'P5E_CPU1_P3_TX_BUF_C_DN<9>'
 '@T6G_MB_LIB.T6G(SCH_1):P5E_CPU1_P3_TX_BUF_C_DN'<9>:
 C_SIGNAL='@t6g_mb_lib.t6g(sch_1):p5e_cpu1_p3_tx_buf_c_dn(9)';
NODE_NAME     C6744 1
 '@T6G_MB_LIB.T6G(SCH_1):PAGE461_I100@PURE_QUANTA.Q_CAP_DIFFBUS(CHIPS)':
 '1': CDS_PINID='\1\';
NODE_NAME     J109 K2
 '@T6G_MB_LIB.T6G(SCH_1):PAGE319_I76@PURE_QUANTA.CONN112_10137002101LF(CHIPS)':
 'K2': CDS_PINID='K2';
NET_NAME
'P5E_CPU1_P3_TX_BUF_C_DP<0>'
 '@T6G_MB_LIB.T6G(SCH_1):P5E_CPU1_P3_TX_BUF_C_DP'<0>:
 C_SIGNAL='@t6g_mb_lib.t6g(sch_1):p5e_cpu1_p3_tx_buf_c_dp(0)';
NODE_NAME     C6725 1
 '@T6G_MB_LIB.T6G(SCH_1):PAGE461_I48@PURE_QUANTA.Q_CAP_DIFFBUS(CHIPS)':
 '1': CDS_PINID='\1\';
NODE_NAME     J110 M1
 '@T6G_MB_LIB.T6G(SCH_1):PAGE318_I76@PURE_QUANTA.CONN112_10137002101LF(CHIPS)':
 'M1': CDS_PINID='M1';
NET_NAME
'P5E_CPU1_P3_TX_BUF_C_DP<10>'
 '@T6G_MB_LIB.T6G(SCH_1):P5E_CPU1_P3_TX_BUF_C_DP'<10>:
 C_SIGNAL='@t6g_mb_lib.t6g(sch_1):p5e_cpu1_p3_tx_buf_c_dp(10)';
NODE_NAME     C6745 1
 '@T6G_MB_LIB.T6G(SCH_1):PAGE461_I99@PURE_QUANTA.Q_CAP_DIFFBUS(CHIPS)':
 '1': CDS_PINID='\1\';
NODE_NAME     J109 M3
 '@T6G_MB_LIB.T6G(SCH_1):PAGE319_I76@PURE_QUANTA.CONN112_10137002101LF(CHIPS)':
 'M3': CDS_PINID='M3';
NET_NAME
'P5E_CPU1_P3_TX_BUF_C_DP<11>'
 '@T6G_MB_LIB.T6G(SCH_1):P5E_CPU1_P3_TX_BUF_C_DP'<11>:
 C_SIGNAL='@t6g_mb_lib.t6g(sch_1):p5e_cpu1_p3_tx_buf_c_dp(11)';
NODE_NAME     C6747 1
 '@T6G_MB_LIB.T6G(SCH_1):PAGE461_I97@PURE_QUANTA.Q_CAP_DIFFBUS(CHIPS)':
 '1': CDS_PINID='\1\';
NODE_NAME     J109 L4
 '@T6G_MB_LIB.T6G(SCH_1):PAGE319_I76@PURE_QUANTA.CONN112_10137002101LF(CHIPS)':
 'L4': CDS_PINID='L4';
NET_NAME
'P5E_CPU1_P3_TX_BUF_C_DP<12>'
 '@T6G_MB_LIB.T6G(SCH_1):P5E_CPU1_P3_TX_BUF_C_DP'<12>:
 C_SIGNAL='@t6g_mb_lib.t6g(sch_1):p5e_cpu1_p3_tx_buf_c_dp(12)';
NODE_NAME     C6749 1
 '@T6G_MB_LIB.T6G(SCH_1):PAGE461_I95@PURE_QUANTA.Q_CAP_DIFFBUS(CHIPS)':
 '1': CDS_PINID='\1\';
NODE_NAME     J109 M5
 '@T6G_MB_LIB.T6G(SCH_1):PAGE319_I16@PURE_QUANTA.CONN112_10137002101LF(CHIPS)':
 'M5': CDS_PINID='M5';
NET_NAME
'P5E_CPU1_P3_TX_BUF_C_DP<13>'
 '@T6G_MB_LIB.T6G(SCH_1):P5E_CPU1_P3_TX_BUF_C_DP'<13>:
 C_SIGNAL='@t6g_mb_lib.t6g(sch_1):p5e_cpu1_p3_tx_buf_c_dp(13)';
NODE_NAME     C6751 1
 '@T6G_MB_LIB.T6G(SCH_1):PAGE461_I93@PURE_QUANTA.Q_CAP_DIFFBUS(CHIPS)':
 '1': CDS_PINID='\1\';
NODE_NAME     J109 L6
 '@T6G_MB_LIB.T6G(SCH_1):PAGE319_I16@PURE_QUANTA.CONN112_10137002101LF(CHIPS)':
 'L6': CDS_PINID='L6';
NET_NAME
'P5E_CPU1_P3_TX_BUF_C_DP<14>'
 '@T6G_MB_LIB.T6G(SCH_1):P5E_CPU1_P3_TX_BUF_C_DP'<14>:
 C_SIGNAL='@t6g_mb_lib.t6g(sch_1):p5e_cpu1_p3_tx_buf_c_dp(14)';
NODE_NAME     C6753 1
 '@T6G_MB_LIB.T6G(SCH_1):PAGE461_I91@PURE_QUANTA.Q_CAP_DIFFBUS(CHIPS)':
 '1': CDS_PINID='\1\';
NODE_NAME     J109 M7
 '@T6G_MB_LIB.T6G(SCH_1):PAGE319_I16@PURE_QUANTA.CONN112_10137002101LF(CHIPS)':
 'M7': CDS_PINID='M7';
NET_NAME
'P5E_CPU1_P3_TX_BUF_C_DP<15>'
 '@T6G_MB_LIB.T6G(SCH_1):P5E_CPU1_P3_TX_BUF_C_DP'<15>:
 C_SIGNAL='@t6g_mb_lib.t6g(sch_1):p5e_cpu1_p3_tx_buf_c_dp(15)';
NODE_NAME     C6755 1
 '@T6G_MB_LIB.T6G(SCH_1):PAGE461_I89@PURE_QUANTA.Q_CAP_DIFFBUS(CHIPS)':
 '1': CDS_PINID='\1\';
NODE_NAME     J109 L8
 '@T6G_MB_LIB.T6G(SCH_1):PAGE319_I16@PURE_QUANTA.CONN112_10137002101LF(CHIPS)':
 'L8': CDS_PINID='L8';
NET_NAME
'P5E_CPU1_P3_TX_BUF_C_DP<1>'
 '@T6G_MB_LIB.T6G(SCH_1):P5E_CPU1_P3_TX_BUF_C_DP'<1>:
 C_SIGNAL='@t6g_mb_lib.t6g(sch_1):p5e_cpu1_p3_tx_buf_c_dp(1)';
NODE_NAME     C6727 1
 '@T6G_MB_LIB.T6G(SCH_1):PAGE461_I32@PURE_QUANTA.Q_CAP_DIFFBUS(CHIPS)':
 '1': CDS_PINID='\1\';
NODE_NAME     J110 L2
 '@T6G_MB_LIB.T6G(SCH_1):PAGE318_I76@PURE_QUANTA.CONN112_10137002101LF(CHIPS)':
 'L2': CDS_PINID='L2';
NET_NAME
'P5E_CPU1_P3_TX_BUF_C_DP<2>'
 '@T6G_MB_LIB.T6G(SCH_1):P5E_CPU1_P3_TX_BUF_C_DP'<2>:
 C_SIGNAL='@t6g_mb_lib.t6g(sch_1):p5e_cpu1_p3_tx_buf_c_dp(2)';
NODE_NAME     C6729 1
 '@T6G_MB_LIB.T6G(SCH_1):PAGE461_I31@PURE_QUANTA.Q_CAP_DIFFBUS(CHIPS)':
 '1': CDS_PINID='\1\';
NODE_NAME     J110 M3
 '@T6G_MB_LIB.T6G(SCH_1):PAGE318_I76@PURE_QUANTA.CONN112_10137002101LF(CHIPS)':
 'M3': CDS_PINID='M3';
NET_NAME
'P5E_CPU1_P3_TX_BUF_C_DP<3>'
 '@T6G_MB_LIB.T6G(SCH_1):P5E_CPU1_P3_TX_BUF_C_DP'<3>:
 C_SIGNAL='@t6g_mb_lib.t6g(sch_1):p5e_cpu1_p3_tx_buf_c_dp(3)';
NODE_NAME     C6731 1
 '@T6G_MB_LIB.T6G(SCH_1):PAGE461_I27@PURE_QUANTA.Q_CAP_DIFFBUS(CHIPS)':
 '1': CDS_PINID='\1\';
NODE_NAME     J110 L4
 '@T6G_MB_LIB.T6G(SCH_1):PAGE318_I76@PURE_QUANTA.CONN112_10137002101LF(CHIPS)':
 'L4': CDS_PINID='L4';
NET_NAME
'P5E_CPU1_P3_TX_BUF_C_DP<4>'
 '@T6G_MB_LIB.T6G(SCH_1):P5E_CPU1_P3_TX_BUF_C_DP'<4>:
 C_SIGNAL='@t6g_mb_lib.t6g(sch_1):p5e_cpu1_p3_tx_buf_c_dp(4)';
NODE_NAME     C6733 1
 '@T6G_MB_LIB.T6G(SCH_1):PAGE461_I26@PURE_QUANTA.Q_CAP_DIFFBUS(CHIPS)':
 '1': CDS_PINID='\1\';
NODE_NAME     J110 M5
 '@T6G_MB_LIB.T6G(SCH_1):PAGE318_I16@PURE_QUANTA.CONN112_10137002101LF(CHIPS)':
 'M5': CDS_PINID='M5';
NET_NAME
'P5E_CPU1_P3_TX_BUF_C_DP<5>'
 '@T6G_MB_LIB.T6G(SCH_1):P5E_CPU1_P3_TX_BUF_C_DP'<5>:
 C_SIGNAL='@t6g_mb_lib.t6g(sch_1):p5e_cpu1_p3_tx_buf_c_dp(5)';
NODE_NAME     C6735 1
 '@T6G_MB_LIB.T6G(SCH_1):PAGE461_I24@PURE_QUANTA.Q_CAP_DIFFBUS(CHIPS)':
 '1': CDS_PINID='\1\';
NODE_NAME     J110 L6
 '@T6G_MB_LIB.T6G(SCH_1):PAGE318_I16@PURE_QUANTA.CONN112_10137002101LF(CHIPS)':
 'L6': CDS_PINID='L6';
NET_NAME
'P5E_CPU1_P3_TX_BUF_C_DP<6>'
 '@T6G_MB_LIB.T6G(SCH_1):P5E_CPU1_P3_TX_BUF_C_DP'<6>:
 C_SIGNAL='@t6g_mb_lib.t6g(sch_1):p5e_cpu1_p3_tx_buf_c_dp(6)';
NODE_NAME     C6737 1
 '@T6G_MB_LIB.T6G(SCH_1):PAGE461_I22@PURE_QUANTA.Q_CAP_DIFFBUS(CHIPS)':
 '1': CDS_PINID='\1\';
NODE_NAME     J110 M7
 '@T6G_MB_LIB.T6G(SCH_1):PAGE318_I16@PURE_QUANTA.CONN112_10137002101LF(CHIPS)':
 'M7': CDS_PINID='M7';
NET_NAME
'P5E_CPU1_P3_TX_BUF_C_DP<7>'
 '@T6G_MB_LIB.T6G(SCH_1):P5E_CPU1_P3_TX_BUF_C_DP'<7>:
 C_SIGNAL='@t6g_mb_lib.t6g(sch_1):p5e_cpu1_p3_tx_buf_c_dp(7)';
NODE_NAME     C6739 1
 '@T6G_MB_LIB.T6G(SCH_1):PAGE461_I17@PURE_QUANTA.Q_CAP_DIFFBUS(CHIPS)':
 '1': CDS_PINID='\1\';
NODE_NAME     J110 L8
 '@T6G_MB_LIB.T6G(SCH_1):PAGE318_I16@PURE_QUANTA.CONN112_10137002101LF(CHIPS)':
 'L8': CDS_PINID='L8';
NET_NAME
'P5E_CPU1_P3_TX_BUF_C_DP<8>'
 '@T6G_MB_LIB.T6G(SCH_1):P5E_CPU1_P3_TX_BUF_C_DP'<8>:
 C_SIGNAL='@t6g_mb_lib.t6g(sch_1):p5e_cpu1_p3_tx_buf_c_dp(8)';
NODE_NAME     C6741 1
 '@T6G_MB_LIB.T6G(SCH_1):PAGE461_I105@PURE_QUANTA.Q_CAP_DIFFBUS(CHIPS)':
 '1': CDS_PINID='\1\';
NODE_NAME     J109 M1
 '@T6G_MB_LIB.T6G(SCH_1):PAGE319_I76@PURE_QUANTA.CONN112_10137002101LF(CHIPS)':
 'M1': CDS_PINID='M1';
NET_NAME
'P5E_CPU1_P3_TX_BUF_C_DP<9>'
 '@T6G_MB_LIB.T6G(SCH_1):P5E_CPU1_P3_TX_BUF_C_DP'<9>:
 C_SIGNAL='@t6g_mb_lib.t6g(sch_1):p5e_cpu1_p3_tx_buf_c_dp(9)';
NODE_NAME     C6743 1
 '@T6G_MB_LIB.T6G(SCH_1):PAGE461_I101@PURE_QUANTA.Q_CAP_DIFFBUS(CHIPS)':
 '1': CDS_PINID='\1\';
NODE_NAME     J109 L2
 '@T6G_MB_LIB.T6G(SCH_1):PAGE319_I76@PURE_QUANTA.CONN112_10137002101LF(CHIPS)':
 'L2': CDS_PINID='L2';
NET_NAME
'P5E_CPU1_P3_TX_BUF_DN<0>'
 '@T6G_MB_LIB.T6G(SCH_1):P5E_CPU1_P3_TX_BUF_DN'<0>:
 C_SIGNAL='@t6g_mb_lib.t6g(sch_1):p5e_cpu1_p3_tx_buf_dn(0)';
NODE_NAME     C6726 2
 '@T6G_MB_LIB.T6G(SCH_1):PAGE461_I47@PURE_QUANTA.Q_CAP_DIFFBUS(CHIPS)':
 '2': CDS_PINID='\2\';
NODE_NAME     U6017 EW10
 '@T6G_MB_LIB.T6G(SCH_1):PAGE461_I142@PURE_QUANTA.PT5161LRS(CHIPS)':
 'B_PETN15': CDS_PINID='B_PETN15';
NET_NAME
'P5E_CPU1_P3_TX_BUF_DN<10>'
 '@T6G_MB_LIB.T6G(SCH_1):P5E_CPU1_P3_TX_BUF_DN'<10>:
 C_SIGNAL='@t6g_mb_lib.t6g(sch_1):p5e_cpu1_p3_tx_buf_dn(10)';
NODE_NAME     U6017 BJ10
 '@T6G_MB_LIB.T6G(SCH_1):PAGE461_I46@PURE_QUANTA.PT5161LRS(CHIPS)':
 'B_PETN5': CDS_PINID='B_PETN5';
NODE_NAME     C6746 2
 '@T6G_MB_LIB.T6G(SCH_1):PAGE461_I98@PURE_QUANTA.Q_CAP_DIFFBUS(CHIPS)':
 '2': CDS_PINID='\2\';
NET_NAME
'P5E_CPU1_P3_TX_BUF_DN<11>'
 '@T6G_MB_LIB.T6G(SCH_1):P5E_CPU1_P3_TX_BUF_DN'<11>:
 C_SIGNAL='@t6g_mb_lib.t6g(sch_1):p5e_cpu1_p3_tx_buf_dn(11)';
NODE_NAME     U6017 BB10
 '@T6G_MB_LIB.T6G(SCH_1):PAGE461_I46@PURE_QUANTA.PT5161LRS(CHIPS)':
 'B_PETN4': CDS_PINID='B_PETN4';
NODE_NAME     C6748 2
 '@T6G_MB_LIB.T6G(SCH_1):PAGE461_I96@PURE_QUANTA.Q_CAP_DIFFBUS(CHIPS)':
 '2': CDS_PINID='\2\';
NET_NAME
'P5E_CPU1_P3_TX_BUF_DN<12>'
 '@T6G_MB_LIB.T6G(SCH_1):P5E_CPU1_P3_TX_BUF_DN'<12>:
 C_SIGNAL='@t6g_mb_lib.t6g(sch_1):p5e_cpu1_p3_tx_buf_dn(12)';
NODE_NAME     U6017 AR10
 '@T6G_MB_LIB.T6G(SCH_1):PAGE461_I46@PURE_QUANTA.PT5161LRS(CHIPS)':
 'B_PETN3': CDS_PINID='B_PETN3';
NODE_NAME     C6750 2
 '@T6G_MB_LIB.T6G(SCH_1):PAGE461_I94@PURE_QUANTA.Q_CAP_DIFFBUS(CHIPS)':
 '2': CDS_PINID='\2\';
NET_NAME
'P5E_CPU1_P3_TX_BUF_DN<13>'
 '@T6G_MB_LIB.T6G(SCH_1):P5E_CPU1_P3_TX_BUF_DN'<13>:
 C_SIGNAL='@t6g_mb_lib.t6g(sch_1):p5e_cpu1_p3_tx_buf_dn(13)';
NODE_NAME     U6017 AH10
 '@T6G_MB_LIB.T6G(SCH_1):PAGE461_I46@PURE_QUANTA.PT5161LRS(CHIPS)':
 'B_PETN2': CDS_PINID='B_PETN2';
NODE_NAME     C6752 2
 '@T6G_MB_LIB.T6G(SCH_1):PAGE461_I92@PURE_QUANTA.Q_CAP_DIFFBUS(CHIPS)':
 '2': CDS_PINID='\2\';
NET_NAME
'P5E_CPU1_P3_TX_BUF_DN<14>'
 '@T6G_MB_LIB.T6G(SCH_1):P5E_CPU1_P3_TX_BUF_DN'<14>:
 C_SIGNAL='@t6g_mb_lib.t6g(sch_1):p5e_cpu1_p3_tx_buf_dn(14)';
NODE_NAME     U6017 AA10
 '@T6G_MB_LIB.T6G(SCH_1):PAGE461_I46@PURE_QUANTA.PT5161LRS(CHIPS)':
 'B_PETN1': CDS_PINID='B_PETN1';
NODE_NAME     C6754 2
 '@T6G_MB_LIB.T6G(SCH_1):PAGE461_I90@PURE_QUANTA.Q_CAP_DIFFBUS(CHIPS)':
 '2': CDS_PINID='\2\';
NET_NAME
'P5E_CPU1_P3_TX_BUF_DN<15>'
 '@T6G_MB_LIB.T6G(SCH_1):P5E_CPU1_P3_TX_BUF_DN'<15>:
 C_SIGNAL='@t6g_mb_lib.t6g(sch_1):p5e_cpu1_p3_tx_buf_dn(15)';
NODE_NAME     U6017 P10
 '@T6G_MB_LIB.T6G(SCH_1):PAGE461_I46@PURE_QUANTA.PT5161LRS(CHIPS)':
 'B_PETN0': CDS_PINID='B_PETN0';
NODE_NAME     C6756 2
 '@T6G_MB_LIB.T6G(SCH_1):PAGE461_I88@PURE_QUANTA.Q_CAP_DIFFBUS(CHIPS)':
 '2': CDS_PINID='\2\';
NET_NAME
'P5E_CPU1_P3_TX_BUF_DN<1>'
 '@T6G_MB_LIB.T6G(SCH_1):P5E_CPU1_P3_TX_BUF_DN'<1>:
 C_SIGNAL='@t6g_mb_lib.t6g(sch_1):p5e_cpu1_p3_tx_buf_dn(1)';
NODE_NAME     C6728 2
 '@T6G_MB_LIB.T6G(SCH_1):PAGE461_I30@PURE_QUANTA.Q_CAP_DIFFBUS(CHIPS)':
 '2': CDS_PINID='\2\';
NODE_NAME     U6017 EM10
 '@T6G_MB_LIB.T6G(SCH_1):PAGE461_I142@PURE_QUANTA.PT5161LRS(CHIPS)':
 'B_PETN14': CDS_PINID='B_PETN14';
NET_NAME
'P5E_CPU1_P3_TX_BUF_DN<2>'
 '@T6G_MB_LIB.T6G(SCH_1):P5E_CPU1_P3_TX_BUF_DN'<2>:
 C_SIGNAL='@t6g_mb_lib.t6g(sch_1):p5e_cpu1_p3_tx_buf_dn(2)';
NODE_NAME     C6730 2
 '@T6G_MB_LIB.T6G(SCH_1):PAGE461_I29@PURE_QUANTA.Q_CAP_DIFFBUS(CHIPS)':
 '2': CDS_PINID='\2\';
NODE_NAME     U6017 EE10
 '@T6G_MB_LIB.T6G(SCH_1):PAGE461_I142@PURE_QUANTA.PT5161LRS(CHIPS)':
 'B_PETN13': CDS_PINID='B_PETN13';
NET_NAME
'P5E_CPU1_P3_TX_BUF_DN<3>'
 '@T6G_MB_LIB.T6G(SCH_1):P5E_CPU1_P3_TX_BUF_DN'<3>:
 C_SIGNAL='@t6g_mb_lib.t6g(sch_1):p5e_cpu1_p3_tx_buf_dn(3)';
NODE_NAME     C6732 2
 '@T6G_MB_LIB.T6G(SCH_1):PAGE461_I28@PURE_QUANTA.Q_CAP_DIFFBUS(CHIPS)':
 '2': CDS_PINID='\2\';
NODE_NAME     U6017 DV10
 '@T6G_MB_LIB.T6G(SCH_1):PAGE461_I142@PURE_QUANTA.PT5161LRS(CHIPS)':
 'B_PETN12': CDS_PINID='B_PETN12';
NET_NAME
'P5E_CPU1_P3_TX_BUF_DN<4>'
 '@T6G_MB_LIB.T6G(SCH_1):P5E_CPU1_P3_TX_BUF_DN'<4>:
 C_SIGNAL='@t6g_mb_lib.t6g(sch_1):p5e_cpu1_p3_tx_buf_dn(4)';
NODE_NAME     C6734 2
 '@T6G_MB_LIB.T6G(SCH_1):PAGE461_I25@PURE_QUANTA.Q_CAP_DIFFBUS(CHIPS)':
 '2': CDS_PINID='\2\';
NODE_NAME     U6017 DL10
 '@T6G_MB_LIB.T6G(SCH_1):PAGE461_I142@PURE_QUANTA.PT5161LRS(CHIPS)':
 'B_PETN11': CDS_PINID='B_PETN11';
NET_NAME
'P5E_CPU1_P3_TX_BUF_DN<5>'
 '@T6G_MB_LIB.T6G(SCH_1):P5E_CPU1_P3_TX_BUF_DN'<5>:
 C_SIGNAL='@t6g_mb_lib.t6g(sch_1):p5e_cpu1_p3_tx_buf_dn(5)';
NODE_NAME     C6736 2
 '@T6G_MB_LIB.T6G(SCH_1):PAGE461_I23@PURE_QUANTA.Q_CAP_DIFFBUS(CHIPS)':
 '2': CDS_PINID='\2\';
NODE_NAME     U6017 DD10
 '@T6G_MB_LIB.T6G(SCH_1):PAGE461_I142@PURE_QUANTA.PT5161LRS(CHIPS)':
 'B_PETN10': CDS_PINID='B_PETN10';
NET_NAME
'P5E_CPU1_P3_TX_BUF_DN<6>'
 '@T6G_MB_LIB.T6G(SCH_1):P5E_CPU1_P3_TX_BUF_DN'<6>:
 C_SIGNAL='@t6g_mb_lib.t6g(sch_1):p5e_cpu1_p3_tx_buf_dn(6)';
NODE_NAME     C6738 2
 '@T6G_MB_LIB.T6G(SCH_1):PAGE461_I16@PURE_QUANTA.Q_CAP_DIFFBUS(CHIPS)':
 '2': CDS_PINID='\2\';
NODE_NAME     U6017 CU10
 '@T6G_MB_LIB.T6G(SCH_1):PAGE461_I142@PURE_QUANTA.PT5161LRS(CHIPS)':
 'B_PETN9': CDS_PINID='B_PETN9';
NET_NAME
'P5E_CPU1_P3_TX_BUF_DN<7>'
 '@T6G_MB_LIB.T6G(SCH_1):P5E_CPU1_P3_TX_BUF_DN'<7>:
 C_SIGNAL='@t6g_mb_lib.t6g(sch_1):p5e_cpu1_p3_tx_buf_dn(7)';
NODE_NAME     C6740 2
 '@T6G_MB_LIB.T6G(SCH_1):PAGE461_I18@PURE_QUANTA.Q_CAP_DIFFBUS(CHIPS)':
 '2': CDS_PINID='\2\';
NODE_NAME     U6017 CK10
 '@T6G_MB_LIB.T6G(SCH_1):PAGE461_I142@PURE_QUANTA.PT5161LRS(CHIPS)':
 'B_PETN8': CDS_PINID='B_PETN8';
NET_NAME
'P5E_CPU1_P3_TX_BUF_DN<8>'
 '@T6G_MB_LIB.T6G(SCH_1):P5E_CPU1_P3_TX_BUF_DN'<8>:
 C_SIGNAL='@t6g_mb_lib.t6g(sch_1):p5e_cpu1_p3_tx_buf_dn(8)';
NODE_NAME     U6017 CC10
 '@T6G_MB_LIB.T6G(SCH_1):PAGE461_I46@PURE_QUANTA.PT5161LRS(CHIPS)':
 'B_PETN7': CDS_PINID='B_PETN7';
NODE_NAME     C6742 2
 '@T6G_MB_LIB.T6G(SCH_1):PAGE461_I104@PURE_QUANTA.Q_CAP_DIFFBUS(CHIPS)':
 '2': CDS_PINID='\2\';
NET_NAME
'P5E_CPU1_P3_TX_BUF_DN<9>'
 '@T6G_MB_LIB.T6G(SCH_1):P5E_CPU1_P3_TX_BUF_DN'<9>:
 C_SIGNAL='@t6g_mb_lib.t6g(sch_1):p5e_cpu1_p3_tx_buf_dn(9)';
NODE_NAME     U6017 BT10
 '@T6G_MB_LIB.T6G(SCH_1):PAGE461_I46@PURE_QUANTA.PT5161LRS(CHIPS)':
 'B_PETN6': CDS_PINID='B_PETN6';
NODE_NAME     C6744 2
 '@T6G_MB_LIB.T6G(SCH_1):PAGE461_I100@PURE_QUANTA.Q_CAP_DIFFBUS(CHIPS)':
 '2': CDS_PINID='\2\';
NET_NAME
'P5E_CPU1_P3_TX_BUF_DP<0>'
 '@T6G_MB_LIB.T6G(SCH_1):P5E_CPU1_P3_TX_BUF_DP'<0>:
 C_SIGNAL='@t6g_mb_lib.t6g(sch_1):p5e_cpu1_p3_tx_buf_dp(0)';
NODE_NAME     C6725 2
 '@T6G_MB_LIB.T6G(SCH_1):PAGE461_I48@PURE_QUANTA.Q_CAP_DIFFBUS(CHIPS)':
 '2': CDS_PINID='\2\';
NODE_NAME     U6017 EU7
 '@T6G_MB_LIB.T6G(SCH_1):PAGE461_I142@PURE_QUANTA.PT5161LRS(CHIPS)':
 'B_PETP15': CDS_PINID='B_PETP15';
NET_NAME
'P5E_CPU1_P3_TX_BUF_DP<10>'
 '@T6G_MB_LIB.T6G(SCH_1):P5E_CPU1_P3_TX_BUF_DP'<10>:
 C_SIGNAL='@t6g_mb_lib.t6g(sch_1):p5e_cpu1_p3_tx_buf_dp(10)';
NODE_NAME     U6017 BG7
 '@T6G_MB_LIB.T6G(SCH_1):PAGE461_I46@PURE_QUANTA.PT5161LRS(CHIPS)':
 'B_PETP5': CDS_PINID='B_PETP5';
NODE_NAME     C6745 2
 '@T6G_MB_LIB.T6G(SCH_1):PAGE461_I99@PURE_QUANTA.Q_CAP_DIFFBUS(CHIPS)':
 '2': CDS_PINID='\2\';
NET_NAME
'P5E_CPU1_P3_TX_BUF_DP<11>'
 '@T6G_MB_LIB.T6G(SCH_1):P5E_CPU1_P3_TX_BUF_DP'<11>:
 C_SIGNAL='@t6g_mb_lib.t6g(sch_1):p5e_cpu1_p3_tx_buf_dp(11)';
NODE_NAME     U6017 AY7
 '@T6G_MB_LIB.T6G(SCH_1):PAGE461_I46@PURE_QUANTA.PT5161LRS(CHIPS)':
 'B_PETP4': CDS_PINID='B_PETP4';
NODE_NAME     C6747 2
 '@T6G_MB_LIB.T6G(SCH_1):PAGE461_I97@PURE_QUANTA.Q_CAP_DIFFBUS(CHIPS)':
 '2': CDS_PINID='\2\';
NET_NAME
'P5E_CPU1_P3_TX_BUF_DP<12>'
 '@T6G_MB_LIB.T6G(SCH_1):P5E_CPU1_P3_TX_BUF_DP'<12>:
 C_SIGNAL='@t6g_mb_lib.t6g(sch_1):p5e_cpu1_p3_tx_buf_dp(12)';
NODE_NAME     U6017 AN7
 '@T6G_MB_LIB.T6G(SCH_1):PAGE461_I46@PURE_QUANTA.PT5161LRS(CHIPS)':
 'B_PETP3': CDS_PINID='B_PETP3';
NODE_NAME     C6749 2
 '@T6G_MB_LIB.T6G(SCH_1):PAGE461_I95@PURE_QUANTA.Q_CAP_DIFFBUS(CHIPS)':
 '2': CDS_PINID='\2\';
NET_NAME
'P5E_CPU1_P3_TX_BUF_DP<13>'
 '@T6G_MB_LIB.T6G(SCH_1):P5E_CPU1_P3_TX_BUF_DP'<13>:
 C_SIGNAL='@t6g_mb_lib.t6g(sch_1):p5e_cpu1_p3_tx_buf_dp(13)';
NODE_NAME     U6017 AF7
 '@T6G_MB_LIB.T6G(SCH_1):PAGE461_I46@PURE_QUANTA.PT5161LRS(CHIPS)':
 'B_PETP2': CDS_PINID='B_PETP2';
NODE_NAME     C6751 2
 '@T6G_MB_LIB.T6G(SCH_1):PAGE461_I93@PURE_QUANTA.Q_CAP_DIFFBUS(CHIPS)':
 '2': CDS_PINID='\2\';
NET_NAME
'P5E_CPU1_P3_TX_BUF_DP<14>'
 '@T6G_MB_LIB.T6G(SCH_1):P5E_CPU1_P3_TX_BUF_DP'<14>:
 C_SIGNAL='@t6g_mb_lib.t6g(sch_1):p5e_cpu1_p3_tx_buf_dp(14)';
NODE_NAME     U6017 W7
 '@T6G_MB_LIB.T6G(SCH_1):PAGE461_I46@PURE_QUANTA.PT5161LRS(CHIPS)':
 'B_PETP1': CDS_PINID='B_PETP1';
NODE_NAME     C6753 2
 '@T6G_MB_LIB.T6G(SCH_1):PAGE461_I91@PURE_QUANTA.Q_CAP_DIFFBUS(CHIPS)':
 '2': CDS_PINID='\2\';
NET_NAME
'P5E_CPU1_P3_TX_BUF_DP<15>'
 '@T6G_MB_LIB.T6G(SCH_1):P5E_CPU1_P3_TX_BUF_DP'<15>:
 C_SIGNAL='@t6g_mb_lib.t6g(sch_1):p5e_cpu1_p3_tx_buf_dp(15)';
NODE_NAME     U6017 M7
 '@T6G_MB_LIB.T6G(SCH_1):PAGE461_I46@PURE_QUANTA.PT5161LRS(CHIPS)':
 'B_PETP0': CDS_PINID='B_PETP0';
NODE_NAME     C6755 2
 '@T6G_MB_LIB.T6G(SCH_1):PAGE461_I89@PURE_QUANTA.Q_CAP_DIFFBUS(CHIPS)':
 '2': CDS_PINID='\2\';
NET_NAME
'P5E_CPU1_P3_TX_BUF_DP<1>'
 '@T6G_MB_LIB.T6G(SCH_1):P5E_CPU1_P3_TX_BUF_DP'<1>:
 C_SIGNAL='@t6g_mb_lib.t6g(sch_1):p5e_cpu1_p3_tx_buf_dp(1)';
NODE_NAME     C6727 2
 '@T6G_MB_LIB.T6G(SCH_1):PAGE461_I32@PURE_QUANTA.Q_CAP_DIFFBUS(CHIPS)':
 '2': CDS_PINID='\2\';
NODE_NAME     U6017 EK7
 '@T6G_MB_LIB.T6G(SCH_1):PAGE461_I142@PURE_QUANTA.PT5161LRS(CHIPS)':
 'B_PETP14': CDS_PINID='B_PETP14';
NET_NAME
'P5E_CPU1_P3_TX_BUF_DP<2>'
 '@T6G_MB_LIB.T6G(SCH_1):P5E_CPU1_P3_TX_BUF_DP'<2>:
 C_SIGNAL='@t6g_mb_lib.t6g(sch_1):p5e_cpu1_p3_tx_buf_dp(2)';
NODE_NAME     C6729 2
 '@T6G_MB_LIB.T6G(SCH_1):PAGE461_I31@PURE_QUANTA.Q_CAP_DIFFBUS(CHIPS)':
 '2': CDS_PINID='\2\';
NODE_NAME     U6017 EC7
 '@T6G_MB_LIB.T6G(SCH_1):PAGE461_I142@PURE_QUANTA.PT5161LRS(CHIPS)':
 'B_PETP13': CDS_PINID='B_PETP13';
NET_NAME
'P5E_CPU1_P3_TX_BUF_DP<3>'
 '@T6G_MB_LIB.T6G(SCH_1):P5E_CPU1_P3_TX_BUF_DP'<3>:
 C_SIGNAL='@t6g_mb_lib.t6g(sch_1):p5e_cpu1_p3_tx_buf_dp(3)';
NODE_NAME     C6731 2
 '@T6G_MB_LIB.T6G(SCH_1):PAGE461_I27@PURE_QUANTA.Q_CAP_DIFFBUS(CHIPS)':
 '2': CDS_PINID='\2\';
NODE_NAME     U6017 DT7
 '@T6G_MB_LIB.T6G(SCH_1):PAGE461_I142@PURE_QUANTA.PT5161LRS(CHIPS)':
 'B_PETP12': CDS_PINID='B_PETP12';
NET_NAME
'P5E_CPU1_P3_TX_BUF_DP<4>'
 '@T6G_MB_LIB.T6G(SCH_1):P5E_CPU1_P3_TX_BUF_DP'<4>:
 C_SIGNAL='@t6g_mb_lib.t6g(sch_1):p5e_cpu1_p3_tx_buf_dp(4)';
NODE_NAME     C6733 2
 '@T6G_MB_LIB.T6G(SCH_1):PAGE461_I26@PURE_QUANTA.Q_CAP_DIFFBUS(CHIPS)':
 '2': CDS_PINID='\2\';
NODE_NAME     U6017 DJ7
 '@T6G_MB_LIB.T6G(SCH_1):PAGE461_I142@PURE_QUANTA.PT5161LRS(CHIPS)':
 'B_PETP11': CDS_PINID='B_PETP11';
NET_NAME
'P5E_CPU1_P3_TX_BUF_DP<5>'
 '@T6G_MB_LIB.T6G(SCH_1):P5E_CPU1_P3_TX_BUF_DP'<5>:
 C_SIGNAL='@t6g_mb_lib.t6g(sch_1):p5e_cpu1_p3_tx_buf_dp(5)';
NODE_NAME     C6735 2
 '@T6G_MB_LIB.T6G(SCH_1):PAGE461_I24@PURE_QUANTA.Q_CAP_DIFFBUS(CHIPS)':
 '2': CDS_PINID='\2\';
NODE_NAME     U6017 DB7
 '@T6G_MB_LIB.T6G(SCH_1):PAGE461_I142@PURE_QUANTA.PT5161LRS(CHIPS)':
 'B_PETP10': CDS_PINID='B_PETP10';
NET_NAME
'P5E_CPU1_P3_TX_BUF_DP<6>'
 '@T6G_MB_LIB.T6G(SCH_1):P5E_CPU1_P3_TX_BUF_DP'<6>:
 C_SIGNAL='@t6g_mb_lib.t6g(sch_1):p5e_cpu1_p3_tx_buf_dp(6)';
NODE_NAME     C6737 2
 '@T6G_MB_LIB.T6G(SCH_1):PAGE461_I22@PURE_QUANTA.Q_CAP_DIFFBUS(CHIPS)':
 '2': CDS_PINID='\2\';
NODE_NAME     U6017 CR7
 '@T6G_MB_LIB.T6G(SCH_1):PAGE461_I142@PURE_QUANTA.PT5161LRS(CHIPS)':
 'B_PETP9': CDS_PINID='B_PETP9';
NET_NAME
'P5E_CPU1_P3_TX_BUF_DP<7>'
 '@T6G_MB_LIB.T6G(SCH_1):P5E_CPU1_P3_TX_BUF_DP'<7>:
 C_SIGNAL='@t6g_mb_lib.t6g(sch_1):p5e_cpu1_p3_tx_buf_dp(7)';
NODE_NAME     C6739 2
 '@T6G_MB_LIB.T6G(SCH_1):PAGE461_I17@PURE_QUANTA.Q_CAP_DIFFBUS(CHIPS)':
 '2': CDS_PINID='\2\';
NODE_NAME     U6017 CH7
 '@T6G_MB_LIB.T6G(SCH_1):PAGE461_I142@PURE_QUANTA.PT5161LRS(CHIPS)':
 'B_PETP8': CDS_PINID='B_PETP8';
NET_NAME
'P5E_CPU1_P3_TX_BUF_DP<8>'
 '@T6G_MB_LIB.T6G(SCH_1):P5E_CPU1_P3_TX_BUF_DP'<8>:
 C_SIGNAL='@t6g_mb_lib.t6g(sch_1):p5e_cpu1_p3_tx_buf_dp(8)';
NODE_NAME     U6017 CA7
 '@T6G_MB_LIB.T6G(SCH_1):PAGE461_I46@PURE_QUANTA.PT5161LRS(CHIPS)':
 'B_PETP7': CDS_PINID='B_PETP7';
NODE_NAME     C6741 2
 '@T6G_MB_LIB.T6G(SCH_1):PAGE461_I105@PURE_QUANTA.Q_CAP_DIFFBUS(CHIPS)':
 '2': CDS_PINID='\2\';
NET_NAME
'P5E_CPU1_P3_TX_BUF_DP<9>'
 '@T6G_MB_LIB.T6G(SCH_1):P5E_CPU1_P3_TX_BUF_DP'<9>:
 C_SIGNAL='@t6g_mb_lib.t6g(sch_1):p5e_cpu1_p3_tx_buf_dp(9)';
NODE_NAME     U6017 BP7
 '@T6G_MB_LIB.T6G(SCH_1):PAGE461_I46@PURE_QUANTA.PT5161LRS(CHIPS)':
 'B_PETP6': CDS_PINID='B_PETP6';
NODE_NAME     C6743 2
 '@T6G_MB_LIB.T6G(SCH_1):PAGE461_I101@PURE_QUANTA.Q_CAP_DIFFBUS(CHIPS)':
 '2': CDS_PINID='\2\';
NET_NAME
'P5E_CPU1_P3_TX_C_DN<0>'
 '@T6G_MB_LIB.T6G(SCH_1):P5E_CPU1_P3_TX_C_DN'<0>:
 C_SIGNAL='@t6g_mb_lib.t6g(sch_1):p5e_cpu1_p3_tx_c_dn(0)';
NODE_NAME     C1546 1
 '@T6G_MB_LIB.T6G(SCH_1):PAGE355_I54@PURE_QUANTA.Q_CAP_DIFFBUS(CHIPS)':
 '1': CDS_PINID='\1\';
NODE_NAME     U6017 EV34
 '@T6G_MB_LIB.T6G(SCH_1):PAGE458_I38@PURE_QUANTA.PT5161LRS(CHIPS)':
 'B_PERP15': CDS_PINID='B_PERP15';
NET_NAME
'P5E_CPU1_P3_TX_C_DN<10>'
 '@T6G_MB_LIB.T6G(SCH_1):P5E_CPU1_P3_TX_C_DN'<10>:
 C_SIGNAL='@t6g_mb_lib.t6g(sch_1):p5e_cpu1_p3_tx_c_dn(10)';
NODE_NAME     C1526 1
 '@T6G_MB_LIB.T6G(SCH_1):PAGE355_I81@PURE_QUANTA.Q_CAP_DIFFBUS(CHIPS)':
 '1': CDS_PINID='\1\';
NODE_NAME     U6017 BH34
 '@T6G_MB_LIB.T6G(SCH_1):PAGE458_I1@PURE_QUANTA.PT5161LRS(CHIPS)':
 'B_PERP5': CDS_PINID='B_PERP5';
NET_NAME
'P5E_CPU1_P3_TX_C_DN<11>'
 '@T6G_MB_LIB.T6G(SCH_1):P5E_CPU1_P3_TX_C_DN'<11>:
 C_SIGNAL='@t6g_mb_lib.t6g(sch_1):p5e_cpu1_p3_tx_c_dn(11)';
NODE_NAME     C1524 1
 '@T6G_MB_LIB.T6G(SCH_1):PAGE355_I84@PURE_QUANTA.Q_CAP_DIFFBUS(CHIPS)':
 '1': CDS_PINID='\1\';
NODE_NAME     U6017 BA34
 '@T6G_MB_LIB.T6G(SCH_1):PAGE458_I1@PURE_QUANTA.PT5161LRS(CHIPS)':
 'B_PERP4': CDS_PINID='B_PERP4';
NET_NAME
'P5E_CPU1_P3_TX_C_DN<12>'
 '@T6G_MB_LIB.T6G(SCH_1):P5E_CPU1_P3_TX_C_DN'<12>:
 C_SIGNAL='@t6g_mb_lib.t6g(sch_1):p5e_cpu1_p3_tx_c_dn(12)';
NODE_NAME     C54 1
 '@T6G_MB_LIB.T6G(SCH_1):PAGE355_I86@PURE_QUANTA.Q_CAP_DIFFBUS(CHIPS)':
 '1': CDS_PINID='\1\';
NODE_NAME     U6017 AP34
 '@T6G_MB_LIB.T6G(SCH_1):PAGE458_I1@PURE_QUANTA.PT5161LRS(CHIPS)':
 'B_PERP3': CDS_PINID='B_PERP3';
NET_NAME
'P5E_CPU1_P3_TX_C_DN<13>'
 '@T6G_MB_LIB.T6G(SCH_1):P5E_CPU1_P3_TX_C_DN'<13>:
 C_SIGNAL='@t6g_mb_lib.t6g(sch_1):p5e_cpu1_p3_tx_c_dn(13)';
NODE_NAME     C52 1
 '@T6G_MB_LIB.T6G(SCH_1):PAGE355_I116@PURE_QUANTA.Q_CAP_DIFFBUS(CHIPS)':
 '1': CDS_PINID='\1\';
NODE_NAME     U6017 AG34
 '@T6G_MB_LIB.T6G(SCH_1):PAGE458_I1@PURE_QUANTA.PT5161LRS(CHIPS)':
 'B_PERP2': CDS_PINID='B_PERP2';
NET_NAME
'P5E_CPU1_P3_TX_C_DN<14>'
 '@T6G_MB_LIB.T6G(SCH_1):P5E_CPU1_P3_TX_C_DN'<14>:
 C_SIGNAL='@t6g_mb_lib.t6g(sch_1):p5e_cpu1_p3_tx_c_dn(14)';
NODE_NAME     C50 1
 '@T6G_MB_LIB.T6G(SCH_1):PAGE355_I118@PURE_QUANTA.Q_CAP_DIFFBUS(CHIPS)':
 '1': CDS_PINID='\1\';
NODE_NAME     U6017 AB35
 '@T6G_MB_LIB.T6G(SCH_1):PAGE458_I1@PURE_QUANTA.PT5161LRS(CHIPS)':
 'B_PERN1': CDS_PINID='B_PERN1';
NET_NAME
'P5E_CPU1_P3_TX_C_DN<15>'
 '@T6G_MB_LIB.T6G(SCH_1):P5E_CPU1_P3_TX_C_DN'<15>:
 C_SIGNAL='@t6g_mb_lib.t6g(sch_1):p5e_cpu1_p3_tx_c_dn(15)';
NODE_NAME     C48 1
 '@T6G_MB_LIB.T6G(SCH_1):PAGE355_I119@PURE_QUANTA.Q_CAP_DIFFBUS(CHIPS)':
 '1': CDS_PINID='\1\';
NODE_NAME     U6017 N34
 '@T6G_MB_LIB.T6G(SCH_1):PAGE458_I1@PURE_QUANTA.PT5161LRS(CHIPS)':
 'B_PERP0': CDS_PINID='B_PERP0';
NET_NAME
'P5E_CPU1_P3_TX_C_DN<1>'
 '@T6G_MB_LIB.T6G(SCH_1):P5E_CPU1_P3_TX_C_DN'<1>:
 C_SIGNAL='@t6g_mb_lib.t6g(sch_1):p5e_cpu1_p3_tx_c_dn(1)';
NODE_NAME     C1544 1
 '@T6G_MB_LIB.T6G(SCH_1):PAGE355_I55@PURE_QUANTA.Q_CAP_DIFFBUS(CHIPS)':
 '1': CDS_PINID='\1\';
NODE_NAME     U6017 EN35
 '@T6G_MB_LIB.T6G(SCH_1):PAGE458_I38@PURE_QUANTA.PT5161LRS(CHIPS)':
 'B_PERN14': CDS_PINID='B_PERN14';
NET_NAME
'P5E_CPU1_P3_TX_C_DN<2>'
 '@T6G_MB_LIB.T6G(SCH_1):P5E_CPU1_P3_TX_C_DN'<2>:
 C_SIGNAL='@t6g_mb_lib.t6g(sch_1):p5e_cpu1_p3_tx_c_dn(2)';
NODE_NAME     C1542 1
 '@T6G_MB_LIB.T6G(SCH_1):PAGE355_I58@PURE_QUANTA.Q_CAP_DIFFBUS(CHIPS)':
 '1': CDS_PINID='\1\';
NODE_NAME     U6017 ED34
 '@T6G_MB_LIB.T6G(SCH_1):PAGE458_I38@PURE_QUANTA.PT5161LRS(CHIPS)':
 'B_PERP13': CDS_PINID='B_PERP13';
NET_NAME
'P5E_CPU1_P3_TX_C_DN<3>'
 '@T6G_MB_LIB.T6G(SCH_1):P5E_CPU1_P3_TX_C_DN'<3>:
 C_SIGNAL='@t6g_mb_lib.t6g(sch_1):p5e_cpu1_p3_tx_c_dn(3)';
NODE_NAME     C1540 1
 '@T6G_MB_LIB.T6G(SCH_1):PAGE355_I68@PURE_QUANTA.Q_CAP_DIFFBUS(CHIPS)':
 '1': CDS_PINID='\1\';
NODE_NAME     U6017 DU34
 '@T6G_MB_LIB.T6G(SCH_1):PAGE458_I38@PURE_QUANTA.PT5161LRS(CHIPS)':
 'B_PERP12': CDS_PINID='B_PERP12';
NET_NAME
'P5E_CPU1_P3_TX_C_DN<4>'
 '@T6G_MB_LIB.T6G(SCH_1):P5E_CPU1_P3_TX_C_DN'<4>:
 C_SIGNAL='@t6g_mb_lib.t6g(sch_1):p5e_cpu1_p3_tx_c_dn(4)';
NODE_NAME     C1538 1
 '@T6G_MB_LIB.T6G(SCH_1):PAGE355_I70@PURE_QUANTA.Q_CAP_DIFFBUS(CHIPS)':
 '1': CDS_PINID='\1\';
NODE_NAME     U6017 DK34
 '@T6G_MB_LIB.T6G(SCH_1):PAGE458_I38@PURE_QUANTA.PT5161LRS(CHIPS)':
 'B_PERP11': CDS_PINID='B_PERP11';
NET_NAME
'P5E_CPU1_P3_TX_C_DN<5>'
 '@T6G_MB_LIB.T6G(SCH_1):P5E_CPU1_P3_TX_C_DN'<5>:
 C_SIGNAL='@t6g_mb_lib.t6g(sch_1):p5e_cpu1_p3_tx_c_dn(5)';
NODE_NAME     C1536 1
 '@T6G_MB_LIB.T6G(SCH_1):PAGE355_I72@PURE_QUANTA.Q_CAP_DIFFBUS(CHIPS)':
 '1': CDS_PINID='\1\';
NODE_NAME     U6017 DC34
 '@T6G_MB_LIB.T6G(SCH_1):PAGE458_I38@PURE_QUANTA.PT5161LRS(CHIPS)':
 'B_PERP10': CDS_PINID='B_PERP10';
NET_NAME
'P5E_CPU1_P3_TX_C_DN<6>'
 '@T6G_MB_LIB.T6G(SCH_1):P5E_CPU1_P3_TX_C_DN'<6>:
 C_SIGNAL='@t6g_mb_lib.t6g(sch_1):p5e_cpu1_p3_tx_c_dn(6)';
NODE_NAME     C1534 1
 '@T6G_MB_LIB.T6G(SCH_1):PAGE355_I74@PURE_QUANTA.Q_CAP_DIFFBUS(CHIPS)':
 '1': CDS_PINID='\1\';
NODE_NAME     U6017 CT34
 '@T6G_MB_LIB.T6G(SCH_1):PAGE458_I38@PURE_QUANTA.PT5161LRS(CHIPS)':
 'B_PERP9': CDS_PINID='B_PERP9';
NET_NAME
'P5E_CPU1_P3_TX_C_DN<7>'
 '@T6G_MB_LIB.T6G(SCH_1):P5E_CPU1_P3_TX_C_DN'<7>:
 C_SIGNAL='@t6g_mb_lib.t6g(sch_1):p5e_cpu1_p3_tx_c_dn(7)';
NODE_NAME     C1532 1
 '@T6G_MB_LIB.T6G(SCH_1):PAGE355_I76@PURE_QUANTA.Q_CAP_DIFFBUS(CHIPS)':
 '1': CDS_PINID='\1\';
NODE_NAME     U6017 CJ34
 '@T6G_MB_LIB.T6G(SCH_1):PAGE458_I38@PURE_QUANTA.PT5161LRS(CHIPS)':
 'B_PERP8': CDS_PINID='B_PERP8';
NET_NAME
'P5E_CPU1_P3_TX_C_DN<8>'
 '@T6G_MB_LIB.T6G(SCH_1):P5E_CPU1_P3_TX_C_DN'<8>:
 C_SIGNAL='@t6g_mb_lib.t6g(sch_1):p5e_cpu1_p3_tx_c_dn(8)';
NODE_NAME     C1530 1
 '@T6G_MB_LIB.T6G(SCH_1):PAGE355_I78@PURE_QUANTA.Q_CAP_DIFFBUS(CHIPS)':
 '1': CDS_PINID='\1\';
NODE_NAME     U6017 CB34
 '@T6G_MB_LIB.T6G(SCH_1):PAGE458_I1@PURE_QUANTA.PT5161LRS(CHIPS)':
 'B_PERP7': CDS_PINID='B_PERP7';
NET_NAME
'P5E_CPU1_P3_TX_C_DN<9>'
 '@T6G_MB_LIB.T6G(SCH_1):P5E_CPU1_P3_TX_C_DN'<9>:
 C_SIGNAL='@t6g_mb_lib.t6g(sch_1):p5e_cpu1_p3_tx_c_dn(9)';
NODE_NAME     C1528 1
 '@T6G_MB_LIB.T6G(SCH_1):PAGE355_I80@PURE_QUANTA.Q_CAP_DIFFBUS(CHIPS)':
 '1': CDS_PINID='\1\';
NODE_NAME     U6017 BR34
 '@T6G_MB_LIB.T6G(SCH_1):PAGE458_I1@PURE_QUANTA.PT5161LRS(CHIPS)':
 'B_PERP6': CDS_PINID='B_PERP6';
NET_NAME
'P5E_CPU1_P3_TX_C_DP<0>'
 '@T6G_MB_LIB.T6G(SCH_1):P5E_CPU1_P3_TX_C_DP'<0>:
 C_SIGNAL='@t6g_mb_lib.t6g(sch_1):p5e_cpu1_p3_tx_c_dp(0)';
NODE_NAME     C1547 1
 '@T6G_MB_LIB.T6G(SCH_1):PAGE355_I53@PURE_QUANTA.Q_CAP_DIFFBUS(CHIPS)':
 '1': CDS_PINID='\1\';
NODE_NAME     U6017 EY35
 '@T6G_MB_LIB.T6G(SCH_1):PAGE458_I38@PURE_QUANTA.PT5161LRS(CHIPS)':
 'B_PERN15': CDS_PINID='B_PERN15';
NET_NAME
'P5E_CPU1_P3_TX_C_DP<10>'
 '@T6G_MB_LIB.T6G(SCH_1):P5E_CPU1_P3_TX_C_DP'<10>:
 C_SIGNAL='@t6g_mb_lib.t6g(sch_1):p5e_cpu1_p3_tx_c_dp(10)';
NODE_NAME     C1527 1
 '@T6G_MB_LIB.T6G(SCH_1):PAGE355_I82@PURE_QUANTA.Q_CAP_DIFFBUS(CHIPS)':
 '1': CDS_PINID='\1\';
NODE_NAME     U6017 BK35
 '@T6G_MB_LIB.T6G(SCH_1):PAGE458_I1@PURE_QUANTA.PT5161LRS(CHIPS)':
 'B_PERN5': CDS_PINID='B_PERN5';
NET_NAME
'P5E_CPU1_P3_TX_C_DP<11>'
 '@T6G_MB_LIB.T6G(SCH_1):P5E_CPU1_P3_TX_C_DP'<11>:
 C_SIGNAL='@t6g_mb_lib.t6g(sch_1):p5e_cpu1_p3_tx_c_dp(11)';
NODE_NAME     C1525 1
 '@T6G_MB_LIB.T6G(SCH_1):PAGE355_I83@PURE_QUANTA.Q_CAP_DIFFBUS(CHIPS)':
 '1': CDS_PINID='\1\';
NODE_NAME     U6017 BC35
 '@T6G_MB_LIB.T6G(SCH_1):PAGE458_I1@PURE_QUANTA.PT5161LRS(CHIPS)':
 'B_PERN4': CDS_PINID='B_PERN4';
NET_NAME
'P5E_CPU1_P3_TX_C_DP<12>'
 '@T6G_MB_LIB.T6G(SCH_1):P5E_CPU1_P3_TX_C_DP'<12>:
 C_SIGNAL='@t6g_mb_lib.t6g(sch_1):p5e_cpu1_p3_tx_c_dp(12)';
NODE_NAME     C55 1
 '@T6G_MB_LIB.T6G(SCH_1):PAGE355_I85@PURE_QUANTA.Q_CAP_DIFFBUS(CHIPS)':
 '1': CDS_PINID='\1\';
NODE_NAME     U6017 AT35
 '@T6G_MB_LIB.T6G(SCH_1):PAGE458_I1@PURE_QUANTA.PT5161LRS(CHIPS)':
 'B_PERN3': CDS_PINID='B_PERN3';
NET_NAME
'P5E_CPU1_P3_TX_C_DP<13>'
 '@T6G_MB_LIB.T6G(SCH_1):P5E_CPU1_P3_TX_C_DP'<13>:
 C_SIGNAL='@t6g_mb_lib.t6g(sch_1):p5e_cpu1_p3_tx_c_dp(13)';
NODE_NAME     C53 1
 '@T6G_MB_LIB.T6G(SCH_1):PAGE355_I107@PURE_QUANTA.Q_CAP_DIFFBUS(CHIPS)':
 '1': CDS_PINID='\1\';
NODE_NAME     U6017 AJ35
 '@T6G_MB_LIB.T6G(SCH_1):PAGE458_I1@PURE_QUANTA.PT5161LRS(CHIPS)':
 'B_PERN2': CDS_PINID='B_PERN2';
NET_NAME
'P5E_CPU1_P3_TX_C_DP<14>'
 '@T6G_MB_LIB.T6G(SCH_1):P5E_CPU1_P3_TX_C_DP'<14>:
 C_SIGNAL='@t6g_mb_lib.t6g(sch_1):p5e_cpu1_p3_tx_c_dp(14)';
NODE_NAME     C51 1
 '@T6G_MB_LIB.T6G(SCH_1):PAGE355_I117@PURE_QUANTA.Q_CAP_DIFFBUS(CHIPS)':
 '1': CDS_PINID='\1\';
NODE_NAME     U6017 Y34
 '@T6G_MB_LIB.T6G(SCH_1):PAGE458_I1@PURE_QUANTA.PT5161LRS(CHIPS)':
 'B_PERP1': CDS_PINID='B_PERP1';
NET_NAME
'P5E_CPU1_P3_TX_C_DP<15>'
 '@T6G_MB_LIB.T6G(SCH_1):P5E_CPU1_P3_TX_C_DP'<15>:
 C_SIGNAL='@t6g_mb_lib.t6g(sch_1):p5e_cpu1_p3_tx_c_dp(15)';
NODE_NAME     C49 1
 '@T6G_MB_LIB.T6G(SCH_1):PAGE355_I120@PURE_QUANTA.Q_CAP_DIFFBUS(CHIPS)':
 '1': CDS_PINID='\1\';
NODE_NAME     U6017 R35
 '@T6G_MB_LIB.T6G(SCH_1):PAGE458_I1@PURE_QUANTA.PT5161LRS(CHIPS)':
 'B_PERN0': CDS_PINID='B_PERN0';
NET_NAME
'P5E_CPU1_P3_TX_C_DP<1>'
 '@T6G_MB_LIB.T6G(SCH_1):P5E_CPU1_P3_TX_C_DP'<1>:
 C_SIGNAL='@t6g_mb_lib.t6g(sch_1):p5e_cpu1_p3_tx_c_dp(1)';
NODE_NAME     C1545 1
 '@T6G_MB_LIB.T6G(SCH_1):PAGE355_I56@PURE_QUANTA.Q_CAP_DIFFBUS(CHIPS)':
 '1': CDS_PINID='\1\';
NODE_NAME     U6017 EL34
 '@T6G_MB_LIB.T6G(SCH_1):PAGE458_I38@PURE_QUANTA.PT5161LRS(CHIPS)':
 'B_PERP14': CDS_PINID='B_PERP14';
NET_NAME
'P5E_CPU1_P3_TX_C_DP<2>'
 '@T6G_MB_LIB.T6G(SCH_1):P5E_CPU1_P3_TX_C_DP'<2>:
 C_SIGNAL='@t6g_mb_lib.t6g(sch_1):p5e_cpu1_p3_tx_c_dp(2)';
NODE_NAME     C1543 1
 '@T6G_MB_LIB.T6G(SCH_1):PAGE355_I57@PURE_QUANTA.Q_CAP_DIFFBUS(CHIPS)':
 '1': CDS_PINID='\1\';
NODE_NAME     U6017 EF35
 '@T6G_MB_LIB.T6G(SCH_1):PAGE458_I38@PURE_QUANTA.PT5161LRS(CHIPS)':
 'B_PERN13': CDS_PINID='B_PERN13';
NET_NAME
'P5E_CPU1_P3_TX_C_DP<3>'
 '@T6G_MB_LIB.T6G(SCH_1):P5E_CPU1_P3_TX_C_DP'<3>:
 C_SIGNAL='@t6g_mb_lib.t6g(sch_1):p5e_cpu1_p3_tx_c_dp(3)';
NODE_NAME     C1541 1
 '@T6G_MB_LIB.T6G(SCH_1):PAGE355_I67@PURE_QUANTA.Q_CAP_DIFFBUS(CHIPS)':
 '1': CDS_PINID='\1\';
NODE_NAME     U6017 DW35
 '@T6G_MB_LIB.T6G(SCH_1):PAGE458_I38@PURE_QUANTA.PT5161LRS(CHIPS)':
 'B_PERN12': CDS_PINID='B_PERN12';
NET_NAME
'P5E_CPU1_P3_TX_C_DP<4>'
 '@T6G_MB_LIB.T6G(SCH_1):P5E_CPU1_P3_TX_C_DP'<4>:
 C_SIGNAL='@t6g_mb_lib.t6g(sch_1):p5e_cpu1_p3_tx_c_dp(4)';
NODE_NAME     C1539 1
 '@T6G_MB_LIB.T6G(SCH_1):PAGE355_I69@PURE_QUANTA.Q_CAP_DIFFBUS(CHIPS)':
 '1': CDS_PINID='\1\';
NODE_NAME     U6017 DM35
 '@T6G_MB_LIB.T6G(SCH_1):PAGE458_I38@PURE_QUANTA.PT5161LRS(CHIPS)':
 'B_PERN11': CDS_PINID='B_PERN11';
NET_NAME
'P5E_CPU1_P3_TX_C_DP<5>'
 '@T6G_MB_LIB.T6G(SCH_1):P5E_CPU1_P3_TX_C_DP'<5>:
 C_SIGNAL='@t6g_mb_lib.t6g(sch_1):p5e_cpu1_p3_tx_c_dp(5)';
NODE_NAME     C1537 1
 '@T6G_MB_LIB.T6G(SCH_1):PAGE355_I71@PURE_QUANTA.Q_CAP_DIFFBUS(CHIPS)':
 '1': CDS_PINID='\1\';
NODE_NAME     U6017 DE35
 '@T6G_MB_LIB.T6G(SCH_1):PAGE458_I38@PURE_QUANTA.PT5161LRS(CHIPS)':
 'B_PERN10': CDS_PINID='B_PERN10';
NET_NAME
'P5E_CPU1_P3_TX_C_DP<6>'
 '@T6G_MB_LIB.T6G(SCH_1):P5E_CPU1_P3_TX_C_DP'<6>:
 C_SIGNAL='@t6g_mb_lib.t6g(sch_1):p5e_cpu1_p3_tx_c_dp(6)';
NODE_NAME     C1535 1
 '@T6G_MB_LIB.T6G(SCH_1):PAGE355_I73@PURE_QUANTA.Q_CAP_DIFFBUS(CHIPS)':
 '1': CDS_PINID='\1\';
NODE_NAME     U6017 CV35
 '@T6G_MB_LIB.T6G(SCH_1):PAGE458_I38@PURE_QUANTA.PT5161LRS(CHIPS)':
 'B_PERN9': CDS_PINID='B_PERN9';
NET_NAME
'P5E_CPU1_P3_TX_C_DP<7>'
 '@T6G_MB_LIB.T6G(SCH_1):P5E_CPU1_P3_TX_C_DP'<7>:
 C_SIGNAL='@t6g_mb_lib.t6g(sch_1):p5e_cpu1_p3_tx_c_dp(7)';
NODE_NAME     C1533 1
 '@T6G_MB_LIB.T6G(SCH_1):PAGE355_I75@PURE_QUANTA.Q_CAP_DIFFBUS(CHIPS)':
 '1': CDS_PINID='\1\';
NODE_NAME     U6017 CL35
 '@T6G_MB_LIB.T6G(SCH_1):PAGE458_I38@PURE_QUANTA.PT5161LRS(CHIPS)':
 'B_PERN8': CDS_PINID='B_PERN8';
NET_NAME
'P5E_CPU1_P3_TX_C_DP<8>'
 '@T6G_MB_LIB.T6G(SCH_1):P5E_CPU1_P3_TX_C_DP'<8>:
 C_SIGNAL='@t6g_mb_lib.t6g(sch_1):p5e_cpu1_p3_tx_c_dp(8)';
NODE_NAME     C1531 1
 '@T6G_MB_LIB.T6G(SCH_1):PAGE355_I77@PURE_QUANTA.Q_CAP_DIFFBUS(CHIPS)':
 '1': CDS_PINID='\1\';
NODE_NAME     U6017 CD35
 '@T6G_MB_LIB.T6G(SCH_1):PAGE458_I1@PURE_QUANTA.PT5161LRS(CHIPS)':
 'B_PERN7': CDS_PINID='B_PERN7';
NET_NAME
'P5E_CPU1_P3_TX_C_DP<9>'
 '@T6G_MB_LIB.T6G(SCH_1):P5E_CPU1_P3_TX_C_DP'<9>:
 C_SIGNAL='@t6g_mb_lib.t6g(sch_1):p5e_cpu1_p3_tx_c_dp(9)';
NODE_NAME     C1529 1
 '@T6G_MB_LIB.T6G(SCH_1):PAGE355_I79@PURE_QUANTA.Q_CAP_DIFFBUS(CHIPS)':
 '1': CDS_PINID='\1\';
NODE_NAME     U6017 BU35
 '@T6G_MB_LIB.T6G(SCH_1):PAGE458_I1@PURE_QUANTA.PT5161LRS(CHIPS)':
 'B_PERN6': CDS_PINID='B_PERN6';
NET_NAME
'P5E_CPU1_P3_TX_DN<0>'
 '@T6G_MB_LIB.T6G(SCH_1):P5E_CPU1_P3_TX_DN'<0>:
 C_SIGNAL='@t6g_mb_lib.t6g(sch_1):p5e_cpu1_p3_tx_dn(0)';
NODE_NAME     U26 CD35
 '@T6G_MB_LIB.T6G(SCH_1):PAGE52_I147@PURE_QUANTA.GENOA_SP5(CHIPS)':
 'P3_TXN0': CDS_PINID='P3_TXN0';
NODE_NAME     C1546 2
 '@T6G_MB_LIB.T6G(SCH_1):PAGE355_I54@PURE_QUANTA.Q_CAP_DIFFBUS(CHIPS)':
 '2': CDS_PINID='\2\';
NET_NAME
'P5E_CPU1_P3_TX_DN<10>'
 '@T6G_MB_LIB.T6G(SCH_1):P5E_CPU1_P3_TX_DN'<10>:
 C_SIGNAL='@t6g_mb_lib.t6g(sch_1):p5e_cpu1_p3_tx_dn(10)';
NODE_NAME     U26 CC26
 '@T6G_MB_LIB.T6G(SCH_1):PAGE52_I147@PURE_QUANTA.GENOA_SP5(CHIPS)':
 'P3_TXN10': CDS_PINID='P3_TXN10';
NODE_NAME     C1526 2
 '@T6G_MB_LIB.T6G(SCH_1):PAGE355_I81@PURE_QUANTA.Q_CAP_DIFFBUS(CHIPS)':
 '2': CDS_PINID='\2\';
NET_NAME
'P5E_CPU1_P3_TX_DN<11>'
 '@T6G_MB_LIB.T6G(SCH_1):P5E_CPU1_P3_TX_DN'<11>:
 C_SIGNAL='@t6g_mb_lib.t6g(sch_1):p5e_cpu1_p3_tx_dn(11)';
NODE_NAME     U26 CG26
 '@T6G_MB_LIB.T6G(SCH_1):PAGE52_I147@PURE_QUANTA.GENOA_SP5(CHIPS)':
 'P3_TXN11': CDS_PINID='P3_TXN11';
NODE_NAME     C1524 2
 '@T6G_MB_LIB.T6G(SCH_1):PAGE355_I84@PURE_QUANTA.Q_CAP_DIFFBUS(CHIPS)':
 '2': CDS_PINID='\2\';
NET_NAME
'P5E_CPU1_P3_TX_DN<12>'
 '@T6G_MB_LIB.T6G(SCH_1):P5E_CPU1_P3_TX_DN'<12>:
 C_SIGNAL='@t6g_mb_lib.t6g(sch_1):p5e_cpu1_p3_tx_dn(12)';
NODE_NAME     U26 CE26
 '@T6G_MB_LIB.T6G(SCH_1):PAGE52_I147@PURE_QUANTA.GENOA_SP5(CHIPS)':
 'P3_TXN12': CDS_PINID='P3_TXN12';
NODE_NAME     C54 2
 '@T6G_MB_LIB.T6G(SCH_1):PAGE355_I86@PURE_QUANTA.Q_CAP_DIFFBUS(CHIPS)':
 '2': CDS_PINID='\2\';
NET_NAME
'P5E_CPU1_P3_TX_DN<13>'
 '@T6G_MB_LIB.T6G(SCH_1):P5E_CPU1_P3_TX_DN'<13>:
 C_SIGNAL='@t6g_mb_lib.t6g(sch_1):p5e_cpu1_p3_tx_dn(13)';
NODE_NAME     U26 CC23
 '@T6G_MB_LIB.T6G(SCH_1):PAGE52_I147@PURE_QUANTA.GENOA_SP5(CHIPS)':
 'P3_TXN13': CDS_PINID='P3_TXN13';
NODE_NAME     C52 2
 '@T6G_MB_LIB.T6G(SCH_1):PAGE355_I116@PURE_QUANTA.Q_CAP_DIFFBUS(CHIPS)':
 '2': CDS_PINID='\2\';
NET_NAME
'P5E_CPU1_P3_TX_DN<14>'
 '@T6G_MB_LIB.T6G(SCH_1):P5E_CPU1_P3_TX_DN'<14>:
 C_SIGNAL='@t6g_mb_lib.t6g(sch_1):p5e_cpu1_p3_tx_dn(14)';
NODE_NAME     U26 CG23
 '@T6G_MB_LIB.T6G(SCH_1):PAGE52_I147@PURE_QUANTA.GENOA_SP5(CHIPS)':
 'P3_TXN14': CDS_PINID='P3_TXN14';
NODE_NAME     C50 2
 '@T6G_MB_LIB.T6G(SCH_1):PAGE355_I118@PURE_QUANTA.Q_CAP_DIFFBUS(CHIPS)':
 '2': CDS_PINID='\2\';
NET_NAME
'P5E_CPU1_P3_TX_DN<15>'
 '@T6G_MB_LIB.T6G(SCH_1):P5E_CPU1_P3_TX_DN'<15>:
 C_SIGNAL='@t6g_mb_lib.t6g(sch_1):p5e_cpu1_p3_tx_dn(15)';
NODE_NAME     U26 CE23
 '@T6G_MB_LIB.T6G(SCH_1):PAGE52_I147@PURE_QUANTA.GENOA_SP5(CHIPS)':
 'P3_TXN15': CDS_PINID='P3_TXN15';
NODE_NAME     C48 2
 '@T6G_MB_LIB.T6G(SCH_1):PAGE355_I119@PURE_QUANTA.Q_CAP_DIFFBUS(CHIPS)':
 '2': CDS_PINID='\2\';
NET_NAME
'P5E_CPU1_P3_TX_DN<1>'
 '@T6G_MB_LIB.T6G(SCH_1):P5E_CPU1_P3_TX_DN'<1>:
 C_SIGNAL='@t6g_mb_lib.t6g(sch_1):p5e_cpu1_p3_tx_dn(1)';
NODE_NAME     U26 CF35
 '@T6G_MB_LIB.T6G(SCH_1):PAGE52_I147@PURE_QUANTA.GENOA_SP5(CHIPS)':
 'P3_TXN1': CDS_PINID='P3_TXN1';
NODE_NAME     C1544 2
 '@T6G_MB_LIB.T6G(SCH_1):PAGE355_I55@PURE_QUANTA.Q_CAP_DIFFBUS(CHIPS)':
 '2': CDS_PINID='\2\';
NET_NAME
'P5E_CPU1_P3_TX_DN<2>'
 '@T6G_MB_LIB.T6G(SCH_1):P5E_CPU1_P3_TX_DN'<2>:
 C_SIGNAL='@t6g_mb_lib.t6g(sch_1):p5e_cpu1_p3_tx_dn(2)';
NODE_NAME     U26 CH35
 '@T6G_MB_LIB.T6G(SCH_1):PAGE52_I147@PURE_QUANTA.GENOA_SP5(CHIPS)':
 'P3_TXN2': CDS_PINID='P3_TXN2';
NODE_NAME     C1542 2
 '@T6G_MB_LIB.T6G(SCH_1):PAGE355_I58@PURE_QUANTA.Q_CAP_DIFFBUS(CHIPS)':
 '2': CDS_PINID='\2\';
NET_NAME
'P5E_CPU1_P3_TX_DN<3>'
 '@T6G_MB_LIB.T6G(SCH_1):P5E_CPU1_P3_TX_DN'<3>:
 C_SIGNAL='@t6g_mb_lib.t6g(sch_1):p5e_cpu1_p3_tx_dn(3)';
NODE_NAME     U26 CC32
 '@T6G_MB_LIB.T6G(SCH_1):PAGE52_I147@PURE_QUANTA.GENOA_SP5(CHIPS)':
 'P3_TXN3': CDS_PINID='P3_TXN3';
NODE_NAME     C1540 2
 '@T6G_MB_LIB.T6G(SCH_1):PAGE355_I68@PURE_QUANTA.Q_CAP_DIFFBUS(CHIPS)':
 '2': CDS_PINID='\2\';
NET_NAME
'P5E_CPU1_P3_TX_DN<4>'
 '@T6G_MB_LIB.T6G(SCH_1):P5E_CPU1_P3_TX_DN'<4>:
 C_SIGNAL='@t6g_mb_lib.t6g(sch_1):p5e_cpu1_p3_tx_dn(4)';
NODE_NAME     U26 CJ32
 '@T6G_MB_LIB.T6G(SCH_1):PAGE52_I147@PURE_QUANTA.GENOA_SP5(CHIPS)':
 'P3_TXN4': CDS_PINID='P3_TXN4';
NODE_NAME     C1538 2
 '@T6G_MB_LIB.T6G(SCH_1):PAGE355_I70@PURE_QUANTA.Q_CAP_DIFFBUS(CHIPS)':
 '2': CDS_PINID='\2\';
NET_NAME
'P5E_CPU1_P3_TX_DN<5>'
 '@T6G_MB_LIB.T6G(SCH_1):P5E_CPU1_P3_TX_DN'<5>:
 C_SIGNAL='@t6g_mb_lib.t6g(sch_1):p5e_cpu1_p3_tx_dn(5)';
NODE_NAME     U26 CG32
 '@T6G_MB_LIB.T6G(SCH_1):PAGE52_I147@PURE_QUANTA.GENOA_SP5(CHIPS)':
 'P3_TXN5': CDS_PINID='P3_TXN5';
NODE_NAME     C1536 2
 '@T6G_MB_LIB.T6G(SCH_1):PAGE355_I72@PURE_QUANTA.Q_CAP_DIFFBUS(CHIPS)':
 '2': CDS_PINID='\2\';
NET_NAME
'P5E_CPU1_P3_TX_DN<6>'
 '@T6G_MB_LIB.T6G(SCH_1):P5E_CPU1_P3_TX_DN'<6>:
 C_SIGNAL='@t6g_mb_lib.t6g(sch_1):p5e_cpu1_p3_tx_dn(6)';
NODE_NAME     U26 CE32
 '@T6G_MB_LIB.T6G(SCH_1):PAGE52_I147@PURE_QUANTA.GENOA_SP5(CHIPS)':
 'P3_TXN6': CDS_PINID='P3_TXN6';
NODE_NAME     C1534 2
 '@T6G_MB_LIB.T6G(SCH_1):PAGE355_I74@PURE_QUANTA.Q_CAP_DIFFBUS(CHIPS)':
 '2': CDS_PINID='\2\';
NET_NAME
'P5E_CPU1_P3_TX_DN<7>'
 '@T6G_MB_LIB.T6G(SCH_1):P5E_CPU1_P3_TX_DN'<7>:
 C_SIGNAL='@t6g_mb_lib.t6g(sch_1):p5e_cpu1_p3_tx_dn(7)';
NODE_NAME     U26 CC29
 '@T6G_MB_LIB.T6G(SCH_1):PAGE52_I147@PURE_QUANTA.GENOA_SP5(CHIPS)':
 'P3_TXN7': CDS_PINID='P3_TXN7';
NODE_NAME     C1532 2
 '@T6G_MB_LIB.T6G(SCH_1):PAGE355_I76@PURE_QUANTA.Q_CAP_DIFFBUS(CHIPS)':
 '2': CDS_PINID='\2\';
NET_NAME
'P5E_CPU1_P3_TX_DN<8>'
 '@T6G_MB_LIB.T6G(SCH_1):P5E_CPU1_P3_TX_DN'<8>:
 C_SIGNAL='@t6g_mb_lib.t6g(sch_1):p5e_cpu1_p3_tx_dn(8)';
NODE_NAME     U26 CG29
 '@T6G_MB_LIB.T6G(SCH_1):PAGE52_I147@PURE_QUANTA.GENOA_SP5(CHIPS)':
 'P3_TXN8': CDS_PINID='P3_TXN8';
NODE_NAME     C1530 2
 '@T6G_MB_LIB.T6G(SCH_1):PAGE355_I78@PURE_QUANTA.Q_CAP_DIFFBUS(CHIPS)':
 '2': CDS_PINID='\2\';
NET_NAME
'P5E_CPU1_P3_TX_DN<9>'
 '@T6G_MB_LIB.T6G(SCH_1):P5E_CPU1_P3_TX_DN'<9>:
 C_SIGNAL='@t6g_mb_lib.t6g(sch_1):p5e_cpu1_p3_tx_dn(9)';
NODE_NAME     U26 CE29
 '@T6G_MB_LIB.T6G(SCH_1):PAGE52_I147@PURE_QUANTA.GENOA_SP5(CHIPS)':
 'P3_TXN9': CDS_PINID='P3_TXN9';
NODE_NAME     C1528 2
 '@T6G_MB_LIB.T6G(SCH_1):PAGE355_I80@PURE_QUANTA.Q_CAP_DIFFBUS(CHIPS)':
 '2': CDS_PINID='\2\';
NET_NAME
'P5E_CPU1_P3_TX_DP<0>'
 '@T6G_MB_LIB.T6G(SCH_1):P5E_CPU1_P3_TX_DP'<0>:
 C_SIGNAL='@t6g_mb_lib.t6g(sch_1):p5e_cpu1_p3_tx_dp(0)';
NODE_NAME     U26 CD36
 '@T6G_MB_LIB.T6G(SCH_1):PAGE52_I147@PURE_QUANTA.GENOA_SP5(CHIPS)':
 'P3_TXP0': CDS_PINID='P3_TXP0';
NODE_NAME     C1547 2
 '@T6G_MB_LIB.T6G(SCH_1):PAGE355_I53@PURE_QUANTA.Q_CAP_DIFFBUS(CHIPS)':
 '2': CDS_PINID='\2\';
NET_NAME
'P5E_CPU1_P3_TX_DP<10>'
 '@T6G_MB_LIB.T6G(SCH_1):P5E_CPU1_P3_TX_DP'<10>:
 C_SIGNAL='@t6g_mb_lib.t6g(sch_1):p5e_cpu1_p3_tx_dp(10)';
NODE_NAME     U26 CC27
 '@T6G_MB_LIB.T6G(SCH_1):PAGE52_I147@PURE_QUANTA.GENOA_SP5(CHIPS)':
 'P3_TXP10': CDS_PINID='P3_TXP10';
NODE_NAME     C1527 2
 '@T6G_MB_LIB.T6G(SCH_1):PAGE355_I82@PURE_QUANTA.Q_CAP_DIFFBUS(CHIPS)':
 '2': CDS_PINID='\2\';
NET_NAME
'P5E_CPU1_P3_TX_DP<11>'
 '@T6G_MB_LIB.T6G(SCH_1):P5E_CPU1_P3_TX_DP'<11>:
 C_SIGNAL='@t6g_mb_lib.t6g(sch_1):p5e_cpu1_p3_tx_dp(11)';
NODE_NAME     U26 CG27
 '@T6G_MB_LIB.T6G(SCH_1):PAGE52_I147@PURE_QUANTA.GENOA_SP5(CHIPS)':
 'P3_TXP11': CDS_PINID='P3_TXP11';
NODE_NAME     C1525 2
 '@T6G_MB_LIB.T6G(SCH_1):PAGE355_I83@PURE_QUANTA.Q_CAP_DIFFBUS(CHIPS)':
 '2': CDS_PINID='\2\';
NET_NAME
'P5E_CPU1_P3_TX_DP<12>'
 '@T6G_MB_LIB.T6G(SCH_1):P5E_CPU1_P3_TX_DP'<12>:
 C_SIGNAL='@t6g_mb_lib.t6g(sch_1):p5e_cpu1_p3_tx_dp(12)';
NODE_NAME     U26 CE27
 '@T6G_MB_LIB.T6G(SCH_1):PAGE52_I147@PURE_QUANTA.GENOA_SP5(CHIPS)':
 'P3_TXP12': CDS_PINID='P3_TXP12';
NODE_NAME     C55 2
 '@T6G_MB_LIB.T6G(SCH_1):PAGE355_I85@PURE_QUANTA.Q_CAP_DIFFBUS(CHIPS)':
 '2': CDS_PINID='\2\';
NET_NAME
'P5E_CPU1_P3_TX_DP<13>'
 '@T6G_MB_LIB.T6G(SCH_1):P5E_CPU1_P3_TX_DP'<13>:
 C_SIGNAL='@t6g_mb_lib.t6g(sch_1):p5e_cpu1_p3_tx_dp(13)';
NODE_NAME     U26 CC24
 '@T6G_MB_LIB.T6G(SCH_1):PAGE52_I147@PURE_QUANTA.GENOA_SP5(CHIPS)':
 'P3_TXP13': CDS_PINID='P3_TXP13';
NODE_NAME     C53 2
 '@T6G_MB_LIB.T6G(SCH_1):PAGE355_I107@PURE_QUANTA.Q_CAP_DIFFBUS(CHIPS)':
 '2': CDS_PINID='\2\';
NET_NAME
'P5E_CPU1_P3_TX_DP<14>'
 '@T6G_MB_LIB.T6G(SCH_1):P5E_CPU1_P3_TX_DP'<14>:
 C_SIGNAL='@t6g_mb_lib.t6g(sch_1):p5e_cpu1_p3_tx_dp(14)';
NODE_NAME     U26 CG24
 '@T6G_MB_LIB.T6G(SCH_1):PAGE52_I147@PURE_QUANTA.GENOA_SP5(CHIPS)':
 'P3_TXP14': CDS_PINID='P3_TXP14';
NODE_NAME     C51 2
 '@T6G_MB_LIB.T6G(SCH_1):PAGE355_I117@PURE_QUANTA.Q_CAP_DIFFBUS(CHIPS)':
 '2': CDS_PINID='\2\';
NET_NAME
'P5E_CPU1_P3_TX_DP<15>'
 '@T6G_MB_LIB.T6G(SCH_1):P5E_CPU1_P3_TX_DP'<15>:
 C_SIGNAL='@t6g_mb_lib.t6g(sch_1):p5e_cpu1_p3_tx_dp(15)';
NODE_NAME     U26 CE24
 '@T6G_MB_LIB.T6G(SCH_1):PAGE52_I147@PURE_QUANTA.GENOA_SP5(CHIPS)':
 'P3_TXP15': CDS_PINID='P3_TXP15';
NODE_NAME     C49 2
 '@T6G_MB_LIB.T6G(SCH_1):PAGE355_I120@PURE_QUANTA.Q_CAP_DIFFBUS(CHIPS)':
 '2': CDS_PINID='\2\';
NET_NAME
'P5E_CPU1_P3_TX_DP<1>'
 '@T6G_MB_LIB.T6G(SCH_1):P5E_CPU1_P3_TX_DP'<1>:
 C_SIGNAL='@t6g_mb_lib.t6g(sch_1):p5e_cpu1_p3_tx_dp(1)';
NODE_NAME     U26 CF36
 '@T6G_MB_LIB.T6G(SCH_1):PAGE52_I147@PURE_QUANTA.GENOA_SP5(CHIPS)':
 'P3_TXP1': CDS_PINID='P3_TXP1';
NODE_NAME     C1545 2
 '@T6G_MB_LIB.T6G(SCH_1):PAGE355_I56@PURE_QUANTA.Q_CAP_DIFFBUS(CHIPS)':
 '2': CDS_PINID='\2\';
NET_NAME
'P5E_CPU1_P3_TX_DP<2>'
 '@T6G_MB_LIB.T6G(SCH_1):P5E_CPU1_P3_TX_DP'<2>:
 C_SIGNAL='@t6g_mb_lib.t6g(sch_1):p5e_cpu1_p3_tx_dp(2)';
NODE_NAME     U26 CH36
 '@T6G_MB_LIB.T6G(SCH_1):PAGE52_I147@PURE_QUANTA.GENOA_SP5(CHIPS)':
 'P3_TXP2': CDS_PINID='P3_TXP2';
NODE_NAME     C1543 2
 '@T6G_MB_LIB.T6G(SCH_1):PAGE355_I57@PURE_QUANTA.Q_CAP_DIFFBUS(CHIPS)':
 '2': CDS_PINID='\2\';
NET_NAME
'P5E_CPU1_P3_TX_DP<3>'
 '@T6G_MB_LIB.T6G(SCH_1):P5E_CPU1_P3_TX_DP'<3>:
 C_SIGNAL='@t6g_mb_lib.t6g(sch_1):p5e_cpu1_p3_tx_dp(3)';
NODE_NAME     U26 CC33
 '@T6G_MB_LIB.T6G(SCH_1):PAGE52_I147@PURE_QUANTA.GENOA_SP5(CHIPS)':
 'P3_TXP3': CDS_PINID='P3_TXP3';
NODE_NAME     C1541 2
 '@T6G_MB_LIB.T6G(SCH_1):PAGE355_I67@PURE_QUANTA.Q_CAP_DIFFBUS(CHIPS)':
 '2': CDS_PINID='\2\';
NET_NAME
'P5E_CPU1_P3_TX_DP<4>'
 '@T6G_MB_LIB.T6G(SCH_1):P5E_CPU1_P3_TX_DP'<4>:
 C_SIGNAL='@t6g_mb_lib.t6g(sch_1):p5e_cpu1_p3_tx_dp(4)';
NODE_NAME     U26 CJ33
 '@T6G_MB_LIB.T6G(SCH_1):PAGE52_I147@PURE_QUANTA.GENOA_SP5(CHIPS)':
 'P3_TXP4': CDS_PINID='P3_TXP4';
NODE_NAME     C1539 2
 '@T6G_MB_LIB.T6G(SCH_1):PAGE355_I69@PURE_QUANTA.Q_CAP_DIFFBUS(CHIPS)':
 '2': CDS_PINID='\2\';
NET_NAME
'P5E_CPU1_P3_TX_DP<5>'
 '@T6G_MB_LIB.T6G(SCH_1):P5E_CPU1_P3_TX_DP'<5>:
 C_SIGNAL='@t6g_mb_lib.t6g(sch_1):p5e_cpu1_p3_tx_dp(5)';
NODE_NAME     U26 CG33
 '@T6G_MB_LIB.T6G(SCH_1):PAGE52_I147@PURE_QUANTA.GENOA_SP5(CHIPS)':
 'P3_TXP5': CDS_PINID='P3_TXP5';
NODE_NAME     C1537 2
 '@T6G_MB_LIB.T6G(SCH_1):PAGE355_I71@PURE_QUANTA.Q_CAP_DIFFBUS(CHIPS)':
 '2': CDS_PINID='\2\';
NET_NAME
'P5E_CPU1_P3_TX_DP<6>'
 '@T6G_MB_LIB.T6G(SCH_1):P5E_CPU1_P3_TX_DP'<6>:
 C_SIGNAL='@t6g_mb_lib.t6g(sch_1):p5e_cpu1_p3_tx_dp(6)';
NODE_NAME     U26 CE33
 '@T6G_MB_LIB.T6G(SCH_1):PAGE52_I147@PURE_QUANTA.GENOA_SP5(CHIPS)':
 'P3_TXP6': CDS_PINID='P3_TXP6';
NODE_NAME     C1535 2
 '@T6G_MB_LIB.T6G(SCH_1):PAGE355_I73@PURE_QUANTA.Q_CAP_DIFFBUS(CHIPS)':
 '2': CDS_PINID='\2\';
NET_NAME
'P5E_CPU1_P3_TX_DP<7>'
 '@T6G_MB_LIB.T6G(SCH_1):P5E_CPU1_P3_TX_DP'<7>:
 C_SIGNAL='@t6g_mb_lib.t6g(sch_1):p5e_cpu1_p3_tx_dp(7)';
NODE_NAME     U26 CC30
 '@T6G_MB_LIB.T6G(SCH_1):PAGE52_I147@PURE_QUANTA.GENOA_SP5(CHIPS)':
 'P3_TXP7': CDS_PINID='P3_TXP7';
NODE_NAME     C1533 2
 '@T6G_MB_LIB.T6G(SCH_1):PAGE355_I75@PURE_QUANTA.Q_CAP_DIFFBUS(CHIPS)':
 '2': CDS_PINID='\2\';
NET_NAME
'P5E_CPU1_P3_TX_DP<8>'
 '@T6G_MB_LIB.T6G(SCH_1):P5E_CPU1_P3_TX_DP'<8>:
 C_SIGNAL='@t6g_mb_lib.t6g(sch_1):p5e_cpu1_p3_tx_dp(8)';
NODE_NAME     U26 CG30
 '@T6G_MB_LIB.T6G(SCH_1):PAGE52_I147@PURE_QUANTA.GENOA_SP5(CHIPS)':
 'P3_TXP8': CDS_PINID='P3_TXP8';
NODE_NAME     C1531 2
 '@T6G_MB_LIB.T6G(SCH_1):PAGE355_I77@PURE_QUANTA.Q_CAP_DIFFBUS(CHIPS)':
 '2': CDS_PINID='\2\';
NET_NAME
'P5E_CPU1_P3_TX_DP<9>'
 '@T6G_MB_LIB.T6G(SCH_1):P5E_CPU1_P3_TX_DP'<9>:
 C_SIGNAL='@t6g_mb_lib.t6g(sch_1):p5e_cpu1_p3_tx_dp(9)';
NODE_NAME     U26 CE30
 '@T6G_MB_LIB.T6G(SCH_1):PAGE52_I147@PURE_QUANTA.GENOA_SP5(CHIPS)':
 'P3_TXP9': CDS_PINID='P3_TXP9';
NODE_NAME     C1529 2
 '@T6G_MB_LIB.T6G(SCH_1):PAGE355_I79@PURE_QUANTA.Q_CAP_DIFFBUS(CHIPS)':
 '2': CDS_PINID='\2\';
NET_NAME
'P5V'
 '@T6G_MB_LIB.T6G(SCH_1):P5V':
 C_SIGNAL='@t6g_mb_lib.t6g(sch_1):p5v',
 CDS_GLOBAL_NET='TRUE';
NODE_NAME     D1 3
 '@T6G_MB_LIB.T6G(SCH_1):PAGE273_I27@PURE_QUANTA.BAT547F(CHIPS)':
 '3': CDS_PINID='\3\';
NODE_NAME     C1227 1
 '@T6G_MB_LIB.T6G(SCH_1):PAGE273_I41@PURE_QUANTA.Q_CAP(CHIPS)':
 'A': CDS_PINID='A';
NODE_NAME     R4638 1
 '@T6G_MB_LIB.T6G(SCH_1):PAGE273_I45@PURE_QUANTA.Q_RES(CHIPS)':
 'A': CDS_PINID='A';
NODE_NAME     R3102 2
 '@T6G_MB_LIB.T6G(SCH_1):PAGE254_I9@PURE_QUANTA.Q_RES(CHIPS)':
 'B': CDS_PINID='B';
NODE_NAME     Q57 1
 '@T6G_MB_LIB.T6G(SCH_1):PAGE273_I23@PURE_QUANTA.MOSFET_NCH_1D3S(CHIPS)':
 '1': CDS_PINID='\1\';
NODE_NAME     Q57 2
 '@T6G_MB_LIB.T6G(SCH_1):PAGE273_I23@PURE_QUANTA.MOSFET_NCH_1D3S(CHIPS)':
 '2': CDS_PINID='\2\';
NODE_NAME     Q57 3
 '@T6G_MB_LIB.T6G(SCH_1):PAGE273_I23@PURE_QUANTA.MOSFET_NCH_1D3S(CHIPS)':
 '3': CDS_PINID='\3\';
NODE_NAME     C1331 1
 '@T6G_MB_LIB.T6G(SCH_1):PAGE273_I43@PURE_QUANTA.Q_CAP(CHIPS)':
 'A': CDS_PINID='A';
NODE_NAME     R3005 1
 '@T6G_MB_LIB.T6G(SCH_1):PAGE369_I15@PURE_QUANTA.Q_RES(CHIPS)':
 'A': CDS_PINID='A';
NODE_NAME     R4639 1
 '@T6G_MB_LIB.T6G(SCH_1):PAGE273_I74@PURE_QUANTA.Q_RES(CHIPS)':
 'A': CDS_PINID='A';
NODE_NAME     R4640 1
 '@T6G_MB_LIB.T6G(SCH_1):PAGE273_I75@PURE_QUANTA.Q_RES(CHIPS)':
 'A': CDS_PINID='A';
NODE_NAME     R4641 1
 '@T6G_MB_LIB.T6G(SCH_1):PAGE273_I76@PURE_QUANTA.Q_RES(CHIPS)':
 'A': CDS_PINID='A';
NODE_NAME     U100 3
 '@T6G_MB_LIB.T6G(SCH_1):PAGE273_I77@PURE_QUANTA.RT9818C44GV(CHIPS)':
 'VDD': CDS_PINID='VDD';
NODE_NAME     C6122 1
 '@T6G_MB_LIB.T6G(SCH_1):PAGE273_I79@PURE_QUANTA.Q_CAP(CHIPS)':
 'A': CDS_PINID='A';
NODE_NAME     R479 1
 '@T6G_MB_LIB.T6G(SCH_1):PAGE273_I83@PURE_QUANTA.Q_RES(CHIPS)':
 'A': CDS_PINID='A';
NET_NAME
'P5V_ADC'
 '@T6G_MB_LIB.T6G(SCH_1):P5V_ADC':
 C_SIGNAL='@t6g_mb_lib.t6g(sch_1):p5v_adc';
NODE_NAME     R1791 1
 '@T6G_MB_LIB.T6G(SCH_1):PAGE369_I14@PURE_QUANTA.Q_RES(CHIPS)':
 'A': CDS_PINID='A';
NODE_NAME     R3005 2
 '@T6G_MB_LIB.T6G(SCH_1):PAGE369_I15@PURE_QUANTA.Q_RES(CHIPS)':
 'B': CDS_PINID='B';
NODE_NAME     R3686 1
 '@T6G_MB_LIB.T6G(SCH_1):PAGE369_I16@PURE_QUANTA.Q_RES(CHIPS)':
 'A': CDS_PINID='A';
NODE_NAME     R3685 1
 '@T6G_MB_LIB.T6G(SCH_1):PAGE369_I18@PURE_QUANTA.Q_RES(CHIPS)':
 'A': CDS_PINID='A';
NET_NAME
'P5V_ADC_MAM'
 '@T6G_MB_LIB.T6G(SCH_1):P5V_ADC_MAM':
 C_SIGNAL='@t6g_mb_lib.t6g(sch_1):p5v_adc_mam';
NODE_NAME     R3685 2
 '@T6G_MB_LIB.T6G(SCH_1):PAGE369_I18@PURE_QUANTA.Q_RES(CHIPS)':
 'B': CDS_PINID='B';
NODE_NAME     C2044 1
 '@T6G_MB_LIB.T6G(SCH_1):PAGE369_I52@PURE_QUANTA.Q_CAP(CHIPS)':
 'A': CDS_PINID='A';
NODE_NAME     U193 8
 '@T6G_MB_LIB.T6G(SCH_1):PAGE369_I169@PURE_QUANTA.MAX11617EEET(CHIPS)':
 'AIN3': CDS_PINID='AIN3';
NET_NAME
'P5V_ADC_TIC'
 '@T6G_MB_LIB.T6G(SCH_1):P5V_ADC_TIC':
 C_SIGNAL='@t6g_mb_lib.t6g(sch_1):p5v_adc_tic';
NODE_NAME     R3686 2
 '@T6G_MB_LIB.T6G(SCH_1):PAGE369_I16@PURE_QUANTA.Q_RES(CHIPS)':
 'B': CDS_PINID='B';
NODE_NAME     C2049 1
 '@T6G_MB_LIB.T6G(SCH_1):PAGE369_I17@PURE_QUANTA.Q_CAP(CHIPS)':
 'A': CDS_PINID='A';
NODE_NAME     U269 13
 '@T6G_MB_LIB.T6G(SCH_1):PAGE369_I142@PURE_QUANTA.ADC128D818CIMTXNOPB(CHIPS)':
 'IN3': CDS_PINID='IN3';
NET_NAME
'P5V_AUX'
 '@T6G_MB_LIB.T6G(SCH_1):P5V_AUX':
 C_SIGNAL='@t6g_mb_lib.t6g(sch_1):p5v_aux',
 CDS_GLOBAL_NET='TRUE';
NODE_NAME     R820 2
 '@T6G_MB_LIB.T6G(SCH_1):PAGE141_I186@PURE_QUANTA.Q_RES(CHIPS)':
 'B': CDS_PINID='B';
NODE_NAME     R1207 2
 '@T6G_MB_LIB.T6G(SCH_1):PAGE143_I41@PURE_QUANTA.Q_RES(CHIPS)':
 'B': CDS_PINID='B';
NODE_NAME     R1208 2
 '@T6G_MB_LIB.T6G(SCH_1):PAGE143_I42@PURE_QUANTA.Q_RES(CHIPS)':
 'B': CDS_PINID='B';
NODE_NAME     PR445 2
 '@T6G_MB_LIB.T6G(SCH_1):PAGE169_I3@PURE_QUANTA.Q_RES(CHIPS)':
 'B': CDS_PINID='B';
NODE_NAME     PR442 2
 '@T6G_MB_LIB.T6G(SCH_1):PAGE176_I21@PURE_QUANTA.Q_RES(CHIPS)':
 'B': CDS_PINID='B';
NODE_NAME     PR335 2
 '@T6G_MB_LIB.T6G(SCH_1):PAGE186_I3@PURE_QUANTA.Q_RES(CHIPS)':
 'B': CDS_PINID='B';
NODE_NAME     C1042 1
 '@T6G_MB_LIB.T6G(SCH_1):PAGE273_I18@PURE_QUANTA.Q_CAP(CHIPS)':
 'A': CDS_PINID='A';
NODE_NAME     C1170 1
 '@T6G_MB_LIB.T6G(SCH_1):PAGE273_I19@PURE_QUANTA.Q_CAP(CHIPS)':
 'A': CDS_PINID='A';
NODE_NAME     C57 1
 '@T6G_MB_LIB.T6G(SCH_1):PAGE273_I20@PURE_QUANTA.Q_CAP(CHIPS)':
 'A': CDS_PINID='A';
NODE_NAME     Q57 5
 '@T6G_MB_LIB.T6G(SCH_1):PAGE273_I23@PURE_QUANTA.MOSFET_NCH_1D3S(CHIPS)':
 '5': CDS_PINID='\5\';
NODE_NAME     PC1877 2
 '@T6G_MB_LIB.T6G(SCH_1):PAGE244_I20@PURE_QUANTA.Q_CAP(CHIPS)':
 'B': CDS_PINID='B';
NODE_NAME     PR8092 2
 '@T6G_MB_LIB.T6G(SCH_1):PAGE244_I27@PURE_QUANTA.Q_RES(CHIPS)':
 'B': CDS_PINID='B';
NODE_NAME     PL8065 2
 '@T6G_MB_LIB.T6G(SCH_1):PAGE244_I28@PURE_QUANTA.Q_INDUCTOR(CHIPS)':
 '2': CDS_PINID='\2\';
NODE_NAME     PC1845 1
 '@T6G_MB_LIB.T6G(SCH_1):PAGE244_I30@PURE_QUANTA.Q_CAPP(CHIPS)':
 'A': CDS_PINID='A';
NODE_NAME     PC1855 1
 '@T6G_MB_LIB.T6G(SCH_1):PAGE244_I31@PURE_QUANTA.Q_CAP(CHIPS)':
 'A': CDS_PINID='A';
NODE_NAME     PC1856 1
 '@T6G_MB_LIB.T6G(SCH_1):PAGE244_I32@PURE_QUANTA.Q_CAP(CHIPS)':
 'A': CDS_PINID='A';
NODE_NAME     PC1852 1
 '@T6G_MB_LIB.T6G(SCH_1):PAGE244_I34@PURE_QUANTA.Q_CAP(CHIPS)':
 'A': CDS_PINID='A';
NODE_NAME     PR290 1
 '@T6G_MB_LIB.T6G(SCH_1):PAGE168_I15@PURE_QUANTA.Q_RES(CHIPS)':
 'A': CDS_PINID='A';
NODE_NAME     PR53 1
 '@T6G_MB_LIB.T6G(SCH_1):PAGE175_I9@PURE_QUANTA.Q_RES(CHIPS)':
 'A': CDS_PINID='A';
NODE_NAME     PR113 1
 '@T6G_MB_LIB.T6G(SCH_1):PAGE182_I2@PURE_QUANTA.Q_RES(CHIPS)':
 'A': CDS_PINID='A';
NODE_NAME     PR411 2
 '@T6G_MB_LIB.T6G(SCH_1):PAGE183_I85@PURE_QUANTA.Q_RES(CHIPS)':
 'B': CDS_PINID='B';
NODE_NAME     PR157 1
 '@T6G_MB_LIB.T6G(SCH_1):PAGE185_I14@PURE_QUANTA.Q_RES(CHIPS)':
 'A': CDS_PINID='A';
NODE_NAME     PR230 1
 '@T6G_MB_LIB.T6G(SCH_1):PAGE192_I9@PURE_QUANTA.Q_RES(CHIPS)':
 'A': CDS_PINID='A';
NODE_NAME     PR340 2
 '@T6G_MB_LIB.T6G(SCH_1):PAGE193_I89@PURE_QUANTA.Q_RES(CHIPS)':
 'B': CDS_PINID='B';
NODE_NAME     PR376 1
 '@T6G_MB_LIB.T6G(SCH_1):PAGE199_I2@PURE_QUANTA.Q_RES(CHIPS)':
 'A': CDS_PINID='A';
NODE_NAME     PR387 2
 '@T6G_MB_LIB.T6G(SCH_1):PAGE200_I3@PURE_QUANTA.Q_RES(CHIPS)':
 'B': CDS_PINID='B';
NODE_NAME     R130 2
 '@T6G_MB_LIB.T6G(SCH_1):PAGE349_I113@PURE_QUANTA.Q_RES(CHIPS)':
 'B': CDS_PINID='B';
NODE_NAME     R4450 2
 '@T6G_MB_LIB.T6G(SCH_1):PAGE153_I27@PURE_QUANTA.Q_RES(CHIPS)':
 'B': CDS_PINID='B';
NODE_NAME     C6027 1
 '@T6G_MB_LIB.T6G(SCH_1):PAGE153_I28@PURE_QUANTA.Q_CAP(CHIPS)':
 'A': CDS_PINID='A';
NODE_NAME     C6028 1
 '@T6G_MB_LIB.T6G(SCH_1):PAGE153_I29@PURE_QUANTA.Q_CAP(CHIPS)':
 'A': CDS_PINID='A';
NODE_NAME     R6208 1
 '@T6G_MB_LIB.T6G(SCH_1):PAGE153_I47@PURE_QUANTA.Q_RES(CHIPS)':
 'A': CDS_PINID='A';
NODE_NAME     R6318 1
 '@T6G_MB_LIB.T6G(SCH_1):PAGE155_I123@PURE_QUANTA.Q_RES(CHIPS)':
 'A': CDS_PINID='A';
NODE_NAME     PR6604 1
 '@T6G_MB_LIB.T6G(SCH_1):PAGE475_I178@PURE_QUANTA.Q_RES(CHIPS)':
 'A': CDS_PINID='A';
NODE_NAME     PR6550 1
 '@T6G_MB_LIB.T6G(SCH_1):PAGE476_I183@PURE_QUANTA.Q_RES(CHIPS)':
 'A': CDS_PINID='A';
NODE_NAME     PR885 1
 '@T6G_MB_LIB.T6G(SCH_1):PAGE477_I7@PURE_QUANTA.Q_RES(CHIPS)':
 'A': CDS_PINID='A';
NODE_NAME     PR6619 1
 '@T6G_MB_LIB.T6G(SCH_1):PAGE478_I42@PURE_QUANTA.Q_RES(CHIPS)':
 'A': CDS_PINID='A';
NODE_NAME     R1238 1
 '@T6G_MB_LIB.T6G(SCH_1):PAGE263_I13@PURE_QUANTA.Q_RES(CHIPS)':
 'A': CDS_PINID='A';
NET_NAME
'P5V_AUX_ADC'
 '@T6G_MB_LIB.T6G(SCH_1):P5V_AUX_ADC':
 C_SIGNAL='@t6g_mb_lib.t6g(sch_1):p5v_aux_adc';
NODE_NAME     R1226 1
 '@T6G_MB_LIB.T6G(SCH_1):PAGE263_I12@PURE_QUANTA.Q_RES(CHIPS)':
 'A': CDS_PINID='A';
NODE_NAME     R1238 2
 '@T6G_MB_LIB.T6G(SCH_1):PAGE263_I13@PURE_QUANTA.Q_RES(CHIPS)':
 'B': CDS_PINID='B';
NODE_NAME     R1263 1
 '@T6G_MB_LIB.T6G(SCH_1):PAGE263_I15@PURE_QUANTA.Q_RES(CHIPS)':
 'A': CDS_PINID='A';
NODE_NAME     R1260 1
 '@T6G_MB_LIB.T6G(SCH_1):PAGE263_I16@PURE_QUANTA.Q_RES(CHIPS)':
 'A': CDS_PINID='A';
NET_NAME
'P5V_AUX_ADC_MAM'
 '@T6G_MB_LIB.T6G(SCH_1):P5V_AUX_ADC_MAM':
 C_SIGNAL='@t6g_mb_lib.t6g(sch_1):p5v_aux_adc_mam';
NODE_NAME     R1260 2
 '@T6G_MB_LIB.T6G(SCH_1):PAGE263_I16@PURE_QUANTA.Q_RES(CHIPS)':
 'B': CDS_PINID='B';
NODE_NAME     C1085 1
 '@T6G_MB_LIB.T6G(SCH_1):PAGE263_I45@PURE_QUANTA.Q_CAP(CHIPS)':
 'A': CDS_PINID='A';
NODE_NAME     U50 5
 '@T6G_MB_LIB.T6G(SCH_1):PAGE263_I156@PURE_QUANTA.MAX11617EEET(CHIPS)':
 'AIN0': CDS_PINID='AIN0';
NET_NAME
'P5V_AUX_ADC_TIC'
 '@T6G_MB_LIB.T6G(SCH_1):P5V_AUX_ADC_TIC':
 C_SIGNAL='@t6g_mb_lib.t6g(sch_1):p5v_aux_adc_tic';
NODE_NAME     R1263 2
 '@T6G_MB_LIB.T6G(SCH_1):PAGE263_I15@PURE_QUANTA.Q_RES(CHIPS)':
 'B': CDS_PINID='B';
NODE_NAME     C1093 1
 '@T6G_MB_LIB.T6G(SCH_1):PAGE263_I43@PURE_QUANTA.Q_CAP(CHIPS)':
 'A': CDS_PINID='A';
NODE_NAME     U51 16
 '@T6G_MB_LIB.T6G(SCH_1):PAGE263_I142@PURE_QUANTA.ADC128D818CIMTXNOPB(CHIPS)':
 'IN0': CDS_PINID='IN0';
NET_NAME
'P5V_AUX_CS'
 '@T6G_MB_LIB.T6G(SCH_1):P5V_AUX_CS':
 C_SIGNAL='@t6g_mb_lib.t6g(sch_1):p5v_aux_cs';
NODE_NAME     PR8089 1
 '@T6G_MB_LIB.T6G(SCH_1):PAGE244_I15@PURE_QUANTA.Q_RES(CHIPS)':
 'A': CDS_PINID='A';
NODE_NAME     U326 3
 '@T6G_MB_LIB.T6G(SCH_1):PAGE244_I38@PURE_QUANTA.MPQ8633AGLEC807Z(CHIPS)':
 'CS': CDS_PINID='CS';
NET_NAME
'P5V_AUX_EN'
 '@T6G_MB_LIB.T6G(SCH_1):P5V_AUX_EN':
 C_SIGNAL='@t6g_mb_lib.t6g(sch_1):p5v_aux_en';
NODE_NAME     U326 8
 '@T6G_MB_LIB.T6G(SCH_1):PAGE244_I38@PURE_QUANTA.MPQ8633AGLEC807Z(CHIPS)':
 'EN': CDS_PINID='EN';
NODE_NAME     R6097 2
 '@T6G_MB_LIB.T6G(SCH_1):PAGE244_I40@PURE_QUANTA.Q_RES(CHIPS)':
 'B': CDS_PINID='B';
NET_NAME
'P5V_AUX_FB'
 '@T6G_MB_LIB.T6G(SCH_1):P5V_AUX_FB':
 C_SIGNAL='@t6g_mb_lib.t6g(sch_1):p5v_aux_fb';
NODE_NAME     PC1877 1
 '@T6G_MB_LIB.T6G(SCH_1):PAGE244_I20@PURE_QUANTA.Q_CAP(CHIPS)':
 'A': CDS_PINID='A';
NODE_NAME     PR8091 1
 '@T6G_MB_LIB.T6G(SCH_1):PAGE244_I23@PURE_QUANTA.Q_RES(CHIPS)':
 'A': CDS_PINID='A';
NODE_NAME     PR8092 1
 '@T6G_MB_LIB.T6G(SCH_1):PAGE244_I27@PURE_QUANTA.Q_RES(CHIPS)':
 'A': CDS_PINID='A';
NODE_NAME     U326 7
 '@T6G_MB_LIB.T6G(SCH_1):PAGE244_I38@PURE_QUANTA.MPQ8633AGLEC807Z(CHIPS)':
 'FB': CDS_PINID='FB';
NET_NAME
'P5V_AUX_MODE'
 '@T6G_MB_LIB.T6G(SCH_1):P5V_AUX_MODE':
 C_SIGNAL='@t6g_mb_lib.t6g(sch_1):p5v_aux_mode';
NODE_NAME     PR3337 1
 '@T6G_MB_LIB.T6G(SCH_1):PAGE244_I37@PURE_QUANTA.Q_RES(CHIPS)':
 'A': CDS_PINID='A';
NODE_NAME     U326 4
 '@T6G_MB_LIB.T6G(SCH_1):PAGE244_I38@PURE_QUANTA.MPQ8633AGLEC807Z(CHIPS)':
 'MODE': CDS_PINID='MODE';
NET_NAME
'P5V_AUX_REF'
 '@T6G_MB_LIB.T6G(SCH_1):P5V_AUX_REF':
 C_SIGNAL='@t6g_mb_lib.t6g(sch_1):p5v_aux_ref';
NODE_NAME     PC1853 1
 '@T6G_MB_LIB.T6G(SCH_1):PAGE244_I19@PURE_QUANTA.Q_CAP(CHIPS)':
 'A': CDS_PINID='A';
NODE_NAME     U326 5
 '@T6G_MB_LIB.T6G(SCH_1):PAGE244_I38@PURE_QUANTA.MPQ8633AGLEC807Z(CHIPS)':
 'TRK_REF': CDS_PINID='TRK_REF';
NET_NAME
'P5V_AUX_VCC'
 '@T6G_MB_LIB.T6G(SCH_1):P5V_AUX_VCC':
 C_SIGNAL='@t6g_mb_lib.t6g(sch_1):p5v_aux_vcc',
 CDS_GLOBAL_NET='TRUE';
NODE_NAME     PC1848 1
 '@T6G_MB_LIB.T6G(SCH_1):PAGE244_I8@PURE_QUANTA.Q_CAP(CHIPS)':
 'A': CDS_PINID='A';
NODE_NAME     R2356 1
 '@T6G_MB_LIB.T6G(SCH_1):PAGE244_I25@PURE_QUANTA.Q_RES(CHIPS)':
 'A': CDS_PINID='A';
NODE_NAME     U326 19
 '@T6G_MB_LIB.T6G(SCH_1):PAGE244_I38@PURE_QUANTA.MPQ8633AGLEC807Z(CHIPS)':
 'VCC': CDS_PINID='VCC';
NODE_NAME     R2343 1
 '@T6G_MB_LIB.T6G(SCH_1):PAGE84_I63@PURE_QUANTA.Q_RES(CHIPS)':
 'A': CDS_PINID='A';
NET_NAME
'P5V_STBY_PWR_LED'
 '@T6G_MB_LIB.T6G(SCH_1):P5V_STBY_PWR_LED':
 C_SIGNAL='@t6g_mb_lib.t6g(sch_1):p5v_stby_pwr_led';
NODE_NAME     D49 A
 '@T6G_MB_LIB.T6G(SCH_1):PAGE143_I38@PURE_QUANTA.Q_LED(CHIPS)':
 'A': CDS_PINID='A';
NODE_NAME     R1207 1
 '@T6G_MB_LIB.T6G(SCH_1):PAGE143_I41@PURE_QUANTA.Q_RES(CHIPS)':
 'A': CDS_PINID='A';
NET_NAME
'PCA9548_PCIE0_ADDR0'
 '@T6G_MB_LIB.T6G(SCH_1):PCA9548_PCIE0_ADDR0':
 C_SIGNAL='@t6g_mb_lib.t6g(sch_1):pca9548_pcie0_addr0';
NODE_NAME     R3709 1
 '@T6G_MB_LIB.T6G(SCH_1):PAGE251_I6@PURE_QUANTA.Q_RES(CHIPS)':
 'A': CDS_PINID='A';
NODE_NAME     R3708 2
 '@T6G_MB_LIB.T6G(SCH_1):PAGE251_I10@PURE_QUANTA.Q_RES(CHIPS)':
 'B': CDS_PINID='B';
NODE_NAME     U39 1
 '@T6G_MB_LIB.T6G(SCH_1):PAGE251_I74@PURE_QUANTA.TCA9548APWR(CHIPS)':
 'A0': CDS_PINID='A0';
NET_NAME
'PCA9548_PCIE0_ADDR1'
 '@T6G_MB_LIB.T6G(SCH_1):PCA9548_PCIE0_ADDR1':
 C_SIGNAL='@t6g_mb_lib.t6g(sch_1):pca9548_pcie0_addr1';
NODE_NAME     R3707 1
 '@T6G_MB_LIB.T6G(SCH_1):PAGE251_I4@PURE_QUANTA.Q_RES(CHIPS)':
 'A': CDS_PINID='A';
NODE_NAME     R3706 2
 '@T6G_MB_LIB.T6G(SCH_1):PAGE251_I8@PURE_QUANTA.Q_RES(CHIPS)':
 'B': CDS_PINID='B';
NODE_NAME     U39 2
 '@T6G_MB_LIB.T6G(SCH_1):PAGE251_I74@PURE_QUANTA.TCA9548APWR(CHIPS)':
 'A1': CDS_PINID='A1';
NET_NAME
'PCA9548_PCIE0_ADDR2'
 '@T6G_MB_LIB.T6G(SCH_1):PCA9548_PCIE0_ADDR2':
 C_SIGNAL='@t6g_mb_lib.t6g(sch_1):pca9548_pcie0_addr2';
NODE_NAME     R3704 1
 '@T6G_MB_LIB.T6G(SCH_1):PAGE251_I1@PURE_QUANTA.Q_RES(CHIPS)':
 'A': CDS_PINID='A';
NODE_NAME     R3703 2
 '@T6G_MB_LIB.T6G(SCH_1):PAGE251_I7@PURE_QUANTA.Q_RES(CHIPS)':
 'B': CDS_PINID='B';
NODE_NAME     U39 21
 '@T6G_MB_LIB.T6G(SCH_1):PAGE251_I74@PURE_QUANTA.TCA9548APWR(CHIPS)':
 'A2': CDS_PINID='A2';
NET_NAME
'PCA9548_PCIE3_ADDR0'
 '@T6G_MB_LIB.T6G(SCH_1):PCA9548_PCIE3_ADDR0':
 C_SIGNAL='@t6g_mb_lib.t6g(sch_1):pca9548_pcie3_addr0';
NODE_NAME     R587 1
 '@T6G_MB_LIB.T6G(SCH_1):PAGE252_I6@PURE_QUANTA.Q_RES(CHIPS)':
 'A': CDS_PINID='A';
NODE_NAME     R320 2
 '@T6G_MB_LIB.T6G(SCH_1):PAGE252_I10@PURE_QUANTA.Q_RES(CHIPS)':
 'B': CDS_PINID='B';
NODE_NAME     U36 1
 '@T6G_MB_LIB.T6G(SCH_1):PAGE252_I33@PURE_QUANTA.TCA9548APWR(CHIPS)':
 'A0': CDS_PINID='A0';
NET_NAME
'PCA9548_PCIE3_ADDR1'
 '@T6G_MB_LIB.T6G(SCH_1):PCA9548_PCIE3_ADDR1':
 C_SIGNAL='@t6g_mb_lib.t6g(sch_1):pca9548_pcie3_addr1';
NODE_NAME     R319 1
 '@T6G_MB_LIB.T6G(SCH_1):PAGE252_I4@PURE_QUANTA.Q_RES(CHIPS)':
 'A': CDS_PINID='A';
NODE_NAME     R318 2
 '@T6G_MB_LIB.T6G(SCH_1):PAGE252_I8@PURE_QUANTA.Q_RES(CHIPS)':
 'B': CDS_PINID='B';
NODE_NAME     U36 2
 '@T6G_MB_LIB.T6G(SCH_1):PAGE252_I33@PURE_QUANTA.TCA9548APWR(CHIPS)':
 'A1': CDS_PINID='A1';
NET_NAME
'PCA9548_PCIE3_ADDR2'
 '@T6G_MB_LIB.T6G(SCH_1):PCA9548_PCIE3_ADDR2':
 C_SIGNAL='@t6g_mb_lib.t6g(sch_1):pca9548_pcie3_addr2';
NODE_NAME     R317 1
 '@T6G_MB_LIB.T6G(SCH_1):PAGE252_I2@PURE_QUANTA.Q_RES(CHIPS)':
 'A': CDS_PINID='A';
NODE_NAME     R316 2
 '@T6G_MB_LIB.T6G(SCH_1):PAGE252_I7@PURE_QUANTA.Q_RES(CHIPS)':
 'B': CDS_PINID='B';
NODE_NAME     U36 21
 '@T6G_MB_LIB.T6G(SCH_1):PAGE252_I33@PURE_QUANTA.TCA9548APWR(CHIPS)':
 'A2': CDS_PINID='A2';
NET_NAME
'PCIE_M2_SSD0_PRSNT_N'
 '@T6G_MB_LIB.T6G(SCH_1):PCIE_M2_SSD0_PRSNT_N':
 C_SIGNAL='@t6g_mb_lib.t6g(sch_1):pcie_m2_ssd0_prsnt_n';
NODE_NAME     J59 1
 '@T6G_MB_LIB.T6G(SCH_1):PAGE345_I88@PURE_QUANTA.SCONN75K_APCI0155P004A(CHIPS)':
 'GND1': CDS_PINID='GND1';
NODE_NAME     R178 2
 '@T6G_MB_LIB.T6G(SCH_1):PAGE345_I24@PURE_QUANTA.Q_RES(CHIPS)':
 'B': CDS_PINID='B';
NODE_NAME     U18 C8
 '@T6G_MB_LIB.T6G(SCH_1):PAGE79_I94@PURE_QUANTA.LCMXO3LF9400C5BG484C(CHIPS)':
 'PT15A': CDS_PINID='PT15A';
NET_NAME
'PDB_PRSNT_N'
 '@T6G_MB_LIB.T6G(SCH_1):PDB_PRSNT_N':
 C_SIGNAL='@t6g_mb_lib.t6g(sch_1):pdb_prsnt_n';
NODE_NAME     C64 1
 '@T6G_MB_LIB.T6G(SCH_1):PAGE363_I453@PURE_QUANTA.Q_CAP(CHIPS)':
 'A': CDS_PINID='A';
NODE_NAME     J45 D3
 '@T6G_MB_LIB.T6G(SCH_1):PAGE363_I466@PURE_QUANTA.CONN60_101062636003K02LF(CHIPS)':
 'D3': CDS_PINID='D3';
NODE_NAME     R1526 1
 '@T6G_MB_LIB.T6G(SCH_1):PAGE363_I476@PURE_QUANTA.Q_RES(CHIPS)':
 'A': CDS_PINID='A';
NET_NAME
'PDB_PRSNT_R_N'
 '@T6G_MB_LIB.T6G(SCH_1):PDB_PRSNT_R_N':
 C_SIGNAL='@t6g_mb_lib.t6g(sch_1):pdb_prsnt_r_n';
NODE_NAME     C1797 1
 '@T6G_MB_LIB.T6G(SCH_1):PAGE372_I9@PURE_QUANTA.Q_CAP(CHIPS)':
 'A': CDS_PINID='A';
NODE_NAME     R3907 1
 '@T6G_MB_LIB.T6G(SCH_1):PAGE372_I10@PURE_QUANTA.Q_RES(CHIPS)':
 'A': CDS_PINID='A';
NODE_NAME     U290 G
 '@T6G_MB_LIB.T6G(SCH_1):PAGE372_I11@PURE_QUANTA.MOSFET_NCH_GDS_ESD_PROTECTED(CHIPS)':
 'G': CDS_PINID='G';
NODE_NAME     R3923 2
 '@T6G_MB_LIB.T6G(SCH_1):PAGE372_I16@PURE_QUANTA.Q_RES(CHIPS)':
 'B': CDS_PINID='B';
NODE_NAME     JP4003 2
 '@T6G_MB_LIB.T6G(SCH_1):PAGE372_I18@PURE_QUANTA.CONN3_210HP1030BR1(CHIPS)':
 '2': CDS_PINID='\2\';
NODE_NAME     R1526 2
 '@T6G_MB_LIB.T6G(SCH_1):PAGE363_I476@PURE_QUANTA.Q_RES(CHIPS)':
 'B': CDS_PINID='B';
NODE_NAME     C1115 1
 '@T6G_MB_LIB.T6G(SCH_1):PAGE363_I478@PURE_QUANTA.Q_CAP(CHIPS)':
 'A': CDS_PINID='A';
NET_NAME
'PD_BIOS_DEBUG_MODE'
 '@T6G_MB_LIB.T6G(SCH_1):PD_BIOS_DEBUG_MODE':
 C_SIGNAL='@t6g_mb_lib.t6g(sch_1):pd_bios_debug_mode';
NODE_NAME     R1508 2
 '@T6G_MB_LIB.T6G(SCH_1):PAGE144_I6@PURE_QUANTA.Q_RES(CHIPS)':
 'B': CDS_PINID='B';
NODE_NAME     SW1 6
 '@T6G_MB_LIB.T6G(SCH_1):PAGE144_I90@PURE_QUANTA.SW20S_DHNF10FQTR(CHIPS)':
 '6': CDS_PINID='\6\';
NET_NAME
'PD_CHA_CPU0_DIMM0_SAA'
 '@T6G_MB_LIB.T6G(SCH_1):PD_CHA_CPU0_DIMM0_SAA':
 C_SIGNAL='@t6g_mb_lib.t6g(sch_1):pd_cha_cpu0_dimm0_saa';
NODE_NAME     R7 1
 '@T6G_MB_LIB.T6G(SCH_1):PAGE85_I499@PURE_QUANTA.Q_RES(CHIPS)':
 'A':XNET_PINS='3',
 CDS_PINID='A';
NODE_NAME     J1 148
 '@T6G_MB_LIB.T6G(SCH_1):PAGE85_I536@PURE_QUANTA.SCONN288_DDR506112002KQ(CHIPS)':
 'HAS': CDS_PINID='HAS';
NET_NAME
'PD_CHA_CPU1_DIMM0_SAA'
 '@T6G_MB_LIB.T6G(SCH_1):PD_CHA_CPU1_DIMM0_SAA':
 C_SIGNAL='@t6g_mb_lib.t6g(sch_1):pd_cha_cpu1_dimm0_saa';
NODE_NAME     J24 148
 '@T6G_MB_LIB.T6G(SCH_1):PAGE97_I22@PURE_QUANTA.SCONN288_DDR506112002KQ(CHIPS)':
 'HAS': CDS_PINID='HAS';
NODE_NAME     R36 1
 '@T6G_MB_LIB.T6G(SCH_1):PAGE97_I129@PURE_QUANTA.Q_RES(CHIPS)':
 'A':XNET_PINS='3',
 CDS_PINID='A';
NET_NAME
'PD_CHB_CPU0_DIMM_SAA'
 '@T6G_MB_LIB.T6G(SCH_1):PD_CHB_CPU0_DIMM_SAA':
 C_SIGNAL='@t6g_mb_lib.t6g(sch_1):pd_chb_cpu0_dimm_saa';
NODE_NAME     R761 1
 '@T6G_MB_LIB.T6G(SCH_1):PAGE86_I349@PURE_QUANTA.Q_RES(CHIPS)':
 'A': CDS_PINID='A';
NODE_NAME     J15 148
 '@T6G_MB_LIB.T6G(SCH_1):PAGE86_I350@PURE_QUANTA.SCONN288_DDR506112002KQ(CHIPS)':
 'HAS': CDS_PINID='HAS';
NET_NAME
'PD_CHB_CPU1_DIMM_SAA'
 '@T6G_MB_LIB.T6G(SCH_1):PD_CHB_CPU1_DIMM_SAA':
 C_SIGNAL='@t6g_mb_lib.t6g(sch_1):pd_chb_cpu1_dimm_saa';
NODE_NAME     J26 148
 '@T6G_MB_LIB.T6G(SCH_1):PAGE98_I22@PURE_QUANTA.SCONN288_DDR506112002KQ(CHIPS)':
 'HAS': CDS_PINID='HAS';
NODE_NAME     R770 1
 '@T6G_MB_LIB.T6G(SCH_1):PAGE98_I127@PURE_QUANTA.Q_RES(CHIPS)':
 'A': CDS_PINID='A';
NET_NAME
'PD_CHC_CPU0_DIMM_SAA'
 '@T6G_MB_LIB.T6G(SCH_1):PD_CHC_CPU0_DIMM_SAA':
 C_SIGNAL='@t6g_mb_lib.t6g(sch_1):pd_chc_cpu0_dimm_saa';
NODE_NAME     R762 1
 '@T6G_MB_LIB.T6G(SCH_1):PAGE87_I349@PURE_QUANTA.Q_RES(CHIPS)':
 'A': CDS_PINID='A';
NODE_NAME     J17 148
 '@T6G_MB_LIB.T6G(SCH_1):PAGE87_I350@PURE_QUANTA.SCONN288_DDR506112002KQ(CHIPS)':
 'HAS': CDS_PINID='HAS';
NET_NAME
'PD_CHC_CPU1_DIMM_SAA'
 '@T6G_MB_LIB.T6G(SCH_1):PD_CHC_CPU1_DIMM_SAA':
 C_SIGNAL='@t6g_mb_lib.t6g(sch_1):pd_chc_cpu1_dimm_saa';
NODE_NAME     J28 148
 '@T6G_MB_LIB.T6G(SCH_1):PAGE99_I22@PURE_QUANTA.SCONN288_DDR506112002KQ(CHIPS)':
 'HAS': CDS_PINID='HAS';
NODE_NAME     R771 1
 '@T6G_MB_LIB.T6G(SCH_1):PAGE99_I148@PURE_QUANTA.Q_RES(CHIPS)':
 'A': CDS_PINID='A';
NET_NAME
'PD_CHD_CPU0_DIMM_SAA'
 '@T6G_MB_LIB.T6G(SCH_1):PD_CHD_CPU0_DIMM_SAA':
 C_SIGNAL='@t6g_mb_lib.t6g(sch_1):pd_chd_cpu0_dimm_saa';
NODE_NAME     R763 1
 '@T6G_MB_LIB.T6G(SCH_1):PAGE88_I349@PURE_QUANTA.Q_RES(CHIPS)':
 'A': CDS_PINID='A';
NODE_NAME     J19 148
 '@T6G_MB_LIB.T6G(SCH_1):PAGE88_I350@PURE_QUANTA.SCONN288_DDR506112002KQ(CHIPS)':
 'HAS': CDS_PINID='HAS';
NET_NAME
'PD_CHD_CPU1_DIMM_SAA'
 '@T6G_MB_LIB.T6G(SCH_1):PD_CHD_CPU1_DIMM_SAA':
 C_SIGNAL='@t6g_mb_lib.t6g(sch_1):pd_chd_cpu1_dimm_saa';
NODE_NAME     J30 148
 '@T6G_MB_LIB.T6G(SCH_1):PAGE100_I52@PURE_QUANTA.SCONN288_DDR506112002KQ(CHIPS)':
 'HAS': CDS_PINID='HAS';
NODE_NAME     R772 1
 '@T6G_MB_LIB.T6G(SCH_1):PAGE100_I146@PURE_QUANTA.Q_RES(CHIPS)':
 'A': CDS_PINID='A';
NET_NAME
'PD_CHE_CPU0_DIMM_SAA'
 '@T6G_MB_LIB.T6G(SCH_1):PD_CHE_CPU0_DIMM_SAA':
 C_SIGNAL='@t6g_mb_lib.t6g(sch_1):pd_che_cpu0_dimm_saa';
NODE_NAME     R5 1
 '@T6G_MB_LIB.T6G(SCH_1):PAGE89_I331@PURE_QUANTA.Q_RES(CHIPS)':
 'A':XNET_PINS='3',
 CDS_PINID='A';
NODE_NAME     J21 148
 '@T6G_MB_LIB.T6G(SCH_1):PAGE89_I348@PURE_QUANTA.SCONN288_DDR506112002KQ(CHIPS)':
 'HAS': CDS_PINID='HAS';
NET_NAME
'PD_CHE_CPU1_DIMM_SAA'
 '@T6G_MB_LIB.T6G(SCH_1):PD_CHE_CPU1_DIMM_SAA':
 C_SIGNAL='@t6g_mb_lib.t6g(sch_1):pd_che_cpu1_dimm_saa';
NODE_NAME     J32 148
 '@T6G_MB_LIB.T6G(SCH_1):PAGE101_I52@PURE_QUANTA.SCONN288_DDR506112002KQ(CHIPS)':
 'HAS': CDS_PINID='HAS';
NODE_NAME     R6 1
 '@T6G_MB_LIB.T6G(SCH_1):PAGE101_I127@PURE_QUANTA.Q_RES(CHIPS)':
 'A':XNET_PINS='3',
 CDS_PINID='A';
NET_NAME
'PD_CHF_CPU0_DIMM_SAA'
 '@T6G_MB_LIB.T6G(SCH_1):PD_CHF_CPU0_DIMM_SAA':
 C_SIGNAL='@t6g_mb_lib.t6g(sch_1):pd_chf_cpu0_dimm_saa';
NODE_NAME     R764 1
 '@T6G_MB_LIB.T6G(SCH_1):PAGE90_I349@PURE_QUANTA.Q_RES(CHIPS)':
 'A': CDS_PINID='A';
NODE_NAME     J23 148
 '@T6G_MB_LIB.T6G(SCH_1):PAGE90_I350@PURE_QUANTA.SCONN288_DDR506112002KQ(CHIPS)':
 'HAS': CDS_PINID='HAS';
NET_NAME
'PD_CHF_CPU1_DIMM_SAA'
 '@T6G_MB_LIB.T6G(SCH_1):PD_CHF_CPU1_DIMM_SAA':
 C_SIGNAL='@t6g_mb_lib.t6g(sch_1):pd_chf_cpu1_dimm_saa';
NODE_NAME     J33 148
 '@T6G_MB_LIB.T6G(SCH_1):PAGE102_I22@PURE_QUANTA.SCONN288_DDR506112002KQ(CHIPS)':
 'HAS': CDS_PINID='HAS';
NODE_NAME     R773 1
 '@T6G_MB_LIB.T6G(SCH_1):PAGE102_I129@PURE_QUANTA.Q_RES(CHIPS)':
 'A': CDS_PINID='A';
NET_NAME
'PD_CHG_CPU0_DIMM0_SAA'
 '@T6G_MB_LIB.T6G(SCH_1):PD_CHG_CPU0_DIMM0_SAA':
 C_SIGNAL='@t6g_mb_lib.t6g(sch_1):pd_chg_cpu0_dimm0_saa';
NODE_NAME     J16 148
 '@T6G_MB_LIB.T6G(SCH_1):PAGE91_I22@PURE_QUANTA.SCONN288_DDR506112002KQ(CHIPS)':
 'HAS': CDS_PINID='HAS';
NODE_NAME     R35 1
 '@T6G_MB_LIB.T6G(SCH_1):PAGE91_I129@PURE_QUANTA.Q_RES(CHIPS)':
 'A':XNET_PINS='3',
 CDS_PINID='A';
NET_NAME
'PD_CHG_CPU1_DIMM0_SAA'
 '@T6G_MB_LIB.T6G(SCH_1):PD_CHG_CPU1_DIMM0_SAA':
 C_SIGNAL='@t6g_mb_lib.t6g(sch_1):pd_chg_cpu1_dimm0_saa';
NODE_NAME     J102 148
 '@T6G_MB_LIB.T6G(SCH_1):PAGE103_I22@PURE_QUANTA.SCONN288_DDR506112002KQ(CHIPS)':
 'HAS': CDS_PINID='HAS';
NODE_NAME     R37 1
 '@T6G_MB_LIB.T6G(SCH_1):PAGE103_I129@PURE_QUANTA.Q_RES(CHIPS)':
 'A':XNET_PINS='3',
 CDS_PINID='A';
NET_NAME
'PD_CHH_CPU0_DIMM_SAA'
 '@T6G_MB_LIB.T6G(SCH_1):PD_CHH_CPU0_DIMM_SAA':
 C_SIGNAL='@t6g_mb_lib.t6g(sch_1):pd_chh_cpu0_dimm_saa';
NODE_NAME     J69 148
 '@T6G_MB_LIB.T6G(SCH_1):PAGE92_I22@PURE_QUANTA.SCONN288_DDR506112002KQ(CHIPS)':
 'HAS': CDS_PINID='HAS';
NODE_NAME     R765 1
 '@T6G_MB_LIB.T6G(SCH_1):PAGE92_I129@PURE_QUANTA.Q_RES(CHIPS)':
 'A': CDS_PINID='A';
NET_NAME
'PD_CHH_CPU1_DIMM_SAA'
 '@T6G_MB_LIB.T6G(SCH_1):PD_CHH_CPU1_DIMM_SAA':
 C_SIGNAL='@t6g_mb_lib.t6g(sch_1):pd_chh_cpu1_dimm_saa';
NODE_NAME     J27 148
 '@T6G_MB_LIB.T6G(SCH_1):PAGE104_I22@PURE_QUANTA.SCONN288_DDR506112002KQ(CHIPS)':
 'HAS': CDS_PINID='HAS';
NODE_NAME     R774 1
 '@T6G_MB_LIB.T6G(SCH_1):PAGE104_I128@PURE_QUANTA.Q_RES(CHIPS)':
 'A': CDS_PINID='A';
NET_NAME
'PD_CHI_CPU0_DIMM_SAA'
 '@T6G_MB_LIB.T6G(SCH_1):PD_CHI_CPU0_DIMM_SAA':
 C_SIGNAL='@t6g_mb_lib.t6g(sch_1):pd_chi_cpu0_dimm_saa';
NODE_NAME     J18 148
 '@T6G_MB_LIB.T6G(SCH_1):PAGE93_I22@PURE_QUANTA.SCONN288_DDR506112002KQ(CHIPS)':
 'HAS': CDS_PINID='HAS';
NODE_NAME     R766 1
 '@T6G_MB_LIB.T6G(SCH_1):PAGE93_I128@PURE_QUANTA.Q_RES(CHIPS)':
 'A': CDS_PINID='A';
NET_NAME
'PD_CHI_CPU1_DIMM_SAA'
 '@T6G_MB_LIB.T6G(SCH_1):PD_CHI_CPU1_DIMM_SAA':
 C_SIGNAL='@t6g_mb_lib.t6g(sch_1):pd_chi_cpu1_dimm_saa';
NODE_NAME     J100 148
 '@T6G_MB_LIB.T6G(SCH_1):PAGE105_I22@PURE_QUANTA.SCONN288_DDR506112002KQ(CHIPS)':
 'HAS': CDS_PINID='HAS';
NODE_NAME     R775 1
 '@T6G_MB_LIB.T6G(SCH_1):PAGE105_I128@PURE_QUANTA.Q_RES(CHIPS)':
 'A': CDS_PINID='A';
NET_NAME
'PD_CHJ_CPU0_DIMM_SAA'
 '@T6G_MB_LIB.T6G(SCH_1):PD_CHJ_CPU0_DIMM_SAA':
 C_SIGNAL='@t6g_mb_lib.t6g(sch_1):pd_chj_cpu0_dimm_saa';
NODE_NAME     J68 148
 '@T6G_MB_LIB.T6G(SCH_1):PAGE94_I22@PURE_QUANTA.SCONN288_DDR506112002KQ(CHIPS)':
 'HAS': CDS_PINID='HAS';
NODE_NAME     R767 1
 '@T6G_MB_LIB.T6G(SCH_1):PAGE94_I129@PURE_QUANTA.Q_RES(CHIPS)':
 'A': CDS_PINID='A';
NET_NAME
'PD_CHJ_CPU1_DIMM_SAA'
 '@T6G_MB_LIB.T6G(SCH_1):PD_CHJ_CPU1_DIMM_SAA':
 C_SIGNAL='@t6g_mb_lib.t6g(sch_1):pd_chj_cpu1_dimm_saa';
NODE_NAME     J29 148
 '@T6G_MB_LIB.T6G(SCH_1):PAGE106_I22@PURE_QUANTA.SCONN288_DDR506112002KQ(CHIPS)':
 'HAS': CDS_PINID='HAS';
NODE_NAME     R776 1
 '@T6G_MB_LIB.T6G(SCH_1):PAGE106_I127@PURE_QUANTA.Q_RES(CHIPS)':
 'A': CDS_PINID='A';
NET_NAME
'PD_CHK_CPU0_DIMM_SAA'
 '@T6G_MB_LIB.T6G(SCH_1):PD_CHK_CPU0_DIMM_SAA':
 C_SIGNAL='@t6g_mb_lib.t6g(sch_1):pd_chk_cpu0_dimm_saa';
NODE_NAME     J20 148
 '@T6G_MB_LIB.T6G(SCH_1):PAGE95_I22@PURE_QUANTA.SCONN288_DDR506112002KQ(CHIPS)':
 'HAS': CDS_PINID='HAS';
NODE_NAME     R768 1
 '@T6G_MB_LIB.T6G(SCH_1):PAGE95_I129@PURE_QUANTA.Q_RES(CHIPS)':
 'A': CDS_PINID='A';
NET_NAME
'PD_CHK_CPU1_DIMM_SAA'
 '@T6G_MB_LIB.T6G(SCH_1):PD_CHK_CPU1_DIMM_SAA':
 C_SIGNAL='@t6g_mb_lib.t6g(sch_1):pd_chk_cpu1_dimm_saa';
NODE_NAME     J99 148
 '@T6G_MB_LIB.T6G(SCH_1):PAGE107_I22@PURE_QUANTA.SCONN288_DDR506112002KQ(CHIPS)':
 'HAS': CDS_PINID='HAS';
NODE_NAME     R777 1
 '@T6G_MB_LIB.T6G(SCH_1):PAGE107_I136@PURE_QUANTA.Q_RES(CHIPS)':
 'A': CDS_PINID='A';
NET_NAME
'PD_CHL_CPU0_DIMM_SAA'
 '@T6G_MB_LIB.T6G(SCH_1):PD_CHL_CPU0_DIMM_SAA':
 C_SIGNAL='@t6g_mb_lib.t6g(sch_1):pd_chl_cpu0_dimm_saa';
NODE_NAME     J67 148
 '@T6G_MB_LIB.T6G(SCH_1):PAGE96_I22@PURE_QUANTA.SCONN288_DDR506112002KQ(CHIPS)':
 'HAS': CDS_PINID='HAS';
NODE_NAME     R769 1
 '@T6G_MB_LIB.T6G(SCH_1):PAGE96_I127@PURE_QUANTA.Q_RES(CHIPS)':
 'A': CDS_PINID='A';
NET_NAME
'PD_CHL_CPU1_DIMM_SAA'
 '@T6G_MB_LIB.T6G(SCH_1):PD_CHL_CPU1_DIMM_SAA':
 C_SIGNAL='@t6g_mb_lib.t6g(sch_1):pd_chl_cpu1_dimm_saa';
NODE_NAME     J37 148
 '@T6G_MB_LIB.T6G(SCH_1):PAGE108_I22@PURE_QUANTA.SCONN288_DDR506112002KQ(CHIPS)':
 'HAS': CDS_PINID='HAS';
NODE_NAME     R778 1
 '@T6G_MB_LIB.T6G(SCH_1):PAGE108_I136@PURE_QUANTA.Q_RES(CHIPS)':
 'A': CDS_PINID='A';
NET_NAME
'PD_CPU_FRU_WP'
 '@T6G_MB_LIB.T6G(SCH_1):PD_CPU_FRU_WP':
 C_SIGNAL='@t6g_mb_lib.t6g(sch_1):pd_cpu_fru_wp';
NODE_NAME     R44 1
 '@T6G_MB_LIB.T6G(SCH_1):PAGE361_I115@PURE_QUANTA.Q_RES(CHIPS)':
 'A': CDS_PINID='A';
NODE_NAME     U1 7
 '@T6G_MB_LIB.T6G(SCH_1):PAGE361_I97@PURE_QUANTA.M24128BWMN6TP(CHIPS)':
 'WC#': CDS_PINID='\wc#\';
NET_NAME
'PD_ESPI_CPU0_CLK2'
 '@T6G_MB_LIB.T6G(SCH_1):PD_ESPI_CPU0_CLK2':
 C_SIGNAL='@t6g_mb_lib.t6g(sch_1):pd_espi_cpu0_clk2';
NODE_NAME     U25 DF27
 '@T6G_MB_LIB.T6G(SCH_1):PAGE29_I287@PURE_QUANTA.GENOA_SP5(CHIPS)':
 'ESPI_CLK2||AGPIO74': CDS_PINID='\espi_clk2||agpio74\';
NODE_NAME     R742 2
 '@T6G_MB_LIB.T6G(SCH_1):PAGE75_I46@PURE_QUANTA.Q_RES(CHIPS)':
 'B': CDS_PINID='B';
NODE_NAME     R753 2
 '@T6G_MB_LIB.T6G(SCH_1):PAGE75_I75@PURE_QUANTA.Q_RES(CHIPS)':
 'B': CDS_PINID='B';
NET_NAME
'PD_ESPI_CPU1_CLK2'
 '@T6G_MB_LIB.T6G(SCH_1):PD_ESPI_CPU1_CLK2':
 C_SIGNAL='@t6g_mb_lib.t6g(sch_1):pd_espi_cpu1_clk2';
NODE_NAME     U26 DF27
 '@T6G_MB_LIB.T6G(SCH_1):PAGE56_I8@PURE_QUANTA.GENOA_SP5(CHIPS)':
 'ESPI_CLK2||AGPIO74': CDS_PINID='\espi_clk2||agpio74\';
NODE_NAME     R736 2
 '@T6G_MB_LIB.T6G(SCH_1):PAGE75_I89@PURE_QUANTA.Q_RES(CHIPS)':
 'B': CDS_PINID='B';
NODE_NAME     R760 2
 '@T6G_MB_LIB.T6G(SCH_1):PAGE75_I92@PURE_QUANTA.Q_RES(CHIPS)':
 'B': CDS_PINID='B';
NET_NAME
'PD_M2_0_DEVSLP'
 '@T6G_MB_LIB.T6G(SCH_1):PD_M2_0_DEVSLP':
 C_SIGNAL='@t6g_mb_lib.t6g(sch_1):pd_m2_0_devslp';
NODE_NAME     J59 38
 '@T6G_MB_LIB.T6G(SCH_1):PAGE345_I88@PURE_QUANTA.SCONN75K_APCI0155P004A(CHIPS)':
 'DEVSLP': CDS_PINID='DEVSLP';
NODE_NAME     R1605 1
 '@T6G_MB_LIB.T6G(SCH_1):PAGE345_I83@PURE_QUANTA.Q_RES(CHIPS)':
 'A': CDS_PINID='A';
NET_NAME
'PD_MB_FRU_WP'
 '@T6G_MB_LIB.T6G(SCH_1):PD_MB_FRU_WP':
 C_SIGNAL='@t6g_mb_lib.t6g(sch_1):pd_mb_fru_wp';
NODE_NAME     U64 7
 '@T6G_MB_LIB.T6G(SCH_1):PAGE361_I35@PURE_QUANTA.M24128BWMN6TP(CHIPS)':
 'WC#': CDS_PINID='\wc#\';
NODE_NAME     R710 1
 '@T6G_MB_LIB.T6G(SCH_1):PAGE361_I57@PURE_QUANTA.Q_RES(CHIPS)':
 'A': CDS_PINID='A';
NET_NAME
'PD_P2E_BUF2_ENSMB'
 '@T6G_MB_LIB.T6G(SCH_1):PD_P2E_BUF2_ENSMB':
 C_SIGNAL='@t6g_mb_lib.t6g(sch_1):pd_p2e_buf2_ensmb';
NODE_NAME     U6000 3
 '@T6G_MB_LIB.T6G(SCH_1):PAGE111_I1@PURE_QUANTA.DS125BR111RTWR(CHIPS)':
 'ENSMB': CDS_PINID='ENSMB';
NODE_NAME     R6160 1
 '@T6G_MB_LIB.T6G(SCH_1):PAGE111_I12@PURE_QUANTA.Q_RES(CHIPS)':
 'A': CDS_PINID='A';
NET_NAME
'PD_U160_EN_N'
 '@T6G_MB_LIB.T6G(SCH_1):PD_U160_EN_N':
 C_SIGNAL='@t6g_mb_lib.t6g(sch_1):pd_u160_en_n';
NODE_NAME     R1313 1
 '@T6G_MB_LIB.T6G(SCH_1):PAGE148_I383@PURE_QUANTA.Q_RES(CHIPS)':
 'A': CDS_PINID='A';
NODE_NAME     JP6001 3
 '@T6G_MB_LIB.T6G(SCH_1):PAGE148_I387@PURE_QUANTA.CONN3_210HP1030BR1(CHIPS)':
 '3': CDS_PINID='\3\';
NET_NAME
'PD_U212_EN_N'
 '@T6G_MB_LIB.T6G(SCH_1):PD_U212_EN_N':
 C_SIGNAL='@t6g_mb_lib.t6g(sch_1):pd_u212_en_n';
NODE_NAME     R1318 1
 '@T6G_MB_LIB.T6G(SCH_1):PAGE148_I378@PURE_QUANTA.Q_RES(CHIPS)':
 'A': CDS_PINID='A';
NODE_NAME     JP6000 3
 '@T6G_MB_LIB.T6G(SCH_1):PAGE148_I386@PURE_QUANTA.CONN3_210HP1030BR1(CHIPS)':
 '3': CDS_PINID='\3\';
NET_NAME
'PD_U5201_EQ'
 '@T6G_MB_LIB.T6G(SCH_1):PD_U5201_EQ':
 C_SIGNAL='@t6g_mb_lib.t6g(sch_1):pd_u5201_eq';
NODE_NAME     R5238 1
 '@T6G_MB_LIB.T6G(SCH_1):PAGE358_I83@PURE_QUANTA.Q_RES(CHIPS)':
 'A': CDS_PINID='A';
NODE_NAME     U5201 6
 '@T6G_MB_LIB.T6G(SCH_1):PAGE358_I84@PURE_QUANTA.TUSB211IRWBR(CHIPS)':
 'EQ': CDS_PINID='EQ';
NET_NAME
'PD_U5201_RSTN'
 '@T6G_MB_LIB.T6G(SCH_1):PD_U5201_RSTN':
 C_SIGNAL='@t6g_mb_lib.t6g(sch_1):pd_u5201_rstn';
NODE_NAME     C5232 1
 '@T6G_MB_LIB.T6G(SCH_1):PAGE358_I81@PURE_QUANTA.Q_CAP(CHIPS)':
 'A': CDS_PINID='A';
NODE_NAME     U5201 5
 '@T6G_MB_LIB.T6G(SCH_1):PAGE358_I84@PURE_QUANTA.TUSB211IRWBR(CHIPS)':
 'RSTN': CDS_PINID='RSTN';
NET_NAME
'PD_U5201_VREG'
 '@T6G_MB_LIB.T6G(SCH_1):PD_U5201_VREG':
 C_SIGNAL='@t6g_mb_lib.t6g(sch_1):pd_u5201_vreg';
NODE_NAME     U5201 11
 '@T6G_MB_LIB.T6G(SCH_1):PAGE358_I84@PURE_QUANTA.TUSB211IRWBR(CHIPS)':
 'VREG': CDS_PINID='VREG';
NODE_NAME     C5236 1
 '@T6G_MB_LIB.T6G(SCH_1):PAGE358_I87@PURE_QUANTA.Q_CAP(CHIPS)':
 'A': CDS_PINID='A';
NET_NAME
'PD_USB_CPU0_WP'
 '@T6G_MB_LIB.T6G(SCH_1):PD_USB_CPU0_WP':
 C_SIGNAL='@t6g_mb_lib.t6g(sch_1):pd_usb_cpu0_wp';
NODE_NAME     U6003 7
 '@T6G_MB_LIB.T6G(SCH_1):PAGE153_I64@PURE_QUANTA.M24128BWMN6TP(CHIPS)':
 'WC#': CDS_PINID='\wc#\';
NODE_NAME     R6223 1
 '@T6G_MB_LIB.T6G(SCH_1):PAGE153_I77@PURE_QUANTA.Q_RES(CHIPS)':
 'A': CDS_PINID='A';
NET_NAME
'PRSNT0_N'
 '@T6G_MB_LIB.T6G(SCH_1):PRSNT0_N':
 C_SIGNAL='@t6g_mb_lib.t6g(sch_1):prsnt0_n';
NODE_NAME     R1801 1
 '@T6G_MB_LIB.T6G(SCH_1):PAGE348_I171@PURE_QUANTA.Q_RES(CHIPS)':
 'A': CDS_PINID='A';
NODE_NAME     J41 OB3
 '@T6G_MB_LIB.T6G(SCH_1):PAGE348_I176@PURE_QUANTA.SCONN168_ME1016810202011(CHIPS)':
 'LD#': CDS_PINID='\ld#\';
NET_NAME
'PRSNT_CABLE_GPU_A1'
 '@T6G_MB_LIB.T6G(SCH_1):PRSNT_CABLE_GPU_A1':
 C_SIGNAL='@t6g_mb_lib.t6g(sch_1):prsnt_cable_gpu_a1';
NODE_NAME     Q134 6
 '@T6G_MB_LIB.T6G(SCH_1):PAGE332_I6@PURE_QUANTA.MOSFET_NCH_DUAL(CHIPS)':
 'D1': CDS_PINID='D1';
NODE_NAME     R4155 2
 '@T6G_MB_LIB.T6G(SCH_1):PAGE332_I8@PURE_QUANTA.Q_RES(CHIPS)':
 'B': CDS_PINID='B';
NODE_NAME     Q134 5
 '@T6G_MB_LIB.T6G(SCH_1):PAGE332_I10@PURE_QUANTA.MOSFET_NCH_DUAL(CHIPS)':
 'G2': CDS_PINID='G2';
NET_NAME
'PRSNT_CABLE_GPU_A1_ISO_N'
 '@T6G_MB_LIB.T6G(SCH_1):PRSNT_CABLE_GPU_A1_ISO_N':
 C_SIGNAL='@t6g_mb_lib.t6g(sch_1):prsnt_cable_gpu_a1_iso_n';
NODE_NAME     R4157 2
 '@T6G_MB_LIB.T6G(SCH_1):PAGE80_I246@PURE_QUANTA.Q_RES(CHIPS)':
 'B': CDS_PINID='B';
NODE_NAME     R9019 1
 '@T6G_MB_LIB.T6G(SCH_1):PAGE246_I42@PURE_QUANTA.Q_RES(CHIPS)':
 'A': CDS_PINID='A';
NODE_NAME     Q134 3
 '@T6G_MB_LIB.T6G(SCH_1):PAGE332_I10@PURE_QUANTA.MOSFET_NCH_DUAL(CHIPS)':
 'D2': CDS_PINID='D2';
NODE_NAME     R4574 2
 '@T6G_MB_LIB.T6G(SCH_1):PAGE332_I31@PURE_QUANTA.Q_RES(CHIPS)':
 'B': CDS_PINID='B';
NODE_NAME     R4156 2
 '@T6G_MB_LIB.T6G(SCH_1):PAGE332_I48@PURE_QUANTA.Q_RES(CHIPS)':
 'B': CDS_PINID='B';
NODE_NAME     C15 1
 '@T6G_MB_LIB.T6G(SCH_1):PAGE332_I50@PURE_QUANTA.Q_CAP(CHIPS)':
 'A': CDS_PINID='A';
NET_NAME
'PRSNT_CABLE_GPU_A1_ISO_R1_N'
 '@T6G_MB_LIB.T6G(SCH_1):PRSNT_CABLE_GPU_A1_ISO_R1_N':
 C_SIGNAL='@t6g_mb_lib.t6g(sch_1):prsnt_cable_gpu_a1_iso_r1_n';
NODE_NAME     R9019 2
 '@T6G_MB_LIB.T6G(SCH_1):PAGE246_I42@PURE_QUANTA.Q_RES(CHIPS)':
 'B': CDS_PINID='B';
NODE_NAME     U181 19
 '@T6G_MB_LIB.T6G(SCH_1):PAGE246_I83@PURE_QUANTA.PCA9539RPW(CHIPS)':
 'IO1_6': CDS_PINID='IO1_6';
NET_NAME
'PRSNT_CABLE_GPU_A1_ISO_R_N'
 '@T6G_MB_LIB.T6G(SCH_1):PRSNT_CABLE_GPU_A1_ISO_R_N':
 C_SIGNAL='@t6g_mb_lib.t6g(sch_1):prsnt_cable_gpu_a1_iso_r_n';
NODE_NAME     U18 AA14
 '@T6G_MB_LIB.T6G(SCH_1):PAGE80_I216@PURE_QUANTA.LCMXO3LF9400C5BG484C(CHIPS)':
 'PB33B': CDS_PINID='PB33B';
NODE_NAME     R4157 1
 '@T6G_MB_LIB.T6G(SCH_1):PAGE80_I246@PURE_QUANTA.Q_RES(CHIPS)':
 'A': CDS_PINID='A';
NET_NAME
'PRSNT_CABLE_GPU_A1_N'
 '@T6G_MB_LIB.T6G(SCH_1):PRSNT_CABLE_GPU_A1_N':
 C_SIGNAL='@t6g_mb_lib.t6g(sch_1):prsnt_cable_gpu_a1_n';
NODE_NAME     J106 A7
 '@T6G_MB_LIB.T6G(SCH_1):PAGE327_I19@PURE_QUANTA.CONN112_10137002101LF(CHIPS)':
 'A7': CDS_PINID='A7';
NODE_NAME     R4154 1
 '@T6G_MB_LIB.T6G(SCH_1):PAGE332_I2@PURE_QUANTA.Q_RES(CHIPS)':
 'A': CDS_PINID='A';
NODE_NAME     R4153 2
 '@T6G_MB_LIB.T6G(SCH_1):PAGE332_I4@PURE_QUANTA.Q_RES(CHIPS)':
 'B': CDS_PINID='B';
NODE_NAME     Q134 2
 '@T6G_MB_LIB.T6G(SCH_1):PAGE332_I6@PURE_QUANTA.MOSFET_NCH_DUAL(CHIPS)':
 'G1': CDS_PINID='G1';
NODE_NAME     R4574 1
 '@T6G_MB_LIB.T6G(SCH_1):PAGE332_I31@PURE_QUANTA.Q_RES(CHIPS)':
 'A': CDS_PINID='A';
NET_NAME
'PRSNT_CABLE_GPU_A2'
 '@T6G_MB_LIB.T6G(SCH_1):PRSNT_CABLE_GPU_A2':
 C_SIGNAL='@t6g_mb_lib.t6g(sch_1):prsnt_cable_gpu_a2';
NODE_NAME     Q133 6
 '@T6G_MB_LIB.T6G(SCH_1):PAGE332_I98@PURE_QUANTA.MOSFET_NCH_DUAL(CHIPS)':
 'D1': CDS_PINID='D1';
NODE_NAME     R4139 2
 '@T6G_MB_LIB.T6G(SCH_1):PAGE332_I99@PURE_QUANTA.Q_RES(CHIPS)':
 'B': CDS_PINID='B';
NODE_NAME     Q133 5
 '@T6G_MB_LIB.T6G(SCH_1):PAGE332_I120@PURE_QUANTA.MOSFET_NCH_DUAL(CHIPS)':
 'G2': CDS_PINID='G2';
NET_NAME
'PRSNT_CABLE_GPU_A2_ISO_N'
 '@T6G_MB_LIB.T6G(SCH_1):PRSNT_CABLE_GPU_A2_ISO_N':
 C_SIGNAL='@t6g_mb_lib.t6g(sch_1):prsnt_cable_gpu_a2_iso_n';
NODE_NAME     R4147 2
 '@T6G_MB_LIB.T6G(SCH_1):PAGE80_I240@PURE_QUANTA.Q_RES(CHIPS)':
 'B': CDS_PINID='B';
NODE_NAME     R9013 1
 '@T6G_MB_LIB.T6G(SCH_1):PAGE246_I43@PURE_QUANTA.Q_RES(CHIPS)':
 'A': CDS_PINID='A';
NODE_NAME     R4578 2
 '@T6G_MB_LIB.T6G(SCH_1):PAGE332_I103@PURE_QUANTA.Q_RES(CHIPS)':
 'B': CDS_PINID='B';
NODE_NAME     Q133 3
 '@T6G_MB_LIB.T6G(SCH_1):PAGE332_I120@PURE_QUANTA.MOSFET_NCH_DUAL(CHIPS)':
 'D2': CDS_PINID='D2';
NODE_NAME     R4142 2
 '@T6G_MB_LIB.T6G(SCH_1):PAGE332_I122@PURE_QUANTA.Q_RES(CHIPS)':
 'B': CDS_PINID='B';
NODE_NAME     C19 1
 '@T6G_MB_LIB.T6G(SCH_1):PAGE332_I127@PURE_QUANTA.Q_CAP(CHIPS)':
 'A': CDS_PINID='A';
NET_NAME
'PRSNT_CABLE_GPU_A2_ISO_R1_N'
 '@T6G_MB_LIB.T6G(SCH_1):PRSNT_CABLE_GPU_A2_ISO_R1_N':
 C_SIGNAL='@t6g_mb_lib.t6g(sch_1):prsnt_cable_gpu_a2_iso_r1_n';
NODE_NAME     R9013 2
 '@T6G_MB_LIB.T6G(SCH_1):PAGE246_I43@PURE_QUANTA.Q_RES(CHIPS)':
 'B': CDS_PINID='B';
NODE_NAME     U181 13
 '@T6G_MB_LIB.T6G(SCH_1):PAGE246_I83@PURE_QUANTA.PCA9539RPW(CHIPS)':
 'IO1_0': CDS_PINID='IO1_0';
NET_NAME
'PRSNT_CABLE_GPU_A2_ISO_R_N'
 '@T6G_MB_LIB.T6G(SCH_1):PRSNT_CABLE_GPU_A2_ISO_R_N':
 C_SIGNAL='@t6g_mb_lib.t6g(sch_1):prsnt_cable_gpu_a2_iso_r_n';
NODE_NAME     U18 V14
 '@T6G_MB_LIB.T6G(SCH_1):PAGE80_I216@PURE_QUANTA.LCMXO3LF9400C5BG484C(CHIPS)':
 'PB32D': CDS_PINID='PB32D';
NODE_NAME     R4147 1
 '@T6G_MB_LIB.T6G(SCH_1):PAGE80_I240@PURE_QUANTA.Q_RES(CHIPS)':
 'A': CDS_PINID='A';
NET_NAME
'PRSNT_CABLE_GPU_A2_N'
 '@T6G_MB_LIB.T6G(SCH_1):PRSNT_CABLE_GPU_A2_N':
 C_SIGNAL='@t6g_mb_lib.t6g(sch_1):prsnt_cable_gpu_a2_n';
NODE_NAME     J108 A3
 '@T6G_MB_LIB.T6G(SCH_1):PAGE320_I72@PURE_QUANTA.CONN112_10137002101LF(CHIPS)':
 'A3': CDS_PINID='A3';
NODE_NAME     R4136 1
 '@T6G_MB_LIB.T6G(SCH_1):PAGE332_I92@PURE_QUANTA.Q_RES(CHIPS)':
 'A': CDS_PINID='A';
NODE_NAME     R4135 2
 '@T6G_MB_LIB.T6G(SCH_1):PAGE332_I93@PURE_QUANTA.Q_RES(CHIPS)':
 'B': CDS_PINID='B';
NODE_NAME     Q133 2
 '@T6G_MB_LIB.T6G(SCH_1):PAGE332_I98@PURE_QUANTA.MOSFET_NCH_DUAL(CHIPS)':
 'G1': CDS_PINID='G1';
NODE_NAME     R4578 1
 '@T6G_MB_LIB.T6G(SCH_1):PAGE332_I103@PURE_QUANTA.Q_RES(CHIPS)':
 'A': CDS_PINID='A';
NET_NAME
'PRSNT_CABLE_GPU_A3'
 '@T6G_MB_LIB.T6G(SCH_1):PRSNT_CABLE_GPU_A3':
 C_SIGNAL='@t6g_mb_lib.t6g(sch_1):prsnt_cable_gpu_a3';
NODE_NAME     Q9002 6
 '@T6G_MB_LIB.T6G(SCH_1):PAGE330_I52@PURE_QUANTA.MOSFET_NCH_DUAL(CHIPS)':
 'D1': CDS_PINID='D1';
NODE_NAME     R9016 2
 '@T6G_MB_LIB.T6G(SCH_1):PAGE330_I61@PURE_QUANTA.Q_RES(CHIPS)':
 'B': CDS_PINID='B';
NODE_NAME     Q9002 5
 '@T6G_MB_LIB.T6G(SCH_1):PAGE330_I75@PURE_QUANTA.MOSFET_NCH_DUAL(CHIPS)':
 'G2': CDS_PINID='G2';
NET_NAME
'PRSNT_CABLE_GPU_A3_ISO_N'
 '@T6G_MB_LIB.T6G(SCH_1):PRSNT_CABLE_GPU_A3_ISO_N':
 C_SIGNAL='@t6g_mb_lib.t6g(sch_1):prsnt_cable_gpu_a3_iso_n';
NODE_NAME     R9018 1
 '@T6G_MB_LIB.T6G(SCH_1):PAGE246_I44@PURE_QUANTA.Q_RES(CHIPS)':
 'A': CDS_PINID='A';
NODE_NAME     C9002 1
 '@T6G_MB_LIB.T6G(SCH_1):PAGE330_I71@PURE_QUANTA.Q_CAP(CHIPS)':
 'A': CDS_PINID='A';
NODE_NAME     R9017 2
 '@T6G_MB_LIB.T6G(SCH_1):PAGE330_I72@PURE_QUANTA.Q_RES(CHIPS)':
 'B': CDS_PINID='B';
NODE_NAME     Q9002 3
 '@T6G_MB_LIB.T6G(SCH_1):PAGE330_I75@PURE_QUANTA.MOSFET_NCH_DUAL(CHIPS)':
 'D2': CDS_PINID='D2';
NET_NAME
'PRSNT_CABLE_GPU_A3_ISO_R_N'
 '@T6G_MB_LIB.T6G(SCH_1):PRSNT_CABLE_GPU_A3_ISO_R_N':
 C_SIGNAL='@t6g_mb_lib.t6g(sch_1):prsnt_cable_gpu_a3_iso_r_n';
NODE_NAME     R9018 2
 '@T6G_MB_LIB.T6G(SCH_1):PAGE246_I44@PURE_QUANTA.Q_RES(CHIPS)':
 'B': CDS_PINID='B';
NODE_NAME     U181 20
 '@T6G_MB_LIB.T6G(SCH_1):PAGE246_I83@PURE_QUANTA.PCA9539RPW(CHIPS)':
 'IO1_7': CDS_PINID='IO1_7';
NET_NAME
'PRSNT_CABLE_GPU_A3_N'
 '@T6G_MB_LIB.T6G(SCH_1):PRSNT_CABLE_GPU_A3_N':
 C_SIGNAL='@t6g_mb_lib.t6g(sch_1):prsnt_cable_gpu_a3_n';
NODE_NAME     J108 N8
 '@T6G_MB_LIB.T6G(SCH_1):PAGE320_I15@PURE_QUANTA.CONN112_10137002101LF(CHIPS)':
 'N8': CDS_PINID='N8';
NODE_NAME     R9015 1
 '@T6G_MB_LIB.T6G(SCH_1):PAGE330_I50@PURE_QUANTA.Q_RES(CHIPS)':
 'A': CDS_PINID='A';
NODE_NAME     R9014 2
 '@T6G_MB_LIB.T6G(SCH_1):PAGE330_I51@PURE_QUANTA.Q_RES(CHIPS)':
 'B': CDS_PINID='B';
NODE_NAME     Q9002 2
 '@T6G_MB_LIB.T6G(SCH_1):PAGE330_I52@PURE_QUANTA.MOSFET_NCH_DUAL(CHIPS)':
 'G1': CDS_PINID='G1';
NET_NAME
'PRSNT_CABLE_GPU_B3'
 '@T6G_MB_LIB.T6G(SCH_1):PRSNT_CABLE_GPU_B3':
 C_SIGNAL='@t6g_mb_lib.t6g(sch_1):prsnt_cable_gpu_b3';
NODE_NAME     Q132 6
 '@T6G_MB_LIB.T6G(SCH_1):PAGE332_I25@PURE_QUANTA.MOSFET_NCH_DUAL(CHIPS)':
 'D1': CDS_PINID='D1';
NODE_NAME     R4126 2
 '@T6G_MB_LIB.T6G(SCH_1):PAGE332_I27@PURE_QUANTA.Q_RES(CHIPS)':
 'B': CDS_PINID='B';
NODE_NAME     Q132 5
 '@T6G_MB_LIB.T6G(SCH_1):PAGE332_I32@PURE_QUANTA.MOSFET_NCH_DUAL(CHIPS)':
 'G2': CDS_PINID='G2';
NET_NAME
'PRSNT_CABLE_GPU_B3_ISO_N'
 '@T6G_MB_LIB.T6G(SCH_1):PRSNT_CABLE_GPU_B3_ISO_N':
 C_SIGNAL='@t6g_mb_lib.t6g(sch_1):prsnt_cable_gpu_b3_iso_n';
NODE_NAME     R4145 2
 '@T6G_MB_LIB.T6G(SCH_1):PAGE79_I121@PURE_QUANTA.Q_RES(CHIPS)':
 'B': CDS_PINID='B';
NODE_NAME     R9011 1
 '@T6G_MB_LIB.T6G(SCH_1):PAGE246_I45@PURE_QUANTA.Q_RES(CHIPS)':
 'A': CDS_PINID='A';
NODE_NAME     Q132 3
 '@T6G_MB_LIB.T6G(SCH_1):PAGE332_I32@PURE_QUANTA.MOSFET_NCH_DUAL(CHIPS)':
 'D2': CDS_PINID='D2';
NODE_NAME     R4573 2
 '@T6G_MB_LIB.T6G(SCH_1):PAGE332_I33@PURE_QUANTA.Q_RES(CHIPS)':
 'B': CDS_PINID='B';
NODE_NAME     C13 1
 '@T6G_MB_LIB.T6G(SCH_1):PAGE332_I64@PURE_QUANTA.Q_CAP(CHIPS)':
 'A': CDS_PINID='A';
NODE_NAME     R4129 2
 '@T6G_MB_LIB.T6G(SCH_1):PAGE332_I66@PURE_QUANTA.Q_RES(CHIPS)':
 'B': CDS_PINID='B';
NET_NAME
'PRSNT_CABLE_GPU_B3_ISO_R1_N'
 '@T6G_MB_LIB.T6G(SCH_1):PRSNT_CABLE_GPU_B3_ISO_R1_N':
 C_SIGNAL='@t6g_mb_lib.t6g(sch_1):prsnt_cable_gpu_b3_iso_r1_n';
NODE_NAME     R9011 2
 '@T6G_MB_LIB.T6G(SCH_1):PAGE246_I45@PURE_QUANTA.Q_RES(CHIPS)':
 'B': CDS_PINID='B';
NODE_NAME     U181 10
 '@T6G_MB_LIB.T6G(SCH_1):PAGE246_I83@PURE_QUANTA.PCA9539RPW(CHIPS)':
 'IO0_6': CDS_PINID='IO0_6';
NET_NAME
'PRSNT_CABLE_GPU_B3_ISO_R_N'
 '@T6G_MB_LIB.T6G(SCH_1):PRSNT_CABLE_GPU_B3_ISO_R_N':
 C_SIGNAL='@t6g_mb_lib.t6g(sch_1):prsnt_cable_gpu_b3_iso_r_n';
NODE_NAME     U18 G12
 '@T6G_MB_LIB.T6G(SCH_1):PAGE79_I94@PURE_QUANTA.LCMXO3LF9400C5BG484C(CHIPS)':
 'PT28A': CDS_PINID='PT28A';
NODE_NAME     R4145 1
 '@T6G_MB_LIB.T6G(SCH_1):PAGE79_I121@PURE_QUANTA.Q_RES(CHIPS)':
 'A': CDS_PINID='A';
NET_NAME
'PRSNT_CABLE_GPU_B3_N'
 '@T6G_MB_LIB.T6G(SCH_1):PRSNT_CABLE_GPU_B3_N':
 C_SIGNAL='@t6g_mb_lib.t6g(sch_1):prsnt_cable_gpu_b3_n';
NODE_NAME     J109 N8
 '@T6G_MB_LIB.T6G(SCH_1):PAGE319_I16@PURE_QUANTA.CONN112_10137002101LF(CHIPS)':
 'N8': CDS_PINID='N8';
NODE_NAME     R4122 1
 '@T6G_MB_LIB.T6G(SCH_1):PAGE332_I13@PURE_QUANTA.Q_RES(CHIPS)':
 'A': CDS_PINID='A';
NODE_NAME     R4121 2
 '@T6G_MB_LIB.T6G(SCH_1):PAGE332_I14@PURE_QUANTA.Q_RES(CHIPS)':
 'B': CDS_PINID='B';
NODE_NAME     Q132 2
 '@T6G_MB_LIB.T6G(SCH_1):PAGE332_I25@PURE_QUANTA.MOSFET_NCH_DUAL(CHIPS)':
 'G1': CDS_PINID='G1';
NODE_NAME     R4573 1
 '@T6G_MB_LIB.T6G(SCH_1):PAGE332_I33@PURE_QUANTA.Q_RES(CHIPS)':
 'A': CDS_PINID='A';
NET_NAME
'PRSNT_CABLE_SWB_B1'
 '@T6G_MB_LIB.T6G(SCH_1):PRSNT_CABLE_SWB_B1':
 C_SIGNAL='@t6g_mb_lib.t6g(sch_1):prsnt_cable_swb_b1';
NODE_NAME     Q9000 6
 '@T6G_MB_LIB.T6G(SCH_1):PAGE330_I21@PURE_QUANTA.MOSFET_NCH_DUAL(CHIPS)':
 'D1': CDS_PINID='D1';
NODE_NAME     R9004 2
 '@T6G_MB_LIB.T6G(SCH_1):PAGE330_I26@PURE_QUANTA.Q_RES(CHIPS)':
 'B': CDS_PINID='B';
NODE_NAME     Q9000 5
 '@T6G_MB_LIB.T6G(SCH_1):PAGE330_I31@PURE_QUANTA.MOSFET_NCH_DUAL(CHIPS)':
 'G2': CDS_PINID='G2';
NET_NAME
'PRSNT_CABLE_SWB_B1_ISO_N'
 '@T6G_MB_LIB.T6G(SCH_1):PRSNT_CABLE_SWB_B1_ISO_N':
 C_SIGNAL='@t6g_mb_lib.t6g(sch_1):prsnt_cable_swb_b1_iso_n';
NODE_NAME     R9010 1
 '@T6G_MB_LIB.T6G(SCH_1):PAGE246_I40@PURE_QUANTA.Q_RES(CHIPS)':
 'A': CDS_PINID='A';
NODE_NAME     Q9000 3
 '@T6G_MB_LIB.T6G(SCH_1):PAGE330_I31@PURE_QUANTA.MOSFET_NCH_DUAL(CHIPS)':
 'D2': CDS_PINID='D2';
NODE_NAME     R9005 2
 '@T6G_MB_LIB.T6G(SCH_1):PAGE330_I32@PURE_QUANTA.Q_RES(CHIPS)':
 'B': CDS_PINID='B';
NODE_NAME     C9000 1
 '@T6G_MB_LIB.T6G(SCH_1):PAGE330_I45@PURE_QUANTA.Q_CAP(CHIPS)':
 'A': CDS_PINID='A';
NET_NAME
'PRSNT_CABLE_SWB_B1_ISO_R_N'
 '@T6G_MB_LIB.T6G(SCH_1):PRSNT_CABLE_SWB_B1_ISO_R_N':
 C_SIGNAL='@t6g_mb_lib.t6g(sch_1):prsnt_cable_swb_b1_iso_r_n';
NODE_NAME     R9010 2
 '@T6G_MB_LIB.T6G(SCH_1):PAGE246_I40@PURE_QUANTA.Q_RES(CHIPS)':
 'B': CDS_PINID='B';
NODE_NAME     U181 14
 '@T6G_MB_LIB.T6G(SCH_1):PAGE246_I83@PURE_QUANTA.PCA9539RPW(CHIPS)':
 'IO1_1': CDS_PINID='IO1_1';
NET_NAME
'PRSNT_CABLE_SWB_B1_N'
 '@T6G_MB_LIB.T6G(SCH_1):PRSNT_CABLE_SWB_B1_N':
 C_SIGNAL='@t6g_mb_lib.t6g(sch_1):prsnt_cable_swb_b1_n';
NODE_NAME     R9002 2
 '@T6G_MB_LIB.T6G(SCH_1):PAGE330_I8@PURE_QUANTA.Q_RES(CHIPS)':
 'B': CDS_PINID='B';
NODE_NAME     Q9000 2
 '@T6G_MB_LIB.T6G(SCH_1):PAGE330_I21@PURE_QUANTA.MOSFET_NCH_DUAL(CHIPS)':
 'G1': CDS_PINID='G1';
NODE_NAME     J106 A1
 '@T6G_MB_LIB.T6G(SCH_1):PAGE327_I74@PURE_QUANTA.CONN112_10137002101LF(CHIPS)':
 'A1': CDS_PINID='A1';
NODE_NAME     R9003 1
 '@T6G_MB_LIB.T6G(SCH_1):PAGE330_I20@PURE_QUANTA.Q_RES(CHIPS)':
 'A': CDS_PINID='A';
NET_NAME
'PRSNT_CABLE_SWB_B2'
 '@T6G_MB_LIB.T6G(SCH_1):PRSNT_CABLE_SWB_B2':
 C_SIGNAL='@t6g_mb_lib.t6g(sch_1):prsnt_cable_swb_b2';
NODE_NAME     R9008 2
 '@T6G_MB_LIB.T6G(SCH_1):PAGE330_I17@PURE_QUANTA.Q_RES(CHIPS)':
 'B': CDS_PINID='B';
NODE_NAME     Q9001 6
 '@T6G_MB_LIB.T6G(SCH_1):PAGE330_I3@PURE_QUANTA.MOSFET_NCH_DUAL(CHIPS)':
 'D1': CDS_PINID='D1';
NODE_NAME     Q9001 5
 '@T6G_MB_LIB.T6G(SCH_1):PAGE330_I22@PURE_QUANTA.MOSFET_NCH_DUAL(CHIPS)':
 'G2': CDS_PINID='G2';
NET_NAME
'PRSNT_CABLE_SWB_B2_ISO_N'
 '@T6G_MB_LIB.T6G(SCH_1):PRSNT_CABLE_SWB_B2_ISO_N':
 C_SIGNAL='@t6g_mb_lib.t6g(sch_1):prsnt_cable_swb_b2_iso_n';
NODE_NAME     R9009 2
 '@T6G_MB_LIB.T6G(SCH_1):PAGE330_I23@PURE_QUANTA.Q_RES(CHIPS)':
 'B': CDS_PINID='B';
NODE_NAME     R9012 1
 '@T6G_MB_LIB.T6G(SCH_1):PAGE246_I39@PURE_QUANTA.Q_RES(CHIPS)':
 'A': CDS_PINID='A';
NODE_NAME     Q9001 3
 '@T6G_MB_LIB.T6G(SCH_1):PAGE330_I22@PURE_QUANTA.MOSFET_NCH_DUAL(CHIPS)':
 'D2': CDS_PINID='D2';
NODE_NAME     C9001 1
 '@T6G_MB_LIB.T6G(SCH_1):PAGE330_I42@PURE_QUANTA.Q_CAP(CHIPS)':
 'A': CDS_PINID='A';
NET_NAME
'PRSNT_CABLE_SWB_B2_ISO_R_N'
 '@T6G_MB_LIB.T6G(SCH_1):PRSNT_CABLE_SWB_B2_ISO_R_N':
 C_SIGNAL='@t6g_mb_lib.t6g(sch_1):prsnt_cable_swb_b2_iso_r_n';
NODE_NAME     R9012 2
 '@T6G_MB_LIB.T6G(SCH_1):PAGE246_I39@PURE_QUANTA.Q_RES(CHIPS)':
 'B': CDS_PINID='B';
NODE_NAME     U181 11
 '@T6G_MB_LIB.T6G(SCH_1):PAGE246_I83@PURE_QUANTA.PCA9539RPW(CHIPS)':
 'IO0_7': CDS_PINID='IO0_7';
NET_NAME
'PRSNT_CABLE_SWB_B2_N'
 '@T6G_MB_LIB.T6G(SCH_1):PRSNT_CABLE_SWB_B2_N':
 C_SIGNAL='@t6g_mb_lib.t6g(sch_1):prsnt_cable_swb_b2_n';
NODE_NAME     J107 N2
 '@T6G_MB_LIB.T6G(SCH_1):PAGE317_I49@PURE_QUANTA.CONN112_10137002101LF(CHIPS)':
 'N2': CDS_PINID='N2';
NODE_NAME     R9007 1
 '@T6G_MB_LIB.T6G(SCH_1):PAGE330_I2@PURE_QUANTA.Q_RES(CHIPS)':
 'A': CDS_PINID='A';
NODE_NAME     Q9001 2
 '@T6G_MB_LIB.T6G(SCH_1):PAGE330_I3@PURE_QUANTA.MOSFET_NCH_DUAL(CHIPS)':
 'G1': CDS_PINID='G1';
NODE_NAME     R9006 2
 '@T6G_MB_LIB.T6G(SCH_1):PAGE330_I15@PURE_QUANTA.Q_RES(CHIPS)':
 'B': CDS_PINID='B';
NET_NAME
'PRSNT_CPU0_N'
 '@T6G_MB_LIB.T6G(SCH_1):PRSNT_CPU0_N':
 C_SIGNAL='@t6g_mb_lib.t6g(sch_1):prsnt_cpu0_n';
NODE_NAME     U25 B66
 '@T6G_MB_LIB.T6G(SCH_1):PAGE27_I227@PURE_QUANTA.GENOA_SP5(CHIPS)':
 'CPU_PRESENT_L': CDS_PINID='CPU_PRESENT_L';
NODE_NAME     R734 1
 '@T6G_MB_LIB.T6G(SCH_1):PAGE144_I19@PURE_QUANTA.Q_RES(CHIPS)':
 'A': CDS_PINID='A';
NODE_NAME     SW1 7
 '@T6G_MB_LIB.T6G(SCH_1):PAGE144_I90@PURE_QUANTA.SW20S_DHNF10FQTR(CHIPS)':
 '7': CDS_PINID='\7\';
NET_NAME
'PRSNT_CPU1_N'
 '@T6G_MB_LIB.T6G(SCH_1):PRSNT_CPU1_N':
 C_SIGNAL='@t6g_mb_lib.t6g(sch_1):prsnt_cpu1_n';
NODE_NAME     U26 B66
 '@T6G_MB_LIB.T6G(SCH_1):PAGE54_I190@PURE_QUANTA.GENOA_SP5(CHIPS)':
 'CPU_PRESENT_L': CDS_PINID='CPU_PRESENT_L';
NODE_NAME     R744 1
 '@T6G_MB_LIB.T6G(SCH_1):PAGE144_I17@PURE_QUANTA.Q_RES(CHIPS)':
 'A': CDS_PINID='A';
NODE_NAME     SW1 8
 '@T6G_MB_LIB.T6G(SCH_1):PAGE144_I90@PURE_QUANTA.SW20S_DHNF10FQTR(CHIPS)':
 '8': CDS_PINID='\8\';
NET_NAME
'PRSNT_HDT_N'
 '@T6G_MB_LIB.T6G(SCH_1):PRSNT_HDT_N':
 C_SIGNAL='@t6g_mb_lib.t6g(sch_1):prsnt_hdt_n';
NODE_NAME     R1528 1
 '@T6G_MB_LIB.T6G(SCH_1):PAGE149_I157@PURE_QUANTA.Q_RES(CHIPS)':
 'A': CDS_PINID='A';
NODE_NAME     R1527 1
 '@T6G_MB_LIB.T6G(SCH_1):PAGE82_I56@PURE_QUANTA.Q_RES(CHIPS)':
 'A': CDS_PINID='A';
NODE_NAME     U18 AB20
 '@T6G_MB_LIB.T6G(SCH_1):PAGE80_I216@PURE_QUANTA.LCMXO3LF9400C5BG484C(CHIPS)':
 'PB44A': CDS_PINID='PB44A';
NET_NAME
'PRSNT_HDT_R_N'
 '@T6G_MB_LIB.T6G(SCH_1):PRSNT_HDT_R_N':
 C_SIGNAL='@t6g_mb_lib.t6g(sch_1):prsnt_hdt_r_n';
NODE_NAME     J54 3
 '@T6G_MB_LIB.T6G(SCH_1):PAGE149_I142@PURE_QUANTA.SCONN20_HSU2101L00007H(CHIPS)':
 '3': CDS_PINID='\3\';
NODE_NAME     R1528 2
 '@T6G_MB_LIB.T6G(SCH_1):PAGE149_I157@PURE_QUANTA.Q_RES(CHIPS)':
 'B': CDS_PINID='B';
NET_NAME
'PRSNT_OCP_SFF_N'
 '@T6G_MB_LIB.T6G(SCH_1):PRSNT_OCP_SFF_N':
 C_SIGNAL='@t6g_mb_lib.t6g(sch_1):prsnt_ocp_sff_n';
NODE_NAME     R6046 2
 '@T6G_MB_LIB.T6G(SCH_1):PAGE80_I64@PURE_QUANTA.Q_RES(CHIPS)':
 'B': CDS_PINID='B';
NODE_NAME     U18 AA3
 '@T6G_MB_LIB.T6G(SCH_1):PAGE80_I216@PURE_QUANTA.LCMXO3LF9400C5BG484C(CHIPS)':
 'PB7A||CSSPIN': CDS_PINID='\pb7a||csspin\';
NET_NAME
'PRSNT_OCP_V3_2_N'
 '@T6G_MB_LIB.T6G(SCH_1):PRSNT_OCP_V3_2_N':
 C_SIGNAL='@t6g_mb_lib.t6g(sch_1):prsnt_ocp_v3_2_n';
NODE_NAME     U18 D15
 '@T6G_MB_LIB.T6G(SCH_1):PAGE79_I94@PURE_QUANTA.LCMXO3LF9400C5BG484C(CHIPS)':
 'PT38D': CDS_PINID='PT38D';
NODE_NAME     R6117 2
 '@T6G_MB_LIB.T6G(SCH_1):PAGE79_I131@PURE_QUANTA.Q_RES(CHIPS)':
 'B': CDS_PINID='B';
NET_NAME
'PRSNT_SWB'
 '@T6G_MB_LIB.T6G(SCH_1):PRSNT_SWB':
 C_SIGNAL='@t6g_mb_lib.t6g(sch_1):prsnt_swb';
NODE_NAME     Q8000 5
 '@T6G_MB_LIB.T6G(SCH_1):PAGE330_I30@PURE_QUANTA.MOSFET_NCH_DUAL(CHIPS)':
 'G2': CDS_PINID='G2';
NODE_NAME     Q8000 6
 '@T6G_MB_LIB.T6G(SCH_1):PAGE330_I29@PURE_QUANTA.MOSFET_NCH_DUAL(CHIPS)':
 'D1': CDS_PINID='D1';
NODE_NAME     R8002 2
 '@T6G_MB_LIB.T6G(SCH_1):PAGE330_I55@PURE_QUANTA.Q_RES(CHIPS)':
 'B': CDS_PINID='B';
NET_NAME
'PRSNT_SWB_ISO_N'
 '@T6G_MB_LIB.T6G(SCH_1):PRSNT_SWB_ISO_N':
 C_SIGNAL='@t6g_mb_lib.t6g(sch_1):prsnt_swb_iso_n';
NODE_NAME     Q8000 3
 '@T6G_MB_LIB.T6G(SCH_1):PAGE330_I30@PURE_QUANTA.MOSFET_NCH_DUAL(CHIPS)':
 'D2': CDS_PINID='D2';
NODE_NAME     R8000 1
 '@T6G_MB_LIB.T6G(SCH_1):PAGE80_I315@PURE_QUANTA.Q_RES(CHIPS)':
 'A': CDS_PINID='A';
NODE_NAME     R8004 1
 '@T6G_MB_LIB.T6G(SCH_1):PAGE246_I41@PURE_QUANTA.Q_RES(CHIPS)':
 'A': CDS_PINID='A';
NODE_NAME     C8000 1
 '@T6G_MB_LIB.T6G(SCH_1):PAGE330_I36@PURE_QUANTA.Q_CAP(CHIPS)':
 'A': CDS_PINID='A';
NODE_NAME     R8003 2
 '@T6G_MB_LIB.T6G(SCH_1):PAGE330_I57@PURE_QUANTA.Q_RES(CHIPS)':
 'B': CDS_PINID='B';
NET_NAME
'PRSNT_SWB_ISO_R1_N'
 '@T6G_MB_LIB.T6G(SCH_1):PRSNT_SWB_ISO_R1_N':
 C_SIGNAL='@t6g_mb_lib.t6g(sch_1):prsnt_swb_iso_r1_n';
NODE_NAME     R8004 2
 '@T6G_MB_LIB.T6G(SCH_1):PAGE246_I41@PURE_QUANTA.Q_RES(CHIPS)':
 'B': CDS_PINID='B';
NODE_NAME     U181 8
 '@T6G_MB_LIB.T6G(SCH_1):PAGE246_I83@PURE_QUANTA.PCA9539RPW(CHIPS)':
 'IO0_4': CDS_PINID='IO0_4';
NET_NAME
'PRSNT_SWB_ISO_R_N'
 '@T6G_MB_LIB.T6G(SCH_1):PRSNT_SWB_ISO_R_N':
 C_SIGNAL='@t6g_mb_lib.t6g(sch_1):prsnt_swb_iso_r_n';
NODE_NAME     U18 AB4
 '@T6G_MB_LIB.T6G(SCH_1):PAGE80_I216@PURE_QUANTA.LCMXO3LF9400C5BG484C(CHIPS)':
 'PB8B': CDS_PINID='PB8B';
NODE_NAME     R8000 2
 '@T6G_MB_LIB.T6G(SCH_1):PAGE80_I315@PURE_QUANTA.Q_RES(CHIPS)':
 'B': CDS_PINID='B';
NET_NAME
'PRSNT_SWB_N'
 '@T6G_MB_LIB.T6G(SCH_1):PRSNT_SWB_N':
 C_SIGNAL='@t6g_mb_lib.t6g(sch_1):prsnt_swb_n';
NODE_NAME     J112 A7
 '@T6G_MB_LIB.T6G(SCH_1):PAGE329_I7@PURE_QUANTA.CONN160_10131762101LF(CHIPS)':
 'A7': CDS_PINID='A7';
NODE_NAME     R8001 1
 '@T6G_MB_LIB.T6G(SCH_1):PAGE330_I12@PURE_QUANTA.Q_RES(CHIPS)':
 'A': CDS_PINID='A';
NODE_NAME     R4058 2
 '@T6G_MB_LIB.T6G(SCH_1):PAGE330_I13@PURE_QUANTA.Q_RES(CHIPS)':
 'B': CDS_PINID='B';
NODE_NAME     Q8000 2
 '@T6G_MB_LIB.T6G(SCH_1):PAGE330_I29@PURE_QUANTA.MOSFET_NCH_DUAL(CHIPS)':
 'G1': CDS_PINID='G1';
NET_NAME
'PU_BIOS_USB_RECOVERY'
 '@T6G_MB_LIB.T6G(SCH_1):PU_BIOS_USB_RECOVERY':
 C_SIGNAL='@t6g_mb_lib.t6g(sch_1):pu_bios_usb_recovery';
NODE_NAME     R22 2
 '@T6G_MB_LIB.T6G(SCH_1):PAGE144_I54@PURE_QUANTA.Q_RES(CHIPS)':
 'B': CDS_PINID='B';
NODE_NAME     SW1 4
 '@T6G_MB_LIB.T6G(SCH_1):PAGE144_I90@PURE_QUANTA.SW20S_DHNF10FQTR(CHIPS)':
 '4': CDS_PINID='\4\';
NET_NAME
'PU_BOOT_RDY_LED'
 '@T6G_MB_LIB.T6G(SCH_1):PU_BOOT_RDY_LED':
 C_SIGNAL='@t6g_mb_lib.t6g(sch_1):pu_boot_rdy_led';
NODE_NAME     R948 1
 '@T6G_MB_LIB.T6G(SCH_1):PAGE143_I7@PURE_QUANTA.Q_RES(CHIPS)':
 'A': CDS_PINID='A';
NODE_NAME     D5 A
 '@T6G_MB_LIB.T6G(SCH_1):PAGE143_I8@PURE_QUANTA.Q_LED(CHIPS)':
 'A': CDS_PINID='A';
NET_NAME
'PU_BUFFER_HDD_ACTIVITY'
 '@T6G_MB_LIB.T6G(SCH_1):PU_BUFFER_HDD_ACTIVITY':
 C_SIGNAL='@t6g_mb_lib.t6g(sch_1):pu_buffer_hdd_activity';
NODE_NAME     U239 1
 '@T6G_MB_LIB.T6G(SCH_1):PAGE345_I53@PURE_QUANTA.74LVC1G126SE7(CHIPS)':
 'OE': CDS_PINID='OE';
NODE_NAME     R5377 2
 '@T6G_MB_LIB.T6G(SCH_1):PAGE345_I62@PURE_QUANTA.Q_RES(CHIPS)':
 'B': CDS_PINID='B';
NET_NAME
'PU_CPU0_USB_HUB_OVRCURR'
 '@T6G_MB_LIB.T6G(SCH_1):PU_CPU0_USB_HUB_OVRCURR':
 C_SIGNAL='@t6g_mb_lib.t6g(sch_1):pu_cpu0_usb_hub_ovrcurr';
NODE_NAME     U6001 30
 '@T6G_MB_LIB.T6G(SCH_1):PAGE153_I1@PURE_QUANTA.CYUSB330468LTXI(CHIPS)':
 'OVRCURR': CDS_PINID='OVRCURR';
NODE_NAME     R6205 2
 '@T6G_MB_LIB.T6G(SCH_1):PAGE153_I43@PURE_QUANTA.Q_RES(CHIPS)':
 'B': CDS_PINID='B';
NET_NAME
'PU_CPU0_USB_HUB_PWR_EN'
 '@T6G_MB_LIB.T6G(SCH_1):PU_CPU0_USB_HUB_PWR_EN':
 C_SIGNAL='@t6g_mb_lib.t6g(sch_1):pu_cpu0_usb_hub_pwr_en';
NODE_NAME     U6001 29
 '@T6G_MB_LIB.T6G(SCH_1):PAGE153_I1@PURE_QUANTA.CYUSB330468LTXI(CHIPS)':
 'PWR_EN': CDS_PINID='PWR_EN';
NODE_NAME     R6204 2
 '@T6G_MB_LIB.T6G(SCH_1):PAGE153_I41@PURE_QUANTA.Q_RES(CHIPS)':
 'B': CDS_PINID='B';
NET_NAME
'PU_CPU0_USB_HUB_RESERVED1'
 '@T6G_MB_LIB.T6G(SCH_1):PU_CPU0_USB_HUB_RESERVED1':
 C_SIGNAL='@t6g_mb_lib.t6g(sch_1):pu_cpu0_usb_hub_reserved1';
NODE_NAME     U6001 21
 '@T6G_MB_LIB.T6G(SCH_1):PAGE153_I1@PURE_QUANTA.CYUSB330468LTXI(CHIPS)':
 'RESERVED1': CDS_PINID='RESERVED1';
NODE_NAME     R6207 2
 '@T6G_MB_LIB.T6G(SCH_1):PAGE153_I45@PURE_QUANTA.Q_RES(CHIPS)':
 'B': CDS_PINID='B';
NET_NAME
'PU_CPU0_USB_HUB_RESERVED2'
 '@T6G_MB_LIB.T6G(SCH_1):PU_CPU0_USB_HUB_RESERVED2':
 C_SIGNAL='@t6g_mb_lib.t6g(sch_1):pu_cpu0_usb_hub_reserved2';
NODE_NAME     U6001 22
 '@T6G_MB_LIB.T6G(SCH_1):PAGE153_I1@PURE_QUANTA.CYUSB330468LTXI(CHIPS)':
 'RESERVED2': CDS_PINID='RESERVED2';
NODE_NAME     R6206 2
 '@T6G_MB_LIB.T6G(SCH_1):PAGE153_I44@PURE_QUANTA.Q_RES(CHIPS)':
 'B': CDS_PINID='B';
NET_NAME
'PU_E1S_0_DUALPORT_EN_N'
 '@T6G_MB_LIB.T6G(SCH_1):PU_E1S_0_DUALPORT_EN_N':
 C_SIGNAL='@t6g_mb_lib.t6g(sch_1):pu_e1s_0_dualport_en_n';
NODE_NAME     R2317 2
 '@T6G_MB_LIB.T6G(SCH_1):PAGE297_I31@PURE_QUANTA.Q_RES(CHIPS)':
 'B': CDS_PINID='B';
NODE_NAME     J90 B9
 '@T6G_MB_LIB.T6G(SCH_1):PAGE297_I90@PURE_QUANTA.SCONN56_123276793(CHIPS)':
 'DUALPORTEN#': CDS_PINID='\dualporten#\';
NET_NAME
'PU_FPGA_DEBUG_LED_CTRL'
 '@T6G_MB_LIB.T6G(SCH_1):PU_FPGA_DEBUG_LED_CTRL':
 C_SIGNAL='@t6g_mb_lib.t6g(sch_1):pu_fpga_debug_led_ctrl';
NODE_NAME     R6040 2
 '@T6G_MB_LIB.T6G(SCH_1):PAGE144_I70@PURE_QUANTA.Q_RES(CHIPS)':
 'B': CDS_PINID='B';
NODE_NAME     SW1 10
 '@T6G_MB_LIB.T6G(SCH_1):PAGE144_I90@PURE_QUANTA.SW20S_DHNF10FQTR(CHIPS)':
 '10': CDS_PINID='\10\';
NET_NAME
'PU_FPGA_DEBUG_SW_SPARE'
 '@T6G_MB_LIB.T6G(SCH_1):PU_FPGA_DEBUG_SW_SPARE':
 C_SIGNAL='@t6g_mb_lib.t6g(sch_1):pu_fpga_debug_sw_spare';
NODE_NAME     R6042 2
 '@T6G_MB_LIB.T6G(SCH_1):PAGE144_I62@PURE_QUANTA.Q_RES(CHIPS)':
 'B': CDS_PINID='B';
NODE_NAME     SW1 5
 '@T6G_MB_LIB.T6G(SCH_1):PAGE144_I90@PURE_QUANTA.SW20S_DHNF10FQTR(CHIPS)':
 '5': CDS_PINID='\5\';
NET_NAME
'PU_JTAG_DBP_BMC_PRDY_N'
 '@T6G_MB_LIB.T6G(SCH_1):PU_JTAG_DBP_BMC_PRDY_N':
 C_SIGNAL='@t6g_mb_lib.t6g(sch_1):pu_jtag_dbp_bmc_prdy_n';
NODE_NAME     J41 A50
 '@T6G_MB_LIB.T6G(SCH_1):PAGE348_I176@PURE_QUANTA.SCONN168_ME1016810202011(CHIPS)':
 'PERN10': CDS_PINID='PERN10';
NODE_NAME     R6071 2
 '@T6G_MB_LIB.T6G(SCH_1):PAGE348_I214@PURE_QUANTA.Q_RES(CHIPS)':
 'B': CDS_PINID='B';
NET_NAME
'PU_OCP_SFF_WAKE_OE'
 '@T6G_MB_LIB.T6G(SCH_1):PU_OCP_SFF_WAKE_OE':
 C_SIGNAL='@t6g_mb_lib.t6g(sch_1):pu_ocp_sff_wake_oe';
NODE_NAME     U8082 1
 '@T6G_MB_LIB.T6G(SCH_1):PAGE337_I8@PURE_QUANTA.74LVC1G126SE7(CHIPS)':
 'OE': CDS_PINID='OE';
NODE_NAME     R45 2
 '@T6G_MB_LIB.T6G(SCH_1):PAGE337_I12@PURE_QUANTA.Q_RES(CHIPS)':
 'B': CDS_PINID='B';
NET_NAME
'PU_OCP_V3_2_WAKE_OE'
 '@T6G_MB_LIB.T6G(SCH_1):PU_OCP_V3_2_WAKE_OE':
 C_SIGNAL='@t6g_mb_lib.t6g(sch_1):pu_ocp_v3_2_wake_oe';
NODE_NAME     R3183 2
 '@T6G_MB_LIB.T6G(SCH_1):PAGE342_I4@PURE_QUANTA.Q_RES(CHIPS)':
 'B': CDS_PINID='B';
NODE_NAME     U217 1
 '@T6G_MB_LIB.T6G(SCH_1):PAGE342_I14@PURE_QUANTA.74LVC1G126SE7(CHIPS)':
 'OE': CDS_PINID='OE';
NET_NAME
'PU_P12V_ALL_PWROK_LED'
 '@T6G_MB_LIB.T6G(SCH_1):PU_P12V_ALL_PWROK_LED':
 C_SIGNAL='@t6g_mb_lib.t6g(sch_1):pu_p12v_all_pwrok_led';
NODE_NAME     R1208 1
 '@T6G_MB_LIB.T6G(SCH_1):PAGE143_I42@PURE_QUANTA.Q_RES(CHIPS)':
 'A': CDS_PINID='A';
NODE_NAME     D46 A
 '@T6G_MB_LIB.T6G(SCH_1):PAGE143_I43@PURE_QUANTA.Q_LED(CHIPS)':
 'A': CDS_PINID='A';
NET_NAME
'PU_RST_SMB_PCIE0_N'
 '@T6G_MB_LIB.T6G(SCH_1):PU_RST_SMB_PCIE0_N':
 C_SIGNAL='@t6g_mb_lib.t6g(sch_1):pu_rst_smb_pcie0_n';
NODE_NAME     R2268 2
 '@T6G_MB_LIB.T6G(SCH_1):PAGE252_I28@PURE_QUANTA.Q_RES(CHIPS)':
 'B': CDS_PINID='B';
NODE_NAME     U36 3
 '@T6G_MB_LIB.T6G(SCH_1):PAGE252_I33@PURE_QUANTA.TCA9548APWR(CHIPS)':
 'RESET#': CDS_PINID='\reset#\';
NET_NAME
'PU_RST_SMB_PCIE2_N'
 '@T6G_MB_LIB.T6G(SCH_1):PU_RST_SMB_PCIE2_N':
 C_SIGNAL='@t6g_mb_lib.t6g(sch_1):pu_rst_smb_pcie2_n';
NODE_NAME     R3710 2
 '@T6G_MB_LIB.T6G(SCH_1):PAGE251_I29@PURE_QUANTA.Q_RES(CHIPS)':
 'B': CDS_PINID='B';
NODE_NAME     U39 3
 '@T6G_MB_LIB.T6G(SCH_1):PAGE251_I74@PURE_QUANTA.TCA9548APWR(CHIPS)':
 'RESET#': CDS_PINID='\reset#\';
NET_NAME
'PU_RST_SMB_U181_N'
 '@T6G_MB_LIB.T6G(SCH_1):PU_RST_SMB_U181_N':
 C_SIGNAL='@t6g_mb_lib.t6g(sch_1):pu_rst_smb_u181_n';
NODE_NAME     R2922 2
 '@T6G_MB_LIB.T6G(SCH_1):PAGE246_I31@PURE_QUANTA.Q_RES(CHIPS)':
 'B': CDS_PINID='B';
NODE_NAME     U181 3
 '@T6G_MB_LIB.T6G(SCH_1):PAGE246_I83@PURE_QUANTA.PCA9539RPW(CHIPS)':
 'RESET': CDS_PINID='RESET';
NET_NAME
'PU_SMERR_LED'
 '@T6G_MB_LIB.T6G(SCH_1):PU_SMERR_LED':
 C_SIGNAL='@t6g_mb_lib.t6g(sch_1):pu_smerr_led';
NODE_NAME     R950 1
 '@T6G_MB_LIB.T6G(SCH_1):PAGE143_I3@PURE_QUANTA.Q_RES(CHIPS)':
 'A': CDS_PINID='A';
NODE_NAME     D6 A
 '@T6G_MB_LIB.T6G(SCH_1):PAGE143_I9@PURE_QUANTA.Q_LED(CHIPS)':
 'A': CDS_PINID='A';
NET_NAME
'PU_SPI_PLD_CS_N'
 '@T6G_MB_LIB.T6G(SCH_1):PU_SPI_PLD_CS_N':
 C_SIGNAL='@t6g_mb_lib.t6g(sch_1):pu_spi_pld_cs_n';
NODE_NAME     U18 AB21
 '@T6G_MB_LIB.T6G(SCH_1):PAGE80_I216@PURE_QUANTA.LCMXO3LF9400C5BG484C(CHIPS)':
 'PB46A||SN': CDS_PINID='\pb46a||sn\';
NODE_NAME     R6085 2
 '@T6G_MB_LIB.T6G(SCH_1):PAGE80_I298@PURE_QUANTA.Q_RES(CHIPS)':
 'B': CDS_PINID='B';
NET_NAME
'PU_TEST'
 '@T6G_MB_LIB.T6G(SCH_1):PU_TEST':
 C_SIGNAL='@t6g_mb_lib.t6g(sch_1):pu_test';
NODE_NAME     U237 5
 '@T6G_MB_LIB.T6G(SCH_1):PAGE110_I63@PURE_QUANTA.PI3EQX12902AZLEX(CHIPS)':
 'TEST#': CDS_PINID='\test#\';
NODE_NAME     R3291 1
 '@T6G_MB_LIB.T6G(SCH_1):PAGE110_I88@PURE_QUANTA.Q_RES(CHIPS)':
 'A': CDS_PINID='A';
NET_NAME
'PU_U160_EN_N'
 '@T6G_MB_LIB.T6G(SCH_1):PU_U160_EN_N':
 C_SIGNAL='@t6g_mb_lib.t6g(sch_1):pu_u160_en_n';
NODE_NAME     R6182 2
 '@T6G_MB_LIB.T6G(SCH_1):PAGE148_I384@PURE_QUANTA.Q_RES(CHIPS)':
 'B': CDS_PINID='B';
NODE_NAME     JP6001 1
 '@T6G_MB_LIB.T6G(SCH_1):PAGE148_I387@PURE_QUANTA.CONN3_210HP1030BR1(CHIPS)':
 '1': CDS_PINID='\1\';
NET_NAME
'PU_U181_INT'
 '@T6G_MB_LIB.T6G(SCH_1):PU_U181_INT':
 C_SIGNAL='@t6g_mb_lib.t6g(sch_1):pu_u181_int';
NODE_NAME     R2923 2
 '@T6G_MB_LIB.T6G(SCH_1):PAGE246_I37@PURE_QUANTA.Q_RES(CHIPS)':
 'B': CDS_PINID='B';
NODE_NAME     U181 1
 '@T6G_MB_LIB.T6G(SCH_1):PAGE246_I83@PURE_QUANTA.PCA9539RPW(CHIPS)':
 'INT': CDS_PINID='INT';
NET_NAME
'PU_U212_EN_N'
 '@T6G_MB_LIB.T6G(SCH_1):PU_U212_EN_N':
 C_SIGNAL='@t6g_mb_lib.t6g(sch_1):pu_u212_en_n';
NODE_NAME     R6181 2
 '@T6G_MB_LIB.T6G(SCH_1):PAGE148_I381@PURE_QUANTA.Q_RES(CHIPS)':
 'B': CDS_PINID='B';
NODE_NAME     JP6000 1
 '@T6G_MB_LIB.T6G(SCH_1):PAGE148_I386@PURE_QUANTA.CONN3_210HP1030BR1(CHIPS)':
 '1': CDS_PINID='\1\';
NET_NAME
'PU_U2_EN'
 '@T6G_MB_LIB.T6G(SCH_1):PU_U2_EN':
 C_SIGNAL='@t6g_mb_lib.t6g(sch_1):pu_u2_en';
NODE_NAME     R201 2
 '@T6G_MB_LIB.T6G(SCH_1):PAGE137_I62@PURE_QUANTA.Q_RES(CHIPS)':
 'B': CDS_PINID='B';
NODE_NAME     U2 5
 '@T6G_MB_LIB.T6G(SCH_1):PAGE137_I99@PURE_QUANTA.PCA9617ADP(CHIPS)':
 'EN': CDS_PINID='EN';
NET_NAME
'PU_U38_6'
 '@T6G_MB_LIB.T6G(SCH_1):PU_U38_6':
 C_SIGNAL='@t6g_mb_lib.t6g(sch_1):pu_u38_6';
NODE_NAME     U38 6
 '@T6G_MB_LIB.T6G(SCH_1):PAGE264_I8@PURE_QUANTA.SN74LVC1G11DCKR(CHIPS)':
 'C': CDS_PINID='C';
NODE_NAME     R6504 2
 '@T6G_MB_LIB.T6G(SCH_1):PAGE264_I51@PURE_QUANTA.Q_RES(CHIPS)':
 'B': CDS_PINID='B';
NET_NAME
'PU_U5_EN'
 '@T6G_MB_LIB.T6G(SCH_1):PU_U5_EN':
 C_SIGNAL='@t6g_mb_lib.t6g(sch_1):pu_u5_en';
NODE_NAME     R78 2
 '@T6G_MB_LIB.T6G(SCH_1):PAGE137_I31@PURE_QUANTA.Q_RES(CHIPS)':
 'B': CDS_PINID='B';
NODE_NAME     U5 5
 '@T6G_MB_LIB.T6G(SCH_1):PAGE137_I48@PURE_QUANTA.PCA9617ADP(CHIPS)':
 'EN': CDS_PINID='EN';
NET_NAME
'PU_U96_EN'
 '@T6G_MB_LIB.T6G(SCH_1):PU_U96_EN':
 C_SIGNAL='@t6g_mb_lib.t6g(sch_1):pu_u96_en';
NODE_NAME     R200 2
 '@T6G_MB_LIB.T6G(SCH_1):PAGE137_I13@PURE_QUANTA.Q_RES(CHIPS)':
 'B': CDS_PINID='B';
NODE_NAME     U96 5
 '@T6G_MB_LIB.T6G(SCH_1):PAGE137_I51@PURE_QUANTA.PCA9617ADP(CHIPS)':
 'EN': CDS_PINID='EN';
NET_NAME
'PV09_RETIMER_CPU0_VCCS'
 '@T6G_MB_LIB.T6G(SCH_1):PV09_RETIMER_CPU0_VCCS':
 C_SIGNAL='@t6g_mb_lib.t6g(sch_1):pv09_retimer_cpu0_vccs';
NODE_NAME     PU6502 40
 '@T6G_MB_LIB.T6G(SCH_1):PAGE475_I42@PURE_QUANTA.ISL69260IRAZT(CHIPS)':
 'VCCS': CDS_PINID='VCCS';
NODE_NAME     PC6606 1
 '@T6G_MB_LIB.T6G(SCH_1):PAGE475_I145@PURE_QUANTA.Q_CAP(CHIPS)':
 'A': CDS_PINID='A';
NODE_NAME     PC6605 1
 '@T6G_MB_LIB.T6G(SCH_1):PAGE475_I146@PURE_QUANTA.Q_CAP(CHIPS)':
 'A': CDS_PINID='A';
NODE_NAME     PU6503 39
 '@T6G_MB_LIB.T6G(SCH_1):PAGE476_I53@PURE_QUANTA.ISL99390FRZTR5935(CHIPS)':
 'REFIN': CDS_PINID='REFIN';
NODE_NAME     PC6553_1 1
 '@T6G_MB_LIB.T6G(SCH_1):PAGE476_I68@PURE_QUANTA.Q_CAP(CHIPS)':
 'A': CDS_PINID='A';
NODE_NAME     PU6504 39
 '@T6G_MB_LIB.T6G(SCH_1):PAGE476_I270@PURE_QUANTA.ISL99390FRZTR5935(CHIPS)':
 'REFIN': CDS_PINID='REFIN';
NODE_NAME     PC6576 1
 '@T6G_MB_LIB.T6G(SCH_1):PAGE476_I281@PURE_QUANTA.Q_CAP(CHIPS)':
 'A': CDS_PINID='A';
NET_NAME
'PV09_RETIMER_CPU1_VCCS'
 '@T6G_MB_LIB.T6G(SCH_1):PV09_RETIMER_CPU1_VCCS':
 C_SIGNAL='@t6g_mb_lib.t6g(sch_1):pv09_retimer_cpu1_vccs';
NODE_NAME     PC6546 1
 '@T6G_MB_LIB.T6G(SCH_1):PAGE477_I72@PURE_QUANTA.Q_CAP(CHIPS)':
 'A': CDS_PINID='A';
NODE_NAME     PC6545 1
 '@T6G_MB_LIB.T6G(SCH_1):PAGE477_I73@PURE_QUANTA.Q_CAP(CHIPS)':
 'A': CDS_PINID='A';
NODE_NAME     PU6510 40
 '@T6G_MB_LIB.T6G(SCH_1):PAGE477_I88@PURE_QUANTA.ISL69260IRAZT(CHIPS)':
 'VCCS': CDS_PINID='VCCS';
NODE_NAME     PC6646 1
 '@T6G_MB_LIB.T6G(SCH_1):PAGE478_I2@PURE_QUANTA.Q_CAP(CHIPS)':
 'A': CDS_PINID='A';
NODE_NAME     PU6512 39
 '@T6G_MB_LIB.T6G(SCH_1):PAGE478_I12@PURE_QUANTA.ISL99390FRZTR5935(CHIPS)':
 'REFIN': CDS_PINID='REFIN';
NODE_NAME     PC6611_1 1
 '@T6G_MB_LIB.T6G(SCH_1):PAGE478_I39@PURE_QUANTA.Q_CAP(CHIPS)':
 'A': CDS_PINID='A';
NODE_NAME     PU6511 39
 '@T6G_MB_LIB.T6G(SCH_1):PAGE478_I51@PURE_QUANTA.ISL99390FRZTR5935(CHIPS)':
 'REFIN': CDS_PINID='REFIN';
NET_NAME
'PVDD11_S3_P0'
 '@T6G_MB_LIB.T6G(SCH_1):PVDD11_S3_P0':
 C_SIGNAL='@t6g_mb_lib.t6g(sch_1):pvdd11_s3_p0',
 CDS_GLOBAL_NET='TRUE';
NODE_NAME     U25 BJ18
 '@T6G_MB_LIB.T6G(SCH_1):PAGE30_I28@PURE_QUANTA.GENOA_SP5(CHIPS)':
 'VDD_11_S3_BJ18': CDS_PINID='VDD_11_S3_BJ18';
NODE_NAME     U25 BJ23
 '@T6G_MB_LIB.T6G(SCH_1):PAGE30_I28@PURE_QUANTA.GENOA_SP5(CHIPS)':
 'VDD_11_S3_BJ23': CDS_PINID='VDD_11_S3_BJ23';
NODE_NAME     U25 BJ25
 '@T6G_MB_LIB.T6G(SCH_1):PAGE30_I28@PURE_QUANTA.GENOA_SP5(CHIPS)':
 'VDD_11_S3_BJ25': CDS_PINID='VDD_11_S3_BJ25';
NODE_NAME     U25 BJ27
 '@T6G_MB_LIB.T6G(SCH_1):PAGE30_I28@PURE_QUANTA.GENOA_SP5(CHIPS)':
 'VDD_11_S3_BJ27': CDS_PINID='VDD_11_S3_BJ27';
NODE_NAME     U25 BK22
 '@T6G_MB_LIB.T6G(SCH_1):PAGE30_I28@PURE_QUANTA.GENOA_SP5(CHIPS)':
 'VDD_11_S3_BK22': CDS_PINID='VDD_11_S3_BK22';
NODE_NAME     U25 BK24
 '@T6G_MB_LIB.T6G(SCH_1):PAGE30_I28@PURE_QUANTA.GENOA_SP5(CHIPS)':
 'VDD_11_S3_BK24': CDS_PINID='VDD_11_S3_BK24';
NODE_NAME     U25 BK26
 '@T6G_MB_LIB.T6G(SCH_1):PAGE30_I28@PURE_QUANTA.GENOA_SP5(CHIPS)':
 'VDD_11_S3_BK26': CDS_PINID='VDD_11_S3_BK26';
NODE_NAME     U25 BK28
 '@T6G_MB_LIB.T6G(SCH_1):PAGE30_I28@PURE_QUANTA.GENOA_SP5(CHIPS)':
 'VDD_11_S3_BK28': CDS_PINID='VDD_11_S3_BK28';
NODE_NAME     U25 BK49
 '@T6G_MB_LIB.T6G(SCH_1):PAGE30_I28@PURE_QUANTA.GENOA_SP5(CHIPS)':
 'VDD_11_S3_BK49': CDS_PINID='VDD_11_S3_BK49';
NODE_NAME     U25 BL23
 '@T6G_MB_LIB.T6G(SCH_1):PAGE30_I28@PURE_QUANTA.GENOA_SP5(CHIPS)':
 'VDD_11_S3_BL23': CDS_PINID='VDD_11_S3_BL23';
NODE_NAME     U25 BL25
 '@T6G_MB_LIB.T6G(SCH_1):PAGE30_I28@PURE_QUANTA.GENOA_SP5(CHIPS)':
 'VDD_11_S3_BL25': CDS_PINID='VDD_11_S3_BL25';
NODE_NAME     U25 BL27
 '@T6G_MB_LIB.T6G(SCH_1):PAGE30_I28@PURE_QUANTA.GENOA_SP5(CHIPS)':
 'VDD_11_S3_BL27': CDS_PINID='VDD_11_S3_BL27';
NODE_NAME     U25 BL48
 '@T6G_MB_LIB.T6G(SCH_1):PAGE30_I28@PURE_QUANTA.GENOA_SP5(CHIPS)':
 'VDD_11_S3_BL48': CDS_PINID='VDD_11_S3_BL48';
NODE_NAME     U25 BM12
 '@T6G_MB_LIB.T6G(SCH_1):PAGE30_I28@PURE_QUANTA.GENOA_SP5(CHIPS)':
 'VDD_11_S3_BM12': CDS_PINID='VDD_11_S3_BM12';
NODE_NAME     U25 BM19
 '@T6G_MB_LIB.T6G(SCH_1):PAGE30_I28@PURE_QUANTA.GENOA_SP5(CHIPS)':
 'VDD_11_S3_BM19': CDS_PINID='VDD_11_S3_BM19';
NODE_NAME     U25 BM22
 '@T6G_MB_LIB.T6G(SCH_1):PAGE30_I28@PURE_QUANTA.GENOA_SP5(CHIPS)':
 'VDD_11_S3_BM22': CDS_PINID='VDD_11_S3_BM22';
NODE_NAME     U25 BM24
 '@T6G_MB_LIB.T6G(SCH_1):PAGE30_I28@PURE_QUANTA.GENOA_SP5(CHIPS)':
 'VDD_11_S3_BM24': CDS_PINID='VDD_11_S3_BM24';
NODE_NAME     U25 BM26
 '@T6G_MB_LIB.T6G(SCH_1):PAGE30_I28@PURE_QUANTA.GENOA_SP5(CHIPS)':
 'VDD_11_S3_BM26': CDS_PINID='VDD_11_S3_BM26';
NODE_NAME     U25 BM28
 '@T6G_MB_LIB.T6G(SCH_1):PAGE30_I28@PURE_QUANTA.GENOA_SP5(CHIPS)':
 'VDD_11_S3_BM28': CDS_PINID='VDD_11_S3_BM28';
NODE_NAME     U25 BM30
 '@T6G_MB_LIB.T6G(SCH_1):PAGE30_I28@PURE_QUANTA.GENOA_SP5(CHIPS)':
 'VDD_11_S3_BM30': CDS_PINID='VDD_11_S3_BM30';
NODE_NAME     U25 BM32
 '@T6G_MB_LIB.T6G(SCH_1):PAGE30_I28@PURE_QUANTA.GENOA_SP5(CHIPS)':
 'VDD_11_S3_BM32': CDS_PINID='VDD_11_S3_BM32';
NODE_NAME     U25 BM34
 '@T6G_MB_LIB.T6G(SCH_1):PAGE30_I28@PURE_QUANTA.GENOA_SP5(CHIPS)':
 'VDD_11_S3_BM34': CDS_PINID='VDD_11_S3_BM34';
NODE_NAME     U25 BM36
 '@T6G_MB_LIB.T6G(SCH_1):PAGE30_I28@PURE_QUANTA.GENOA_SP5(CHIPS)':
 'VDD_11_S3_BM36': CDS_PINID='VDD_11_S3_BM36';
NODE_NAME     U25 BM39
 '@T6G_MB_LIB.T6G(SCH_1):PAGE30_I28@PURE_QUANTA.GENOA_SP5(CHIPS)':
 'VDD_11_S3_BM39': CDS_PINID='VDD_11_S3_BM39';
NODE_NAME     U25 BM41
 '@T6G_MB_LIB.T6G(SCH_1):PAGE30_I28@PURE_QUANTA.GENOA_SP5(CHIPS)':
 'VDD_11_S3_BM41': CDS_PINID='VDD_11_S3_BM41';
NODE_NAME     U25 BM43
 '@T6G_MB_LIB.T6G(SCH_1):PAGE30_I28@PURE_QUANTA.GENOA_SP5(CHIPS)':
 'VDD_11_S3_BM43': CDS_PINID='VDD_11_S3_BM43';
NODE_NAME     U25 BM45
 '@T6G_MB_LIB.T6G(SCH_1):PAGE30_I28@PURE_QUANTA.GENOA_SP5(CHIPS)':
 'VDD_11_S3_BM45': CDS_PINID='VDD_11_S3_BM45';
NODE_NAME     U25 BM47
 '@T6G_MB_LIB.T6G(SCH_1):PAGE30_I28@PURE_QUANTA.GENOA_SP5(CHIPS)':
 'VDD_11_S3_BM47': CDS_PINID='VDD_11_S3_BM47';
NODE_NAME     U25 BM49
 '@T6G_MB_LIB.T6G(SCH_1):PAGE30_I28@PURE_QUANTA.GENOA_SP5(CHIPS)':
 'VDD_11_S3_BM49': CDS_PINID='VDD_11_S3_BM49';
NODE_NAME     U25 BN25
 '@T6G_MB_LIB.T6G(SCH_1):PAGE30_I28@PURE_QUANTA.GENOA_SP5(CHIPS)':
 'VDD_11_S3_BN25': CDS_PINID='VDD_11_S3_BN25';
NODE_NAME     U25 BN29
 '@T6G_MB_LIB.T6G(SCH_1):PAGE30_I28@PURE_QUANTA.GENOA_SP5(CHIPS)':
 'VDD_11_S3_BN29': CDS_PINID='VDD_11_S3_BN29';
NODE_NAME     U25 BN33
 '@T6G_MB_LIB.T6G(SCH_1):PAGE30_I28@PURE_QUANTA.GENOA_SP5(CHIPS)':
 'VDD_11_S3_BN33': CDS_PINID='VDD_11_S3_BN33';
NODE_NAME     U25 BN40
 '@T6G_MB_LIB.T6G(SCH_1):PAGE30_I28@PURE_QUANTA.GENOA_SP5(CHIPS)':
 'VDD_11_S3_BN40': CDS_PINID='VDD_11_S3_BN40';
NODE_NAME     U25 BN44
 '@T6G_MB_LIB.T6G(SCH_1):PAGE30_I28@PURE_QUANTA.GENOA_SP5(CHIPS)':
 'VDD_11_S3_BN44': CDS_PINID='VDD_11_S3_BN44';
NODE_NAME     U25 BN48
 '@T6G_MB_LIB.T6G(SCH_1):PAGE30_I28@PURE_QUANTA.GENOA_SP5(CHIPS)':
 'VDD_11_S3_BN48': CDS_PINID='VDD_11_S3_BN48';
NODE_NAME     U25 BP22
 '@T6G_MB_LIB.T6G(SCH_1):PAGE30_I28@PURE_QUANTA.GENOA_SP5(CHIPS)':
 'VDD_11_S3_BP22': CDS_PINID='VDD_11_S3_BP22';
NODE_NAME     U25 BR4
 '@T6G_MB_LIB.T6G(SCH_1):PAGE30_I28@PURE_QUANTA.GENOA_SP5(CHIPS)':
 'VDD_11_S3_BR4': CDS_PINID='VDD_11_S3_BR4';
NODE_NAME     U25 BR11
 '@T6G_MB_LIB.T6G(SCH_1):PAGE30_I28@PURE_QUANTA.GENOA_SP5(CHIPS)':
 'VDD_11_S3_BR11': CDS_PINID='VDD_11_S3_BR11';
NODE_NAME     U25 BR18
 '@T6G_MB_LIB.T6G(SCH_1):PAGE30_I28@PURE_QUANTA.GENOA_SP5(CHIPS)':
 'VDD_11_S3_BR18': CDS_PINID='VDD_11_S3_BR18';
NODE_NAME     U25 BV5
 '@T6G_MB_LIB.T6G(SCH_1):PAGE30_I28@PURE_QUANTA.GENOA_SP5(CHIPS)':
 'VDD_11_S3_BV5': CDS_PINID='VDD_11_S3_BV5';
NODE_NAME     U25 BV12
 '@T6G_MB_LIB.T6G(SCH_1):PAGE30_I28@PURE_QUANTA.GENOA_SP5(CHIPS)':
 'VDD_11_S3_BV12': CDS_PINID='VDD_11_S3_BV12';
NODE_NAME     U25 BV19
 '@T6G_MB_LIB.T6G(SCH_1):PAGE30_I28@PURE_QUANTA.GENOA_SP5(CHIPS)':
 'VDD_11_S3_BV19': CDS_PINID='VDD_11_S3_BV19';
NODE_NAME     U25 BV22
 '@T6G_MB_LIB.T6G(SCH_1):PAGE30_I28@PURE_QUANTA.GENOA_SP5(CHIPS)':
 'VDD_11_S3_BV22': CDS_PINID='VDD_11_S3_BV22';
NODE_NAME     U25 CA4
 '@T6G_MB_LIB.T6G(SCH_1):PAGE30_I28@PURE_QUANTA.GENOA_SP5(CHIPS)':
 'VDD_11_S3_CA4': CDS_PINID='VDD_11_S3_CA4';
NODE_NAME     U25 CA11
 '@T6G_MB_LIB.T6G(SCH_1):PAGE30_I28@PURE_QUANTA.GENOA_SP5(CHIPS)':
 'VDD_11_S3_CA11': CDS_PINID='VDD_11_S3_CA11';
NODE_NAME     U25 CA18
 '@T6G_MB_LIB.T6G(SCH_1):PAGE30_I28@PURE_QUANTA.GENOA_SP5(CHIPS)':
 'VDD_11_S3_CA18': CDS_PINID='VDD_11_S3_CA18';
NODE_NAME     U25 CB22
 '@T6G_MB_LIB.T6G(SCH_1):PAGE30_I28@PURE_QUANTA.GENOA_SP5(CHIPS)':
 'VDD_11_S3_CB22': CDS_PINID='VDD_11_S3_CB22';
NODE_NAME     U25 CD5
 '@T6G_MB_LIB.T6G(SCH_1):PAGE30_I28@PURE_QUANTA.GENOA_SP5(CHIPS)':
 'VDD_11_S3_CD5': CDS_PINID='VDD_11_S3_CD5';
NODE_NAME     U25 CD12
 '@T6G_MB_LIB.T6G(SCH_1):PAGE30_I28@PURE_QUANTA.GENOA_SP5(CHIPS)':
 'VDD_11_S3_CD12': CDS_PINID='VDD_11_S3_CD12';
NODE_NAME     U25 CD19
 '@T6G_MB_LIB.T6G(SCH_1):PAGE30_I28@PURE_QUANTA.GENOA_SP5(CHIPS)':
 'VDD_11_S3_CD19': CDS_PINID='VDD_11_S3_CD19';
NODE_NAME     U25 CF22
 '@T6G_MB_LIB.T6G(SCH_1):PAGE30_I28@PURE_QUANTA.GENOA_SP5(CHIPS)':
 'VDD_11_S3_CF22': CDS_PINID='VDD_11_S3_CF22';
NODE_NAME     U25 CG4
 '@T6G_MB_LIB.T6G(SCH_1):PAGE30_I28@PURE_QUANTA.GENOA_SP5(CHIPS)':
 'VDD_11_S3_CG4': CDS_PINID='VDD_11_S3_CG4';
NODE_NAME     U25 CG11
 '@T6G_MB_LIB.T6G(SCH_1):PAGE30_I28@PURE_QUANTA.GENOA_SP5(CHIPS)':
 'VDD_11_S3_CG11': CDS_PINID='VDD_11_S3_CG11';
NODE_NAME     U25 CG18
 '@T6G_MB_LIB.T6G(SCH_1):PAGE30_I28@PURE_QUANTA.GENOA_SP5(CHIPS)':
 'VDD_11_S3_CG18': CDS_PINID='VDD_11_S3_CG18';
NODE_NAME     U25 CJ22
 '@T6G_MB_LIB.T6G(SCH_1):PAGE30_I28@PURE_QUANTA.GENOA_SP5(CHIPS)':
 'VDD_11_S3_CJ22': CDS_PINID='VDD_11_S3_CJ22';
NODE_NAME     U25 CK5
 '@T6G_MB_LIB.T6G(SCH_1):PAGE30_I28@PURE_QUANTA.GENOA_SP5(CHIPS)':
 'VDD_11_S3_CK5': CDS_PINID='VDD_11_S3_CK5';
NODE_NAME     U25 CK12
 '@T6G_MB_LIB.T6G(SCH_1):PAGE30_I28@PURE_QUANTA.GENOA_SP5(CHIPS)':
 'VDD_11_S3_CK12': CDS_PINID='VDD_11_S3_CK12';
NODE_NAME     U25 CK19
 '@T6G_MB_LIB.T6G(SCH_1):PAGE30_I28@PURE_QUANTA.GENOA_SP5(CHIPS)':
 'VDD_11_S3_CK19': CDS_PINID='VDD_11_S3_CK19';
NODE_NAME     U25 CM22
 '@T6G_MB_LIB.T6G(SCH_1):PAGE30_I28@PURE_QUANTA.GENOA_SP5(CHIPS)':
 'VDD_11_S3_CM22': CDS_PINID='VDD_11_S3_CM22';
NODE_NAME     U25 CN4
 '@T6G_MB_LIB.T6G(SCH_1):PAGE30_I28@PURE_QUANTA.GENOA_SP5(CHIPS)':
 'VDD_11_S3_CN4': CDS_PINID='VDD_11_S3_CN4';
NODE_NAME     U25 CN11
 '@T6G_MB_LIB.T6G(SCH_1):PAGE30_I28@PURE_QUANTA.GENOA_SP5(CHIPS)':
 'VDD_11_S3_CN11': CDS_PINID='VDD_11_S3_CN11';
NODE_NAME     U25 CN18
 '@T6G_MB_LIB.T6G(SCH_1):PAGE30_I28@PURE_QUANTA.GENOA_SP5(CHIPS)':
 'VDD_11_S3_CN18': CDS_PINID='VDD_11_S3_CN18';
NODE_NAME     U25 CT5
 '@T6G_MB_LIB.T6G(SCH_1):PAGE30_I28@PURE_QUANTA.GENOA_SP5(CHIPS)':
 'VDD_11_S3_CT5': CDS_PINID='VDD_11_S3_CT5';
NODE_NAME     U25 CT12
 '@T6G_MB_LIB.T6G(SCH_1):PAGE30_I28@PURE_QUANTA.GENOA_SP5(CHIPS)':
 'VDD_11_S3_CT12': CDS_PINID='VDD_11_S3_CT12';
NODE_NAME     U25 CT19
 '@T6G_MB_LIB.T6G(SCH_1):PAGE30_I28@PURE_QUANTA.GENOA_SP5(CHIPS)':
 'VDD_11_S3_CT19': CDS_PINID='VDD_11_S3_CT19';
NODE_NAME     U25 CT22
 '@T6G_MB_LIB.T6G(SCH_1):PAGE30_I28@PURE_QUANTA.GENOA_SP5(CHIPS)':
 'VDD_11_S3_CT22': CDS_PINID='VDD_11_S3_CT22';
NODE_NAME     U25 CW4
 '@T6G_MB_LIB.T6G(SCH_1):PAGE30_I28@PURE_QUANTA.GENOA_SP5(CHIPS)':
 'VDD_11_S3_CW4': CDS_PINID='VDD_11_S3_CW4';
NODE_NAME     U25 CW11
 '@T6G_MB_LIB.T6G(SCH_1):PAGE30_I28@PURE_QUANTA.GENOA_SP5(CHIPS)':
 'VDD_11_S3_CW11': CDS_PINID='VDD_11_S3_CW11';
NODE_NAME     U25 CW18
 '@T6G_MB_LIB.T6G(SCH_1):PAGE30_I28@PURE_QUANTA.GENOA_SP5(CHIPS)':
 'VDD_11_S3_CW18': CDS_PINID='VDD_11_S3_CW18';
NODE_NAME     U25 CY22
 '@T6G_MB_LIB.T6G(SCH_1):PAGE30_I28@PURE_QUANTA.GENOA_SP5(CHIPS)':
 'VDD_11_S3_CY22': CDS_PINID='VDD_11_S3_CY22';
NODE_NAME     U25 DB5
 '@T6G_MB_LIB.T6G(SCH_1):PAGE30_I28@PURE_QUANTA.GENOA_SP5(CHIPS)':
 'VDD_11_S3_DB5': CDS_PINID='VDD_11_S3_DB5';
NODE_NAME     U25 DB12
 '@T6G_MB_LIB.T6G(SCH_1):PAGE30_I28@PURE_QUANTA.GENOA_SP5(CHIPS)':
 'VDD_11_S3_DB12': CDS_PINID='VDD_11_S3_DB12';
NODE_NAME     U25 DB19
 '@T6G_MB_LIB.T6G(SCH_1):PAGE30_I28@PURE_QUANTA.GENOA_SP5(CHIPS)':
 'VDD_11_S3_DB19': CDS_PINID='VDD_11_S3_DB19';
NODE_NAME     U25 DE4
 '@T6G_MB_LIB.T6G(SCH_1):PAGE30_I28@PURE_QUANTA.GENOA_SP5(CHIPS)':
 'VDD_11_S3_DE4': CDS_PINID='VDD_11_S3_DE4';
NODE_NAME     U25 DE11
 '@T6G_MB_LIB.T6G(SCH_1):PAGE30_I28@PURE_QUANTA.GENOA_SP5(CHIPS)':
 'VDD_11_S3_DE11': CDS_PINID='VDD_11_S3_DE11';
NODE_NAME     U25 DE18
 '@T6G_MB_LIB.T6G(SCH_1):PAGE30_I28@PURE_QUANTA.GENOA_SP5(CHIPS)':
 'VDD_11_S3_DE18': CDS_PINID='VDD_11_S3_DE18';
NODE_NAME     U25 DG5
 '@T6G_MB_LIB.T6G(SCH_1):PAGE30_I28@PURE_QUANTA.GENOA_SP5(CHIPS)':
 'VDD_11_S3_DG5': CDS_PINID='VDD_11_S3_DG5';
NODE_NAME     C2133 1
 '@T6G_MB_LIB.T6G(SCH_1):PAGE67_I110@PURE_QUANTA.Q_CAP(CHIPS)':
 'A': CDS_PINID='A';
NODE_NAME     C2138 1
 '@T6G_MB_LIB.T6G(SCH_1):PAGE67_I112@PURE_QUANTA.Q_CAP(CHIPS)':
 'A': CDS_PINID='A';
NODE_NAME     C2132 1
 '@T6G_MB_LIB.T6G(SCH_1):PAGE67_I113@PURE_QUANTA.Q_CAP(CHIPS)':
 'A': CDS_PINID='A';
NODE_NAME     C2137 1
 '@T6G_MB_LIB.T6G(SCH_1):PAGE67_I115@PURE_QUANTA.Q_CAP(CHIPS)':
 'A': CDS_PINID='A';
NODE_NAME     C3890 1
 '@T6G_MB_LIB.T6G(SCH_1):PAGE67_I116@PURE_QUANTA.Q_CAP(CHIPS)':
 'A': CDS_PINID='A';
NODE_NAME     C3891 1
 '@T6G_MB_LIB.T6G(SCH_1):PAGE67_I117@PURE_QUANTA.Q_CAP(CHIPS)':
 'A': CDS_PINID='A';
NODE_NAME     C3892 1
 '@T6G_MB_LIB.T6G(SCH_1):PAGE67_I118@PURE_QUANTA.Q_CAP(CHIPS)':
 'A': CDS_PINID='A';
NODE_NAME     C3893 1
 '@T6G_MB_LIB.T6G(SCH_1):PAGE67_I120@PURE_QUANTA.Q_CAP(CHIPS)':
 'A': CDS_PINID='A';
NODE_NAME     C2142 1
 '@T6G_MB_LIB.T6G(SCH_1):PAGE67_I121@PURE_QUANTA.Q_CAP(CHIPS)':
 'A': CDS_PINID='A';
NODE_NAME     C2146 1
 '@T6G_MB_LIB.T6G(SCH_1):PAGE67_I122@PURE_QUANTA.Q_CAP(CHIPS)':
 'A': CDS_PINID='A';
NODE_NAME     C2150 1
 '@T6G_MB_LIB.T6G(SCH_1):PAGE67_I123@PURE_QUANTA.Q_CAP(CHIPS)':
 'A': CDS_PINID='A';
NODE_NAME     C2153 1
 '@T6G_MB_LIB.T6G(SCH_1):PAGE67_I124@PURE_QUANTA.Q_CAP(CHIPS)':
 'A': CDS_PINID='A';
NODE_NAME     C2156 1
 '@T6G_MB_LIB.T6G(SCH_1):PAGE67_I125@PURE_QUANTA.Q_CAP(CHIPS)':
 'A': CDS_PINID='A';
NODE_NAME     C2158 1
 '@T6G_MB_LIB.T6G(SCH_1):PAGE67_I127@PURE_QUANTA.Q_CAP(CHIPS)':
 'A': CDS_PINID='A';
NODE_NAME     C2160 1
 '@T6G_MB_LIB.T6G(SCH_1):PAGE67_I128@PURE_QUANTA.Q_CAP(CHIPS)':
 'A': CDS_PINID='A';
NODE_NAME     C2162 1
 '@T6G_MB_LIB.T6G(SCH_1):PAGE67_I129@PURE_QUANTA.Q_CAP(CHIPS)':
 'A': CDS_PINID='A';
NODE_NAME     C3932 1
 '@T6G_MB_LIB.T6G(SCH_1):PAGE69_I53@PURE_QUANTA.Q_CAP(CHIPS)':
 'A': CDS_PINID='A';
NODE_NAME     C2603 1
 '@T6G_MB_LIB.T6G(SCH_1):PAGE69_I58@PURE_QUANTA.Q_CAP(CHIPS)':
 'A': CDS_PINID='A';
NODE_NAME     C2602 1
 '@T6G_MB_LIB.T6G(SCH_1):PAGE69_I60@PURE_QUANTA.Q_CAP(CHIPS)':
 'A': CDS_PINID='A';
NODE_NAME     C2601 1
 '@T6G_MB_LIB.T6G(SCH_1):PAGE69_I71@PURE_QUANTA.Q_CAP(CHIPS)':
 'A': CDS_PINID='A';
NODE_NAME     C2600 1
 '@T6G_MB_LIB.T6G(SCH_1):PAGE69_I76@PURE_QUANTA.Q_CAP(CHIPS)':
 'A': CDS_PINID='A';
NODE_NAME     C3933 1
 '@T6G_MB_LIB.T6G(SCH_1):PAGE69_I111@PURE_QUANTA.Q_CAP(CHIPS)':
 'A': CDS_PINID='A';
NODE_NAME     C2610 1
 '@T6G_MB_LIB.T6G(SCH_1):PAGE69_I112@PURE_QUANTA.Q_CAP(CHIPS)':
 'A': CDS_PINID='A';
NODE_NAME     C2609 1
 '@T6G_MB_LIB.T6G(SCH_1):PAGE69_I113@PURE_QUANTA.Q_CAP(CHIPS)':
 'A': CDS_PINID='A';
NODE_NAME     C2617 1
 '@T6G_MB_LIB.T6G(SCH_1):PAGE69_I114@PURE_QUANTA.Q_CAP(CHIPS)':
 'A': CDS_PINID='A';
NODE_NAME     C2616 1
 '@T6G_MB_LIB.T6G(SCH_1):PAGE69_I115@PURE_QUANTA.Q_CAP(CHIPS)':
 'A': CDS_PINID='A';
NODE_NAME     C2624 1
 '@T6G_MB_LIB.T6G(SCH_1):PAGE69_I116@PURE_QUANTA.Q_CAP(CHIPS)':
 'A': CDS_PINID='A';
NODE_NAME     C2623 1
 '@T6G_MB_LIB.T6G(SCH_1):PAGE69_I117@PURE_QUANTA.Q_CAP(CHIPS)':
 'A': CDS_PINID='A';
NODE_NAME     C2630 1
 '@T6G_MB_LIB.T6G(SCH_1):PAGE69_I118@PURE_QUANTA.Q_CAP(CHIPS)':
 'A': CDS_PINID='A';
NODE_NAME     C2629 1
 '@T6G_MB_LIB.T6G(SCH_1):PAGE69_I119@PURE_QUANTA.Q_CAP(CHIPS)':
 'A': CDS_PINID='A';
NODE_NAME     C2636 1
 '@T6G_MB_LIB.T6G(SCH_1):PAGE69_I120@PURE_QUANTA.Q_CAP(CHIPS)':
 'A': CDS_PINID='A';
NODE_NAME     C2635 1
 '@T6G_MB_LIB.T6G(SCH_1):PAGE69_I121@PURE_QUANTA.Q_CAP(CHIPS)':
 'A': CDS_PINID='A';
NODE_NAME     C2608 1
 '@T6G_MB_LIB.T6G(SCH_1):PAGE69_I122@PURE_QUANTA.Q_CAP(CHIPS)':
 'A': CDS_PINID='A';
NODE_NAME     C2615 1
 '@T6G_MB_LIB.T6G(SCH_1):PAGE69_I123@PURE_QUANTA.Q_CAP(CHIPS)':
 'A': CDS_PINID='A';
NODE_NAME     C2607 1
 '@T6G_MB_LIB.T6G(SCH_1):PAGE69_I124@PURE_QUANTA.Q_CAP(CHIPS)':
 'A': CDS_PINID='A';
NODE_NAME     C2614 1
 '@T6G_MB_LIB.T6G(SCH_1):PAGE69_I125@PURE_QUANTA.Q_CAP(CHIPS)':
 'A': CDS_PINID='A';
NODE_NAME     C2622 1
 '@T6G_MB_LIB.T6G(SCH_1):PAGE69_I126@PURE_QUANTA.Q_CAP(CHIPS)':
 'A': CDS_PINID='A';
NODE_NAME     C2621 1
 '@T6G_MB_LIB.T6G(SCH_1):PAGE69_I127@PURE_QUANTA.Q_CAP(CHIPS)':
 'A': CDS_PINID='A';
NODE_NAME     C2628 1
 '@T6G_MB_LIB.T6G(SCH_1):PAGE69_I129@PURE_QUANTA.Q_CAP(CHIPS)':
 'A': CDS_PINID='A';
NODE_NAME     C2634 1
 '@T6G_MB_LIB.T6G(SCH_1):PAGE69_I130@PURE_QUANTA.Q_CAP(CHIPS)':
 'A': CDS_PINID='A';
NODE_NAME     C2627 1
 '@T6G_MB_LIB.T6G(SCH_1):PAGE69_I131@PURE_QUANTA.Q_CAP(CHIPS)':
 'A': CDS_PINID='A';
NODE_NAME     C2633 1
 '@T6G_MB_LIB.T6G(SCH_1):PAGE69_I132@PURE_QUANTA.Q_CAP(CHIPS)':
 'A': CDS_PINID='A';
NODE_NAME     C2642 1
 '@T6G_MB_LIB.T6G(SCH_1):PAGE69_I133@PURE_QUANTA.Q_CAP(CHIPS)':
 'A': CDS_PINID='A';
NODE_NAME     C2641 1
 '@T6G_MB_LIB.T6G(SCH_1):PAGE69_I134@PURE_QUANTA.Q_CAP(CHIPS)':
 'A': CDS_PINID='A';
NODE_NAME     C2648 1
 '@T6G_MB_LIB.T6G(SCH_1):PAGE69_I135@PURE_QUANTA.Q_CAP(CHIPS)':
 'A': CDS_PINID='A';
NODE_NAME     C2647 1
 '@T6G_MB_LIB.T6G(SCH_1):PAGE69_I136@PURE_QUANTA.Q_CAP(CHIPS)':
 'A': CDS_PINID='A';
NODE_NAME     C3934 1
 '@T6G_MB_LIB.T6G(SCH_1):PAGE69_I138@PURE_QUANTA.Q_CAP(CHIPS)':
 'A': CDS_PINID='A';
NODE_NAME     C2653 1
 '@T6G_MB_LIB.T6G(SCH_1):PAGE69_I139@PURE_QUANTA.Q_CAP(CHIPS)':
 'A': CDS_PINID='A';
NODE_NAME     C3935 1
 '@T6G_MB_LIB.T6G(SCH_1):PAGE69_I140@PURE_QUANTA.Q_CAP(CHIPS)':
 'A': CDS_PINID='A';
NODE_NAME     C2658 1
 '@T6G_MB_LIB.T6G(SCH_1):PAGE69_I142@PURE_QUANTA.Q_CAP(CHIPS)':
 'A': CDS_PINID='A';
NODE_NAME     C2640 1
 '@T6G_MB_LIB.T6G(SCH_1):PAGE69_I143@PURE_QUANTA.Q_CAP(CHIPS)':
 'A': CDS_PINID='A';
NODE_NAME     C2646 1
 '@T6G_MB_LIB.T6G(SCH_1):PAGE69_I144@PURE_QUANTA.Q_CAP(CHIPS)':
 'A': CDS_PINID='A';
NODE_NAME     C2639 1
 '@T6G_MB_LIB.T6G(SCH_1):PAGE69_I145@PURE_QUANTA.Q_CAP(CHIPS)':
 'A': CDS_PINID='A';
NODE_NAME     C2645 1
 '@T6G_MB_LIB.T6G(SCH_1):PAGE69_I146@PURE_QUANTA.Q_CAP(CHIPS)':
 'A': CDS_PINID='A';
NODE_NAME     C2652 1
 '@T6G_MB_LIB.T6G(SCH_1):PAGE69_I147@PURE_QUANTA.Q_CAP(CHIPS)':
 'A': CDS_PINID='A';
NODE_NAME     C2657 1
 '@T6G_MB_LIB.T6G(SCH_1):PAGE69_I149@PURE_QUANTA.Q_CAP(CHIPS)':
 'A': CDS_PINID='A';
NODE_NAME     C2651 1
 '@T6G_MB_LIB.T6G(SCH_1):PAGE69_I151@PURE_QUANTA.Q_CAP(CHIPS)':
 'A': CDS_PINID='A';
NODE_NAME     C2656 1
 '@T6G_MB_LIB.T6G(SCH_1):PAGE69_I152@PURE_QUANTA.Q_CAP(CHIPS)':
 'A': CDS_PINID='A';
NODE_NAME     R363 1
 '@T6G_MB_LIB.T6G(SCH_1):PAGE138_I56@PURE_QUANTA.Q_RES(CHIPS)':
 'A': CDS_PINID='A';
NODE_NAME     PL22 2
 '@T6G_MB_LIB.T6G(SCH_1):PAGE183_I52@PURE_QUANTA.Q_INDUCTOR(CHIPS)':
 '2': CDS_PINID='\2\';
NODE_NAME     PC229 1
 '@T6G_MB_LIB.T6G(SCH_1):PAGE183_I66@PURE_QUANTA.Q_CAPP(CHIPS)':
 'A': CDS_PINID='A';
NODE_NAME     PC230 1
 '@T6G_MB_LIB.T6G(SCH_1):PAGE183_I67@PURE_QUANTA.Q_CAPP(CHIPS)':
 'A': CDS_PINID='A';
NODE_NAME     PC801 1
 '@T6G_MB_LIB.T6G(SCH_1):PAGE183_I70@PURE_QUANTA.Q_CAPP(CHIPS)':
 'A': CDS_PINID='A';
NODE_NAME     PC224_1 1
 '@T6G_MB_LIB.T6G(SCH_1):PAGE183_I81@PURE_QUANTA.Q_CAP(CHIPS)':
 'A': CDS_PINID='A';
NODE_NAME     R5006 1
 '@T6G_MB_LIB.T6G(SCH_1):PAGE136_I145@PURE_QUANTA.Q_RES(CHIPS)':
 'A': CDS_PINID='A';
NODE_NAME     R5007 1
 '@T6G_MB_LIB.T6G(SCH_1):PAGE136_I147@PURE_QUANTA.Q_RES(CHIPS)':
 'A': CDS_PINID='A';
NODE_NAME     R5008 1
 '@T6G_MB_LIB.T6G(SCH_1):PAGE136_I148@PURE_QUANTA.Q_RES(CHIPS)':
 'A': CDS_PINID='A';
NODE_NAME     R5009 1
 '@T6G_MB_LIB.T6G(SCH_1):PAGE136_I150@PURE_QUANTA.Q_RES(CHIPS)':
 'A': CDS_PINID='A';
NODE_NAME     R5015 1
 '@T6G_MB_LIB.T6G(SCH_1):PAGE136_I157@PURE_QUANTA.Q_RES(CHIPS)':
 'A': CDS_PINID='A';
NODE_NAME     R5014 1
 '@T6G_MB_LIB.T6G(SCH_1):PAGE136_I159@PURE_QUANTA.Q_RES(CHIPS)':
 'A': CDS_PINID='A';
NODE_NAME     R5017 1
 '@T6G_MB_LIB.T6G(SCH_1):PAGE136_I161@PURE_QUANTA.Q_RES(CHIPS)':
 'A': CDS_PINID='A';
NODE_NAME     R5016 1
 '@T6G_MB_LIB.T6G(SCH_1):PAGE136_I162@PURE_QUANTA.Q_RES(CHIPS)':
 'A': CDS_PINID='A';
NODE_NAME     R360 1
 '@T6G_MB_LIB.T6G(SCH_1):PAGE138_I55@PURE_QUANTA.Q_RES(CHIPS)':
 'A': CDS_PINID='A';
NODE_NAME     R420 1
 '@T6G_MB_LIB.T6G(SCH_1):PAGE28_I22@PURE_QUANTA.Q_RES(CHIPS)':
 'A': CDS_PINID='A';
NODE_NAME     R425 1
 '@T6G_MB_LIB.T6G(SCH_1):PAGE28_I25@PURE_QUANTA.Q_RES(CHIPS)':
 'A': CDS_PINID='A';
NODE_NAME     PR114 1
 '@T6G_MB_LIB.T6G(SCH_1):PAGE182_I30@PURE_QUANTA.Q_RES(CHIPS)':
 'A': CDS_PINID='A';
NODE_NAME     PR137 2
 '@T6G_MB_LIB.T6G(SCH_1):PAGE183_I56@PURE_QUANTA.Q_RES(CHIPS)':
 'B': CDS_PINID='B';
NODE_NAME     PC223 1
 '@T6G_MB_LIB.T6G(SCH_1):PAGE183_I58@PURE_QUANTA.Q_CAPP(CHIPS)':
 'A': CDS_PINID='A';
NODE_NAME     PC226 1
 '@T6G_MB_LIB.T6G(SCH_1):PAGE183_I59@PURE_QUANTA.Q_CAPP(CHIPS)':
 'A': CDS_PINID='A';
NODE_NAME     PC225_2 1
 '@T6G_MB_LIB.T6G(SCH_1):PAGE183_I62@PURE_QUANTA.Q_CAP(CHIPS)':
 'A': CDS_PINID='A';
NODE_NAME     PC228 1
 '@T6G_MB_LIB.T6G(SCH_1):PAGE183_I65@PURE_QUANTA.Q_CAPP(CHIPS)':
 'A': CDS_PINID='A';
NODE_NAME     PL23 2
 '@T6G_MB_LIB.T6G(SCH_1):PAGE183_I73@PURE_QUANTA.Q_INDUCTOR(CHIPS)':
 '2': CDS_PINID='\2\';
NODE_NAME     PC222 1
 '@T6G_MB_LIB.T6G(SCH_1):PAGE183_I76@PURE_QUANTA.Q_CAP(CHIPS)':
 'A': CDS_PINID='A';
NODE_NAME     PC227_1 1
 '@T6G_MB_LIB.T6G(SCH_1):PAGE183_I82@PURE_QUANTA.Q_CAP(CHIPS)':
 'A': CDS_PINID='A';
NODE_NAME     PR414 1
 '@T6G_MB_LIB.T6G(SCH_1):PAGE183_I83@PURE_QUANTA.Q_RES(CHIPS)':
 'A': CDS_PINID='A';
NODE_NAME     PC800 1
 '@T6G_MB_LIB.T6G(SCH_1):PAGE183_I89@PURE_QUANTA.Q_CAPP(CHIPS)':
 'A': CDS_PINID='A';
NODE_NAME     PC221_2 1
 '@T6G_MB_LIB.T6G(SCH_1):PAGE183_I90@PURE_QUANTA.Q_CAP(CHIPS)':
 'A': CDS_PINID='A';
NODE_NAME     PR138 2
 '@T6G_MB_LIB.T6G(SCH_1):PAGE183_I91@PURE_QUANTA.Q_RES(CHIPS)':
 'B': CDS_PINID='B';
NODE_NAME     R421 1
 '@T6G_MB_LIB.T6G(SCH_1):PAGE28_I23@PURE_QUANTA.Q_RES(CHIPS)':
 'A': CDS_PINID='A';
NODE_NAME     R423 1
 '@T6G_MB_LIB.T6G(SCH_1):PAGE28_I24@PURE_QUANTA.Q_RES(CHIPS)':
 'A': CDS_PINID='A';
NODE_NAME     R6081 1
 '@T6G_MB_LIB.T6G(SCH_1):PAGE28_I210@PURE_QUANTA.Q_RES(CHIPS)':
 'A': CDS_PINID='A';
NODE_NAME     R6082 1
 '@T6G_MB_LIB.T6G(SCH_1):PAGE28_I212@PURE_QUANTA.Q_RES(CHIPS)':
 'A': CDS_PINID='A';
NODE_NAME     R6083 1
 '@T6G_MB_LIB.T6G(SCH_1):PAGE28_I213@PURE_QUANTA.Q_RES(CHIPS)':
 'A': CDS_PINID='A';
NODE_NAME     R6084 1
 '@T6G_MB_LIB.T6G(SCH_1):PAGE28_I214@PURE_QUANTA.Q_RES(CHIPS)':
 'A': CDS_PINID='A';
NODE_NAME     C3 1
 '@T6G_MB_LIB.T6G(SCH_1):PAGE137_I56@PURE_QUANTA.Q_CAP(CHIPS)':
 'A': CDS_PINID='A';
NODE_NAME     R322 1
 '@T6G_MB_LIB.T6G(SCH_1):PAGE137_I73@PURE_QUANTA.Q_RES(CHIPS)':
 'A': CDS_PINID='A';
NODE_NAME     R290 1
 '@T6G_MB_LIB.T6G(SCH_1):PAGE137_I78@PURE_QUANTA.Q_RES(CHIPS)':
 'A': CDS_PINID='A';
NODE_NAME     U2 1
 '@T6G_MB_LIB.T6G(SCH_1):PAGE137_I99@PURE_QUANTA.PCA9617ADP(CHIPS)':
 'VCCA': CDS_PINID='VCCA';
NET_NAME
'PVDD11_S3_P0_ADDR_CFG'
 '@T6G_MB_LIB.T6G(SCH_1):PVDD11_S3_P0_ADDR_CFG':
 C_SIGNAL='@t6g_mb_lib.t6g(sch_1):pvdd11_s3_p0_addr_cfg';
NODE_NAME     PR126 1
 '@T6G_MB_LIB.T6G(SCH_1):PAGE182_I22@PURE_QUANTA.Q_RES(CHIPS)':
 'A': CDS_PINID='A';
NODE_NAME     PU21 34
 '@T6G_MB_LIB.T6G(SCH_1):PAGE182_I24@PURE_QUANTA.RAA229621GNPHA0(CHIPS)':
 'EN1||ADDR_CFG': CDS_PINID='\en1||addr_cfg\';
NET_NAME
'PVDD11_S3_P0_EN'
 '@T6G_MB_LIB.T6G(SCH_1):PVDD11_S3_P0_EN':
 C_SIGNAL='@t6g_mb_lib.t6g(sch_1):pvdd11_s3_p0_en';
NODE_NAME     R227 2
 '@T6G_MB_LIB.T6G(SCH_1):PAGE81_I103@PURE_QUANTA.Q_RES(CHIPS)':
 'B': CDS_PINID='B';
NODE_NAME     R123 1
 '@T6G_MB_LIB.T6G(SCH_1):PAGE182_I43@PURE_QUANTA.Q_RES(CHIPS)':
 'A': CDS_PINID='A';
NET_NAME
'PVDD11_S3_P0_EN_R'
 '@T6G_MB_LIB.T6G(SCH_1):PVDD11_S3_P0_EN_R':
 C_SIGNAL='@t6g_mb_lib.t6g(sch_1):pvdd11_s3_p0_en_r';
NODE_NAME     PU21 13
 '@T6G_MB_LIB.T6G(SCH_1):PAGE182_I24@PURE_QUANTA.RAA229621GNPHA0(CHIPS)':
 'EN0': CDS_PINID='EN0';
NODE_NAME     R123 2
 '@T6G_MB_LIB.T6G(SCH_1):PAGE182_I43@PURE_QUANTA.Q_RES(CHIPS)':
 'B': CDS_PINID='B';
NODE_NAME     C197 1
 '@T6G_MB_LIB.T6G(SCH_1):PAGE182_I45@PURE_QUANTA.Q_CAP(CHIPS)':
 'A': CDS_PINID='A';
NET_NAME
'PVDD11_S3_P0_IMON1'
 '@T6G_MB_LIB.T6G(SCH_1):PVDD11_S3_P0_IMON1':
 C_SIGNAL='@t6g_mb_lib.t6g(sch_1):pvdd11_s3_p0_imon1';
NODE_NAME     PU21 23
 '@T6G_MB_LIB.T6G(SCH_1):PAGE182_I24@PURE_QUANTA.RAA229621GNPHA0(CHIPS)':
 'CS7': CDS_PINID='CS7';
NODE_NAME     PU22 38
 '@T6G_MB_LIB.T6G(SCH_1):PAGE183_I92@PURE_QUANTA.ISL99390FRZTR5935(CHIPS)':
 'IOUT': CDS_PINID='IOUT';
NET_NAME
'PVDD11_S3_P0_IMON2'
 '@T6G_MB_LIB.T6G(SCH_1):PVDD11_S3_P0_IMON2':
 C_SIGNAL='@t6g_mb_lib.t6g(sch_1):pvdd11_s3_p0_imon2';
NODE_NAME     PU21 24
 '@T6G_MB_LIB.T6G(SCH_1):PAGE182_I24@PURE_QUANTA.RAA229621GNPHA0(CHIPS)':
 'CS6': CDS_PINID='CS6';
NODE_NAME     PU23 38
 '@T6G_MB_LIB.T6G(SCH_1):PAGE183_I13@PURE_QUANTA.ISL99390FRZTR5935(CHIPS)':
 'IOUT': CDS_PINID='IOUT';
NET_NAME
'PVDD11_S3_P0_LSET1'
 '@T6G_MB_LIB.T6G(SCH_1):PVDD11_S3_P0_LSET1':
 C_SIGNAL='@t6g_mb_lib.t6g(sch_1):pvdd11_s3_p0_lset1';
NODE_NAME     PR133 2
 '@T6G_MB_LIB.T6G(SCH_1):PAGE183_I37@PURE_QUANTA.Q_RES(CHIPS)':
 'B': CDS_PINID='B';
NODE_NAME     PU22 37
 '@T6G_MB_LIB.T6G(SCH_1):PAGE183_I92@PURE_QUANTA.ISL99390FRZTR5935(CHIPS)':
 'LSET': CDS_PINID='LSET';
NET_NAME
'PVDD11_S3_P0_LSET2'
 '@T6G_MB_LIB.T6G(SCH_1):PVDD11_S3_P0_LSET2':
 C_SIGNAL='@t6g_mb_lib.t6g(sch_1):pvdd11_s3_p0_lset2';
NODE_NAME     PR134 2
 '@T6G_MB_LIB.T6G(SCH_1):PAGE183_I11@PURE_QUANTA.Q_RES(CHIPS)':
 'B': CDS_PINID='B';
NODE_NAME     PU23 37
 '@T6G_MB_LIB.T6G(SCH_1):PAGE183_I13@PURE_QUANTA.ISL99390FRZTR5935(CHIPS)':
 'LSET': CDS_PINID='LSET';
NET_NAME
'PVDD11_S3_P0_OCP_N'
 '@T6G_MB_LIB.T6G(SCH_1):PVDD11_S3_P0_OCP_N':
 C_SIGNAL='@t6g_mb_lib.t6g(sch_1):pvdd11_s3_p0_ocp_n';
NODE_NAME     R8116 1
 '@T6G_MB_LIB.T6G(SCH_1):PAGE182_I13@PURE_QUANTA.Q_RES(CHIPS)':
 'A': CDS_PINID='A';
NODE_NAME     R226 2
 '@T6G_MB_LIB.T6G(SCH_1):PAGE81_I111@PURE_QUANTA.Q_RES(CHIPS)':
 'B': CDS_PINID='B';
NET_NAME
'PVDD11_S3_P0_OCP_N_R'
 '@T6G_MB_LIB.T6G(SCH_1):PVDD11_S3_P0_OCP_N_R':
 C_SIGNAL='@t6g_mb_lib.t6g(sch_1):pvdd11_s3_p0_ocp_n_r';
NODE_NAME     R8116 2
 '@T6G_MB_LIB.T6G(SCH_1):PAGE182_I13@PURE_QUANTA.Q_RES(CHIPS)':
 'B': CDS_PINID='B';
NODE_NAME     PU21 33
 '@T6G_MB_LIB.T6G(SCH_1):PAGE182_I24@PURE_QUANTA.RAA229621GNPHA0(CHIPS)':
 'OCP_L': CDS_PINID='OCP_L';
NODE_NAME     R124 2
 '@T6G_MB_LIB.T6G(SCH_1):PAGE182_I25@PURE_QUANTA.Q_RES(CHIPS)':
 'B': CDS_PINID='B';
NET_NAME
'PVDD11_S3_P0_PMALERT'
 '@T6G_MB_LIB.T6G(SCH_1):PVDD11_S3_P0_PMALERT':
 C_SIGNAL='@t6g_mb_lib.t6g(sch_1):pvdd11_s3_p0_pmalert';
NODE_NAME     R1189 1
 '@T6G_MB_LIB.T6G(SCH_1):PAGE82_I57@PURE_QUANTA.Q_RES(CHIPS)':
 'A': CDS_PINID='A';
NODE_NAME     U18 L7
 '@T6G_MB_LIB.T6G(SCH_1):PAGE81_I143@PURE_QUANTA.LCMXO3LF9400C5BG484C(CHIPS)':
 'PL13A': CDS_PINID='PL13A';
NODE_NAME     R120 1
 '@T6G_MB_LIB.T6G(SCH_1):PAGE182_I39@PURE_QUANTA.Q_RES(CHIPS)':
 'A': CDS_PINID='A';
NODE_NAME     C5009 1
 '@T6G_MB_LIB.T6G(SCH_1):PAGE182_I88@PURE_QUANTA.Q_CAP(CHIPS)':
 'A': CDS_PINID='A';
NET_NAME
'PVDD11_S3_P0_PMALERT_R'
 '@T6G_MB_LIB.T6G(SCH_1):PVDD11_S3_P0_PMALERT_R':
 C_SIGNAL='@t6g_mb_lib.t6g(sch_1):pvdd11_s3_p0_pmalert_r';
NODE_NAME     PU21 11
 '@T6G_MB_LIB.T6G(SCH_1):PAGE182_I24@PURE_QUANTA.RAA229621GNPHA0(CHIPS)':
 'NPMALERT': CDS_PINID='NPMALERT';
NODE_NAME     R120 2
 '@T6G_MB_LIB.T6G(SCH_1):PAGE182_I39@PURE_QUANTA.Q_RES(CHIPS)':
 'B': CDS_PINID='B';
NET_NAME
'PVDD11_S3_P0_PMSCL_R'
 '@T6G_MB_LIB.T6G(SCH_1):PVDD11_S3_P0_PMSCL_R':
 C_SIGNAL='@t6g_mb_lib.t6g(sch_1):pvdd11_s3_p0_pmscl_r';
NODE_NAME     PU21 10
 '@T6G_MB_LIB.T6G(SCH_1):PAGE182_I24@PURE_QUANTA.RAA229621GNPHA0(CHIPS)':
 'PMSCL': CDS_PINID='PMSCL';
NODE_NAME     R118 2
 '@T6G_MB_LIB.T6G(SCH_1):PAGE182_I41@PURE_QUANTA.Q_RES(CHIPS)':
 'B': CDS_PINID='B';
NET_NAME
'PVDD11_S3_P0_PMSDA_R'
 '@T6G_MB_LIB.T6G(SCH_1):PVDD11_S3_P0_PMSDA_R':
 C_SIGNAL='@t6g_mb_lib.t6g(sch_1):pvdd11_s3_p0_pmsda_r';
NODE_NAME     PU21 9
 '@T6G_MB_LIB.T6G(SCH_1):PAGE182_I24@PURE_QUANTA.RAA229621GNPHA0(CHIPS)':
 'PMSDA': CDS_PINID='PMSDA';
NODE_NAME     R119 2
 '@T6G_MB_LIB.T6G(SCH_1):PAGE182_I40@PURE_QUANTA.Q_RES(CHIPS)':
 'B': CDS_PINID='B';
NET_NAME
'PVDD11_S3_P0_PVCC'
 '@T6G_MB_LIB.T6G(SCH_1):PVDD11_S3_P0_PVCC':
 C_SIGNAL='@t6g_mb_lib.t6g(sch_1):pvdd11_s3_p0_pvcc',
 CDS_GLOBAL_NET='TRUE';
NODE_NAME     PU23 4
 '@T6G_MB_LIB.T6G(SCH_1):PAGE183_I13@PURE_QUANTA.ISL99390FRZTR5935(CHIPS)':
 'PVCC': CDS_PINID='PVCC';
NODE_NAME     PR132 1
 '@T6G_MB_LIB.T6G(SCH_1):PAGE183_I14@PURE_QUANTA.Q_RES(CHIPS)':
 'A': CDS_PINID='A';
NODE_NAME     PC206_11P0_2 1
 '@T6G_MB_LIB.T6G(SCH_1):PAGE183_I17@PURE_QUANTA.Q_CAP(CHIPS)':
 'A': CDS_PINID='A';
NODE_NAME     PR131 1
 '@T6G_MB_LIB.T6G(SCH_1):PAGE183_I40@PURE_QUANTA.Q_RES(CHIPS)':
 'A': CDS_PINID='A';
NODE_NAME     PC205_11P0_1 1
 '@T6G_MB_LIB.T6G(SCH_1):PAGE183_I42@PURE_QUANTA.Q_CAP(CHIPS)':
 'A': CDS_PINID='A';
NODE_NAME     PR411 1
 '@T6G_MB_LIB.T6G(SCH_1):PAGE183_I85@PURE_QUANTA.Q_RES(CHIPS)':
 'A': CDS_PINID='A';
NODE_NAME     PR413 1
 '@T6G_MB_LIB.T6G(SCH_1):PAGE183_I86@PURE_QUANTA.Q_RES(CHIPS)':
 'A': CDS_PINID='A';
NODE_NAME     PU22 4
 '@T6G_MB_LIB.T6G(SCH_1):PAGE183_I92@PURE_QUANTA.ISL99390FRZTR5935(CHIPS)':
 'PVCC': CDS_PINID='PVCC';
NET_NAME
'PVDD11_S3_P0_PWM1'
 '@T6G_MB_LIB.T6G(SCH_1):PVDD11_S3_P0_PWM1':
 C_SIGNAL='@t6g_mb_lib.t6g(sch_1):pvdd11_s3_p0_pwm1';
NODE_NAME     PU21 8
 '@T6G_MB_LIB.T6G(SCH_1):PAGE182_I24@PURE_QUANTA.RAA229621GNPHA0(CHIPS)':
 'PWM7': CDS_PINID='PWM7';
NODE_NAME     PU22 34
 '@T6G_MB_LIB.T6G(SCH_1):PAGE183_I92@PURE_QUANTA.ISL99390FRZTR5935(CHIPS)':
 'PWM': CDS_PINID='PWM';
NET_NAME
'PVDD11_S3_P0_PWM2'
 '@T6G_MB_LIB.T6G(SCH_1):PVDD11_S3_P0_PWM2':
 C_SIGNAL='@t6g_mb_lib.t6g(sch_1):pvdd11_s3_p0_pwm2';
NODE_NAME     PU21 7
 '@T6G_MB_LIB.T6G(SCH_1):PAGE182_I24@PURE_QUANTA.RAA229621GNPHA0(CHIPS)':
 'PWM6': CDS_PINID='PWM6';
NODE_NAME     PU23 34
 '@T6G_MB_LIB.T6G(SCH_1):PAGE183_I13@PURE_QUANTA.ISL99390FRZTR5935(CHIPS)':
 'PWM': CDS_PINID='PWM';
NET_NAME
'PVDD11_S3_P0_RESET_N'
 '@T6G_MB_LIB.T6G(SCH_1):PVDD11_S3_P0_RESET_N':
 C_SIGNAL='@t6g_mb_lib.t6g(sch_1):pvdd11_s3_p0_reset_n';
NODE_NAME     PR129 2
 '@T6G_MB_LIB.T6G(SCH_1):PAGE182_I67@PURE_QUANTA.Q_RES(CHIPS)':
 'B': CDS_PINID='B';
NODE_NAME     U18 H17
 '@T6G_MB_LIB.T6G(SCH_1):PAGE80_I217@PURE_QUANTA.LCMXO3LF9400C5BG484C(CHIPS)':
 'PR10C': CDS_PINID='PR10C';
NET_NAME
'PVDD11_S3_P0_RESET_N_R'
 '@T6G_MB_LIB.T6G(SCH_1):PVDD11_S3_P0_RESET_N_R':
 C_SIGNAL='@t6g_mb_lib.t6g(sch_1):pvdd11_s3_p0_reset_n_r';
NODE_NAME     PR129 1
 '@T6G_MB_LIB.T6G(SCH_1):PAGE182_I67@PURE_QUANTA.Q_RES(CHIPS)':
 'A': CDS_PINID='A';
NODE_NAME     PR128 1
 '@T6G_MB_LIB.T6G(SCH_1):PAGE182_I68@PURE_QUANTA.Q_RES(CHIPS)':
 'A': CDS_PINID='A';
NODE_NAME     PU21 14
 '@T6G_MB_LIB.T6G(SCH_1):PAGE182_I24@PURE_QUANTA.RAA229621GNPHA0(CHIPS)':
 'RESET_L': CDS_PINID='RESET_L';
NODE_NAME     PR127 1
 '@T6G_MB_LIB.T6G(SCH_1):PAGE182_I57@PURE_QUANTA.Q_RES(CHIPS)':
 'A': CDS_PINID='A';
NET_NAME
'PVDD11_S3_P0_TEMP0'
 '@T6G_MB_LIB.T6G(SCH_1):PVDD11_S3_P0_TEMP0':
 C_SIGNAL='@t6g_mb_lib.t6g(sch_1):pvdd11_s3_p0_temp0';
NODE_NAME     PU21 36
 '@T6G_MB_LIB.T6G(SCH_1):PAGE182_I24@PURE_QUANTA.RAA229621GNPHA0(CHIPS)':
 'TEMP0': CDS_PINID='TEMP0';
NODE_NAME     PC198 1
 '@T6G_MB_LIB.T6G(SCH_1):PAGE182_I50@PURE_QUANTA.Q_CAP(CHIPS)':
 'A': CDS_PINID='A';
NODE_NAME     PU23 36
 '@T6G_MB_LIB.T6G(SCH_1):PAGE183_I13@PURE_QUANTA.ISL99390FRZTR5935(CHIPS)':
 'TOUT_FLT': CDS_PINID='TOUT_FLT';
NODE_NAME     PU22 36
 '@T6G_MB_LIB.T6G(SCH_1):PAGE183_I92@PURE_QUANTA.ISL99390FRZTR5935(CHIPS)':
 'TOUT_FLT': CDS_PINID='TOUT_FLT';
NET_NAME
'PVDD11_S3_P0_TEMP1'
 '@T6G_MB_LIB.T6G(SCH_1):PVDD11_S3_P0_TEMP1':
 C_SIGNAL='@t6g_mb_lib.t6g(sch_1):pvdd11_s3_p0_temp1';
NODE_NAME     PU21 35
 '@T6G_MB_LIB.T6G(SCH_1):PAGE182_I24@PURE_QUANTA.RAA229621GNPHA0(CHIPS)':
 'TEMP1': CDS_PINID='TEMP1';
NODE_NAME     PR412 1
 '@T6G_MB_LIB.T6G(SCH_1):PAGE182_I52@PURE_QUANTA.Q_RES(CHIPS)':
 'A': CDS_PINID='A';
NET_NAME
'PVDD11_S3_P0_VCC'
 '@T6G_MB_LIB.T6G(SCH_1):PVDD11_S3_P0_VCC':
 C_SIGNAL='@t6g_mb_lib.t6g(sch_1):pvdd11_s3_p0_vcc';
NODE_NAME     PC200 1
 '@T6G_MB_LIB.T6G(SCH_1):PAGE182_I82@PURE_QUANTA.Q_CAP(CHIPS)':
 'A': CDS_PINID='A';
NODE_NAME     PU21 39
 '@T6G_MB_LIB.T6G(SCH_1):PAGE182_I24@PURE_QUANTA.RAA229621GNPHA0(CHIPS)':
 'VCC': CDS_PINID='VCC';
NODE_NAME     PC4 1
 '@T6G_MB_LIB.T6G(SCH_1):PAGE182_I79@PURE_QUANTA.Q_CAP(CHIPS)':
 'A': CDS_PINID='A';
NODE_NAME     PR130 1
 '@T6G_MB_LIB.T6G(SCH_1):PAGE182_I85@PURE_QUANTA.Q_RES(CHIPS)':
 'A': CDS_PINID='A';
NET_NAME
'PVDD11_S3_P0_VCC1'
 '@T6G_MB_LIB.T6G(SCH_1):PVDD11_S3_P0_VCC1':
 C_SIGNAL='@t6g_mb_lib.t6g(sch_1):pvdd11_s3_p0_vcc1';
NODE_NAME     PC203 1
 '@T6G_MB_LIB.T6G(SCH_1):PAGE183_I36@PURE_QUANTA.Q_CAP(CHIPS)':
 'A': CDS_PINID='A';
NODE_NAME     PR131 2
 '@T6G_MB_LIB.T6G(SCH_1):PAGE183_I40@PURE_QUANTA.Q_RES(CHIPS)':
 'B': CDS_PINID='B';
NODE_NAME     PU22 35
 '@T6G_MB_LIB.T6G(SCH_1):PAGE183_I92@PURE_QUANTA.ISL99390FRZTR5935(CHIPS)':
 'EN': CDS_PINID='EN';
NODE_NAME     PU22 3
 '@T6G_MB_LIB.T6G(SCH_1):PAGE183_I92@PURE_QUANTA.ISL99390FRZTR5935(CHIPS)':
 'VCC': CDS_PINID='VCC';
NET_NAME
'PVDD11_S3_P0_VCC2'
 '@T6G_MB_LIB.T6G(SCH_1):PVDD11_S3_P0_VCC2':
 C_SIGNAL='@t6g_mb_lib.t6g(sch_1):pvdd11_s3_p0_vcc2';
NODE_NAME     PC204 1
 '@T6G_MB_LIB.T6G(SCH_1):PAGE183_I9@PURE_QUANTA.Q_CAP(CHIPS)':
 'A': CDS_PINID='A';
NODE_NAME     PU23 35
 '@T6G_MB_LIB.T6G(SCH_1):PAGE183_I13@PURE_QUANTA.ISL99390FRZTR5935(CHIPS)':
 'EN': CDS_PINID='EN';
NODE_NAME     PU23 3
 '@T6G_MB_LIB.T6G(SCH_1):PAGE183_I13@PURE_QUANTA.ISL99390FRZTR5935(CHIPS)':
 'VCC': CDS_PINID='VCC';
NODE_NAME     PR132 2
 '@T6G_MB_LIB.T6G(SCH_1):PAGE183_I14@PURE_QUANTA.Q_RES(CHIPS)':
 'B': CDS_PINID='B';
NET_NAME
'PVDD11_S3_P0_VCCS'
 '@T6G_MB_LIB.T6G(SCH_1):PVDD11_S3_P0_VCCS':
 C_SIGNAL='@t6g_mb_lib.t6g(sch_1):pvdd11_s3_p0_vccs';
NODE_NAME     PC9 1
 '@T6G_MB_LIB.T6G(SCH_1):PAGE182_I77@PURE_QUANTA.Q_CAP(CHIPS)':
 'A': CDS_PINID='A';
NODE_NAME     PC201_1 1
 '@T6G_MB_LIB.T6G(SCH_1):PAGE183_I34@PURE_QUANTA.Q_CAP(CHIPS)':
 'A': CDS_PINID='A';
NODE_NAME     PU21 40
 '@T6G_MB_LIB.T6G(SCH_1):PAGE182_I24@PURE_QUANTA.RAA229621GNPHA0(CHIPS)':
 'VCCS': CDS_PINID='VCCS';
NODE_NAME     PC199 1
 '@T6G_MB_LIB.T6G(SCH_1):PAGE182_I80@PURE_QUANTA.Q_CAP(CHIPS)':
 'A': CDS_PINID='A';
NODE_NAME     PC202_2 1
 '@T6G_MB_LIB.T6G(SCH_1):PAGE183_I7@PURE_QUANTA.Q_CAP(CHIPS)':
 'A': CDS_PINID='A';
NODE_NAME     PU23 39
 '@T6G_MB_LIB.T6G(SCH_1):PAGE183_I13@PURE_QUANTA.ISL99390FRZTR5935(CHIPS)':
 'REFIN': CDS_PINID='REFIN';
NODE_NAME     PU22 39
 '@T6G_MB_LIB.T6G(SCH_1):PAGE183_I92@PURE_QUANTA.ISL99390FRZTR5935(CHIPS)':
 'REFIN': CDS_PINID='REFIN';
NET_NAME
'PVDD11_S3_P0_VDDIO'
 '@T6G_MB_LIB.T6G(SCH_1):PVDD11_S3_P0_VDDIO':
 C_SIGNAL='@t6g_mb_lib.t6g(sch_1):pvdd11_s3_p0_vddio';
NODE_NAME     R8458 2
 '@T6G_MB_LIB.T6G(SCH_1):PAGE182_I9@PURE_QUANTA.Q_RES(CHIPS)':
 'B': CDS_PINID='B';
NODE_NAME     PU21 15
 '@T6G_MB_LIB.T6G(SCH_1):PAGE182_I24@PURE_QUANTA.RAA229621GNPHA0(CHIPS)':
 'VDDIO': CDS_PINID='VDDIO';
NET_NAME
'PVDD11_S3_P0_VINSEN'
 '@T6G_MB_LIB.T6G(SCH_1):PVDD11_S3_P0_VINSEN':
 C_SIGNAL='@t6g_mb_lib.t6g(sch_1):pvdd11_s3_p0_vinsen';
NODE_NAME     PR125 2
 '@T6G_MB_LIB.T6G(SCH_1):PAGE182_I16@PURE_QUANTA.Q_RES(CHIPS)':
 'B': CDS_PINID='B';
NODE_NAME     PR601 1
 '@T6G_MB_LIB.T6G(SCH_1):PAGE182_I18@PURE_QUANTA.Q_RES(CHIPS)':
 'A': CDS_PINID='A';
NODE_NAME     PC5 1
 '@T6G_MB_LIB.T6G(SCH_1):PAGE182_I20@PURE_QUANTA.Q_CAP(CHIPS)':
 'A': CDS_PINID='A';
NODE_NAME     PU21 38
 '@T6G_MB_LIB.T6G(SCH_1):PAGE182_I24@PURE_QUANTA.RAA229621GNPHA0(CHIPS)':
 'VINSEN': CDS_PINID='VINSEN';
NET_NAME
'PVDD11_S3_P0_VMON'
 '@T6G_MB_LIB.T6G(SCH_1):PVDD11_S3_P0_VMON':
 C_SIGNAL='@t6g_mb_lib.t6g(sch_1):pvdd11_s3_p0_vmon';
NODE_NAME     PR113 2
 '@T6G_MB_LIB.T6G(SCH_1):PAGE182_I2@PURE_QUANTA.Q_RES(CHIPS)':
 'B': CDS_PINID='B';
NODE_NAME     PC193 1
 '@T6G_MB_LIB.T6G(SCH_1):PAGE182_I4@PURE_QUANTA.Q_CAP(CHIPS)':
 'A': CDS_PINID='A';
NODE_NAME     PR3 1
 '@T6G_MB_LIB.T6G(SCH_1):PAGE182_I6@PURE_QUANTA.Q_RES(CHIPS)':
 'A': CDS_PINID='A';
NODE_NAME     PU21 37
 '@T6G_MB_LIB.T6G(SCH_1):PAGE182_I24@PURE_QUANTA.RAA229621GNPHA0(CHIPS)':
 'VMON||IINSEN': CDS_PINID='\vmon||iinsen\';
NET_NAME
'PVDD11_S3_P0_VOS1'
 '@T6G_MB_LIB.T6G(SCH_1):PVDD11_S3_P0_VOS1':
 C_SIGNAL='@t6g_mb_lib.t6g(sch_1):pvdd11_s3_p0_vos1';
NODE_NAME     PR137 1
 '@T6G_MB_LIB.T6G(SCH_1):PAGE183_I56@PURE_QUANTA.Q_RES(CHIPS)':
 'A': CDS_PINID='A';
NODE_NAME     PU22 1
 '@T6G_MB_LIB.T6G(SCH_1):PAGE183_I92@PURE_QUANTA.ISL99390FRZTR5935(CHIPS)':
 'VOS': CDS_PINID='VOS';
NET_NAME
'PVDD11_S3_P0_VOS2'
 '@T6G_MB_LIB.T6G(SCH_1):PVDD11_S3_P0_VOS2':
 C_SIGNAL='@t6g_mb_lib.t6g(sch_1):pvdd11_s3_p0_vos2';
NODE_NAME     PU23 1
 '@T6G_MB_LIB.T6G(SCH_1):PAGE183_I13@PURE_QUANTA.ISL99390FRZTR5935(CHIPS)':
 'VOS': CDS_PINID='VOS';
NODE_NAME     PR138 1
 '@T6G_MB_LIB.T6G(SCH_1):PAGE183_I91@PURE_QUANTA.Q_RES(CHIPS)':
 'A': CDS_PINID='A';
NET_NAME
'PVDD11_S3_P1'
 '@T6G_MB_LIB.T6G(SCH_1):PVDD11_S3_P1':
 C_SIGNAL='@t6g_mb_lib.t6g(sch_1):pvdd11_s3_p1',
 CDS_GLOBAL_NET='TRUE';
NODE_NAME     U26 BJ18
 '@T6G_MB_LIB.T6G(SCH_1):PAGE57_I45@PURE_QUANTA.GENOA_SP5(CHIPS)':
 'VDD_11_S3_BJ18': CDS_PINID='VDD_11_S3_BJ18';
NODE_NAME     U26 BJ23
 '@T6G_MB_LIB.T6G(SCH_1):PAGE57_I45@PURE_QUANTA.GENOA_SP5(CHIPS)':
 'VDD_11_S3_BJ23': CDS_PINID='VDD_11_S3_BJ23';
NODE_NAME     U26 BJ25
 '@T6G_MB_LIB.T6G(SCH_1):PAGE57_I45@PURE_QUANTA.GENOA_SP5(CHIPS)':
 'VDD_11_S3_BJ25': CDS_PINID='VDD_11_S3_BJ25';
NODE_NAME     U26 BJ27
 '@T6G_MB_LIB.T6G(SCH_1):PAGE57_I45@PURE_QUANTA.GENOA_SP5(CHIPS)':
 'VDD_11_S3_BJ27': CDS_PINID='VDD_11_S3_BJ27';
NODE_NAME     U26 BK22
 '@T6G_MB_LIB.T6G(SCH_1):PAGE57_I45@PURE_QUANTA.GENOA_SP5(CHIPS)':
 'VDD_11_S3_BK22': CDS_PINID='VDD_11_S3_BK22';
NODE_NAME     U26 BK24
 '@T6G_MB_LIB.T6G(SCH_1):PAGE57_I45@PURE_QUANTA.GENOA_SP5(CHIPS)':
 'VDD_11_S3_BK24': CDS_PINID='VDD_11_S3_BK24';
NODE_NAME     U26 BK26
 '@T6G_MB_LIB.T6G(SCH_1):PAGE57_I45@PURE_QUANTA.GENOA_SP5(CHIPS)':
 'VDD_11_S3_BK26': CDS_PINID='VDD_11_S3_BK26';
NODE_NAME     U26 BK28
 '@T6G_MB_LIB.T6G(SCH_1):PAGE57_I45@PURE_QUANTA.GENOA_SP5(CHIPS)':
 'VDD_11_S3_BK28': CDS_PINID='VDD_11_S3_BK28';
NODE_NAME     U26 BK49
 '@T6G_MB_LIB.T6G(SCH_1):PAGE57_I45@PURE_QUANTA.GENOA_SP5(CHIPS)':
 'VDD_11_S3_BK49': CDS_PINID='VDD_11_S3_BK49';
NODE_NAME     U26 BL23
 '@T6G_MB_LIB.T6G(SCH_1):PAGE57_I45@PURE_QUANTA.GENOA_SP5(CHIPS)':
 'VDD_11_S3_BL23': CDS_PINID='VDD_11_S3_BL23';
NODE_NAME     U26 BL25
 '@T6G_MB_LIB.T6G(SCH_1):PAGE57_I45@PURE_QUANTA.GENOA_SP5(CHIPS)':
 'VDD_11_S3_BL25': CDS_PINID='VDD_11_S3_BL25';
NODE_NAME     U26 BL27
 '@T6G_MB_LIB.T6G(SCH_1):PAGE57_I45@PURE_QUANTA.GENOA_SP5(CHIPS)':
 'VDD_11_S3_BL27': CDS_PINID='VDD_11_S3_BL27';
NODE_NAME     U26 BL48
 '@T6G_MB_LIB.T6G(SCH_1):PAGE57_I45@PURE_QUANTA.GENOA_SP5(CHIPS)':
 'VDD_11_S3_BL48': CDS_PINID='VDD_11_S3_BL48';
NODE_NAME     U26 BM12
 '@T6G_MB_LIB.T6G(SCH_1):PAGE57_I45@PURE_QUANTA.GENOA_SP5(CHIPS)':
 'VDD_11_S3_BM12': CDS_PINID='VDD_11_S3_BM12';
NODE_NAME     U26 BM19
 '@T6G_MB_LIB.T6G(SCH_1):PAGE57_I45@PURE_QUANTA.GENOA_SP5(CHIPS)':
 'VDD_11_S3_BM19': CDS_PINID='VDD_11_S3_BM19';
NODE_NAME     U26 BM22
 '@T6G_MB_LIB.T6G(SCH_1):PAGE57_I45@PURE_QUANTA.GENOA_SP5(CHIPS)':
 'VDD_11_S3_BM22': CDS_PINID='VDD_11_S3_BM22';
NODE_NAME     U26 BM24
 '@T6G_MB_LIB.T6G(SCH_1):PAGE57_I45@PURE_QUANTA.GENOA_SP5(CHIPS)':
 'VDD_11_S3_BM24': CDS_PINID='VDD_11_S3_BM24';
NODE_NAME     U26 BM26
 '@T6G_MB_LIB.T6G(SCH_1):PAGE57_I45@PURE_QUANTA.GENOA_SP5(CHIPS)':
 'VDD_11_S3_BM26': CDS_PINID='VDD_11_S3_BM26';
NODE_NAME     U26 BM28
 '@T6G_MB_LIB.T6G(SCH_1):PAGE57_I45@PURE_QUANTA.GENOA_SP5(CHIPS)':
 'VDD_11_S3_BM28': CDS_PINID='VDD_11_S3_BM28';
NODE_NAME     U26 BM30
 '@T6G_MB_LIB.T6G(SCH_1):PAGE57_I45@PURE_QUANTA.GENOA_SP5(CHIPS)':
 'VDD_11_S3_BM30': CDS_PINID='VDD_11_S3_BM30';
NODE_NAME     U26 BM32
 '@T6G_MB_LIB.T6G(SCH_1):PAGE57_I45@PURE_QUANTA.GENOA_SP5(CHIPS)':
 'VDD_11_S3_BM32': CDS_PINID='VDD_11_S3_BM32';
NODE_NAME     U26 BM34
 '@T6G_MB_LIB.T6G(SCH_1):PAGE57_I45@PURE_QUANTA.GENOA_SP5(CHIPS)':
 'VDD_11_S3_BM34': CDS_PINID='VDD_11_S3_BM34';
NODE_NAME     U26 BM36
 '@T6G_MB_LIB.T6G(SCH_1):PAGE57_I45@PURE_QUANTA.GENOA_SP5(CHIPS)':
 'VDD_11_S3_BM36': CDS_PINID='VDD_11_S3_BM36';
NODE_NAME     U26 BM39
 '@T6G_MB_LIB.T6G(SCH_1):PAGE57_I45@PURE_QUANTA.GENOA_SP5(CHIPS)':
 'VDD_11_S3_BM39': CDS_PINID='VDD_11_S3_BM39';
NODE_NAME     U26 BM41
 '@T6G_MB_LIB.T6G(SCH_1):PAGE57_I45@PURE_QUANTA.GENOA_SP5(CHIPS)':
 'VDD_11_S3_BM41': CDS_PINID='VDD_11_S3_BM41';
NODE_NAME     U26 BM43
 '@T6G_MB_LIB.T6G(SCH_1):PAGE57_I45@PURE_QUANTA.GENOA_SP5(CHIPS)':
 'VDD_11_S3_BM43': CDS_PINID='VDD_11_S3_BM43';
NODE_NAME     U26 BM45
 '@T6G_MB_LIB.T6G(SCH_1):PAGE57_I45@PURE_QUANTA.GENOA_SP5(CHIPS)':
 'VDD_11_S3_BM45': CDS_PINID='VDD_11_S3_BM45';
NODE_NAME     U26 BM47
 '@T6G_MB_LIB.T6G(SCH_1):PAGE57_I45@PURE_QUANTA.GENOA_SP5(CHIPS)':
 'VDD_11_S3_BM47': CDS_PINID='VDD_11_S3_BM47';
NODE_NAME     U26 BM49
 '@T6G_MB_LIB.T6G(SCH_1):PAGE57_I45@PURE_QUANTA.GENOA_SP5(CHIPS)':
 'VDD_11_S3_BM49': CDS_PINID='VDD_11_S3_BM49';
NODE_NAME     U26 BN25
 '@T6G_MB_LIB.T6G(SCH_1):PAGE57_I45@PURE_QUANTA.GENOA_SP5(CHIPS)':
 'VDD_11_S3_BN25': CDS_PINID='VDD_11_S3_BN25';
NODE_NAME     U26 BN29
 '@T6G_MB_LIB.T6G(SCH_1):PAGE57_I45@PURE_QUANTA.GENOA_SP5(CHIPS)':
 'VDD_11_S3_BN29': CDS_PINID='VDD_11_S3_BN29';
NODE_NAME     U26 BN33
 '@T6G_MB_LIB.T6G(SCH_1):PAGE57_I45@PURE_QUANTA.GENOA_SP5(CHIPS)':
 'VDD_11_S3_BN33': CDS_PINID='VDD_11_S3_BN33';
NODE_NAME     U26 BN40
 '@T6G_MB_LIB.T6G(SCH_1):PAGE57_I45@PURE_QUANTA.GENOA_SP5(CHIPS)':
 'VDD_11_S3_BN40': CDS_PINID='VDD_11_S3_BN40';
NODE_NAME     U26 BN44
 '@T6G_MB_LIB.T6G(SCH_1):PAGE57_I45@PURE_QUANTA.GENOA_SP5(CHIPS)':
 'VDD_11_S3_BN44': CDS_PINID='VDD_11_S3_BN44';
NODE_NAME     U26 BN48
 '@T6G_MB_LIB.T6G(SCH_1):PAGE57_I45@PURE_QUANTA.GENOA_SP5(CHIPS)':
 'VDD_11_S3_BN48': CDS_PINID='VDD_11_S3_BN48';
NODE_NAME     U26 BP22
 '@T6G_MB_LIB.T6G(SCH_1):PAGE57_I45@PURE_QUANTA.GENOA_SP5(CHIPS)':
 'VDD_11_S3_BP22': CDS_PINID='VDD_11_S3_BP22';
NODE_NAME     U26 BR4
 '@T6G_MB_LIB.T6G(SCH_1):PAGE57_I45@PURE_QUANTA.GENOA_SP5(CHIPS)':
 'VDD_11_S3_BR4': CDS_PINID='VDD_11_S3_BR4';
NODE_NAME     U26 BR11
 '@T6G_MB_LIB.T6G(SCH_1):PAGE57_I45@PURE_QUANTA.GENOA_SP5(CHIPS)':
 'VDD_11_S3_BR11': CDS_PINID='VDD_11_S3_BR11';
NODE_NAME     U26 BR18
 '@T6G_MB_LIB.T6G(SCH_1):PAGE57_I45@PURE_QUANTA.GENOA_SP5(CHIPS)':
 'VDD_11_S3_BR18': CDS_PINID='VDD_11_S3_BR18';
NODE_NAME     U26 BV5
 '@T6G_MB_LIB.T6G(SCH_1):PAGE57_I45@PURE_QUANTA.GENOA_SP5(CHIPS)':
 'VDD_11_S3_BV5': CDS_PINID='VDD_11_S3_BV5';
NODE_NAME     U26 BV12
 '@T6G_MB_LIB.T6G(SCH_1):PAGE57_I45@PURE_QUANTA.GENOA_SP5(CHIPS)':
 'VDD_11_S3_BV12': CDS_PINID='VDD_11_S3_BV12';
NODE_NAME     U26 BV19
 '@T6G_MB_LIB.T6G(SCH_1):PAGE57_I45@PURE_QUANTA.GENOA_SP5(CHIPS)':
 'VDD_11_S3_BV19': CDS_PINID='VDD_11_S3_BV19';
NODE_NAME     U26 BV22
 '@T6G_MB_LIB.T6G(SCH_1):PAGE57_I45@PURE_QUANTA.GENOA_SP5(CHIPS)':
 'VDD_11_S3_BV22': CDS_PINID='VDD_11_S3_BV22';
NODE_NAME     U26 CA4
 '@T6G_MB_LIB.T6G(SCH_1):PAGE57_I45@PURE_QUANTA.GENOA_SP5(CHIPS)':
 'VDD_11_S3_CA4': CDS_PINID='VDD_11_S3_CA4';
NODE_NAME     U26 CA11
 '@T6G_MB_LIB.T6G(SCH_1):PAGE57_I45@PURE_QUANTA.GENOA_SP5(CHIPS)':
 'VDD_11_S3_CA11': CDS_PINID='VDD_11_S3_CA11';
NODE_NAME     U26 CA18
 '@T6G_MB_LIB.T6G(SCH_1):PAGE57_I45@PURE_QUANTA.GENOA_SP5(CHIPS)':
 'VDD_11_S3_CA18': CDS_PINID='VDD_11_S3_CA18';
NODE_NAME     U26 CB22
 '@T6G_MB_LIB.T6G(SCH_1):PAGE57_I45@PURE_QUANTA.GENOA_SP5(CHIPS)':
 'VDD_11_S3_CB22': CDS_PINID='VDD_11_S3_CB22';
NODE_NAME     U26 CD5
 '@T6G_MB_LIB.T6G(SCH_1):PAGE57_I45@PURE_QUANTA.GENOA_SP5(CHIPS)':
 'VDD_11_S3_CD5': CDS_PINID='VDD_11_S3_CD5';
NODE_NAME     U26 CD12
 '@T6G_MB_LIB.T6G(SCH_1):PAGE57_I45@PURE_QUANTA.GENOA_SP5(CHIPS)':
 'VDD_11_S3_CD12': CDS_PINID='VDD_11_S3_CD12';
NODE_NAME     U26 CD19
 '@T6G_MB_LIB.T6G(SCH_1):PAGE57_I45@PURE_QUANTA.GENOA_SP5(CHIPS)':
 'VDD_11_S3_CD19': CDS_PINID='VDD_11_S3_CD19';
NODE_NAME     U26 CF22
 '@T6G_MB_LIB.T6G(SCH_1):PAGE57_I45@PURE_QUANTA.GENOA_SP5(CHIPS)':
 'VDD_11_S3_CF22': CDS_PINID='VDD_11_S3_CF22';
NODE_NAME     U26 CG4
 '@T6G_MB_LIB.T6G(SCH_1):PAGE57_I45@PURE_QUANTA.GENOA_SP5(CHIPS)':
 'VDD_11_S3_CG4': CDS_PINID='VDD_11_S3_CG4';
NODE_NAME     U26 CG11
 '@T6G_MB_LIB.T6G(SCH_1):PAGE57_I45@PURE_QUANTA.GENOA_SP5(CHIPS)':
 'VDD_11_S3_CG11': CDS_PINID='VDD_11_S3_CG11';
NODE_NAME     U26 CG18
 '@T6G_MB_LIB.T6G(SCH_1):PAGE57_I45@PURE_QUANTA.GENOA_SP5(CHIPS)':
 'VDD_11_S3_CG18': CDS_PINID='VDD_11_S3_CG18';
NODE_NAME     U26 CJ22
 '@T6G_MB_LIB.T6G(SCH_1):PAGE57_I45@PURE_QUANTA.GENOA_SP5(CHIPS)':
 'VDD_11_S3_CJ22': CDS_PINID='VDD_11_S3_CJ22';
NODE_NAME     U26 CK5
 '@T6G_MB_LIB.T6G(SCH_1):PAGE57_I45@PURE_QUANTA.GENOA_SP5(CHIPS)':
 'VDD_11_S3_CK5': CDS_PINID='VDD_11_S3_CK5';
NODE_NAME     U26 CK12
 '@T6G_MB_LIB.T6G(SCH_1):PAGE57_I45@PURE_QUANTA.GENOA_SP5(CHIPS)':
 'VDD_11_S3_CK12': CDS_PINID='VDD_11_S3_CK12';
NODE_NAME     U26 CK19
 '@T6G_MB_LIB.T6G(SCH_1):PAGE57_I45@PURE_QUANTA.GENOA_SP5(CHIPS)':
 'VDD_11_S3_CK19': CDS_PINID='VDD_11_S3_CK19';
NODE_NAME     U26 CM22
 '@T6G_MB_LIB.T6G(SCH_1):PAGE57_I45@PURE_QUANTA.GENOA_SP5(CHIPS)':
 'VDD_11_S3_CM22': CDS_PINID='VDD_11_S3_CM22';
NODE_NAME     U26 CN4
 '@T6G_MB_LIB.T6G(SCH_1):PAGE57_I45@PURE_QUANTA.GENOA_SP5(CHIPS)':
 'VDD_11_S3_CN4': CDS_PINID='VDD_11_S3_CN4';
NODE_NAME     U26 CN11
 '@T6G_MB_LIB.T6G(SCH_1):PAGE57_I45@PURE_QUANTA.GENOA_SP5(CHIPS)':
 'VDD_11_S3_CN11': CDS_PINID='VDD_11_S3_CN11';
NODE_NAME     U26 CN18
 '@T6G_MB_LIB.T6G(SCH_1):PAGE57_I45@PURE_QUANTA.GENOA_SP5(CHIPS)':
 'VDD_11_S3_CN18': CDS_PINID='VDD_11_S3_CN18';
NODE_NAME     U26 CT5
 '@T6G_MB_LIB.T6G(SCH_1):PAGE57_I45@PURE_QUANTA.GENOA_SP5(CHIPS)':
 'VDD_11_S3_CT5': CDS_PINID='VDD_11_S3_CT5';
NODE_NAME     U26 CT12
 '@T6G_MB_LIB.T6G(SCH_1):PAGE57_I45@PURE_QUANTA.GENOA_SP5(CHIPS)':
 'VDD_11_S3_CT12': CDS_PINID='VDD_11_S3_CT12';
NODE_NAME     U26 CT19
 '@T6G_MB_LIB.T6G(SCH_1):PAGE57_I45@PURE_QUANTA.GENOA_SP5(CHIPS)':
 'VDD_11_S3_CT19': CDS_PINID='VDD_11_S3_CT19';
NODE_NAME     U26 CT22
 '@T6G_MB_LIB.T6G(SCH_1):PAGE57_I45@PURE_QUANTA.GENOA_SP5(CHIPS)':
 'VDD_11_S3_CT22': CDS_PINID='VDD_11_S3_CT22';
NODE_NAME     U26 CW4
 '@T6G_MB_LIB.T6G(SCH_1):PAGE57_I45@PURE_QUANTA.GENOA_SP5(CHIPS)':
 'VDD_11_S3_CW4': CDS_PINID='VDD_11_S3_CW4';
NODE_NAME     U26 CW11
 '@T6G_MB_LIB.T6G(SCH_1):PAGE57_I45@PURE_QUANTA.GENOA_SP5(CHIPS)':
 'VDD_11_S3_CW11': CDS_PINID='VDD_11_S3_CW11';
NODE_NAME     U26 CW18
 '@T6G_MB_LIB.T6G(SCH_1):PAGE57_I45@PURE_QUANTA.GENOA_SP5(CHIPS)':
 'VDD_11_S3_CW18': CDS_PINID='VDD_11_S3_CW18';
NODE_NAME     U26 CY22
 '@T6G_MB_LIB.T6G(SCH_1):PAGE57_I45@PURE_QUANTA.GENOA_SP5(CHIPS)':
 'VDD_11_S3_CY22': CDS_PINID='VDD_11_S3_CY22';
NODE_NAME     U26 DB5
 '@T6G_MB_LIB.T6G(SCH_1):PAGE57_I45@PURE_QUANTA.GENOA_SP5(CHIPS)':
 'VDD_11_S3_DB5': CDS_PINID='VDD_11_S3_DB5';
NODE_NAME     U26 DB12
 '@T6G_MB_LIB.T6G(SCH_1):PAGE57_I45@PURE_QUANTA.GENOA_SP5(CHIPS)':
 'VDD_11_S3_DB12': CDS_PINID='VDD_11_S3_DB12';
NODE_NAME     U26 DB19
 '@T6G_MB_LIB.T6G(SCH_1):PAGE57_I45@PURE_QUANTA.GENOA_SP5(CHIPS)':
 'VDD_11_S3_DB19': CDS_PINID='VDD_11_S3_DB19';
NODE_NAME     U26 DE4
 '@T6G_MB_LIB.T6G(SCH_1):PAGE57_I45@PURE_QUANTA.GENOA_SP5(CHIPS)':
 'VDD_11_S3_DE4': CDS_PINID='VDD_11_S3_DE4';
NODE_NAME     U26 DE11
 '@T6G_MB_LIB.T6G(SCH_1):PAGE57_I45@PURE_QUANTA.GENOA_SP5(CHIPS)':
 'VDD_11_S3_DE11': CDS_PINID='VDD_11_S3_DE11';
NODE_NAME     U26 DE18
 '@T6G_MB_LIB.T6G(SCH_1):PAGE57_I45@PURE_QUANTA.GENOA_SP5(CHIPS)':
 'VDD_11_S3_DE18': CDS_PINID='VDD_11_S3_DE18';
NODE_NAME     U26 DG5
 '@T6G_MB_LIB.T6G(SCH_1):PAGE57_I45@PURE_QUANTA.GENOA_SP5(CHIPS)':
 'VDD_11_S3_DG5': CDS_PINID='VDD_11_S3_DG5';
NODE_NAME     C2262 1
 '@T6G_MB_LIB.T6G(SCH_1):PAGE71_I1@PURE_QUANTA.Q_CAP(CHIPS)':
 'A': CDS_PINID='A';
NODE_NAME     C2261 1
 '@T6G_MB_LIB.T6G(SCH_1):PAGE71_I3@PURE_QUANTA.Q_CAP(CHIPS)':
 'A': CDS_PINID='A';
NODE_NAME     C2267 1
 '@T6G_MB_LIB.T6G(SCH_1):PAGE71_I11@PURE_QUANTA.Q_CAP(CHIPS)':
 'A': CDS_PINID='A';
NODE_NAME     C3902 1
 '@T6G_MB_LIB.T6G(SCH_1):PAGE71_I12@PURE_QUANTA.Q_CAP(CHIPS)':
 'A': CDS_PINID='A';
NODE_NAME     C2266 1
 '@T6G_MB_LIB.T6G(SCH_1):PAGE71_I13@PURE_QUANTA.Q_CAP(CHIPS)':
 'A': CDS_PINID='A';
NODE_NAME     C2271 1
 '@T6G_MB_LIB.T6G(SCH_1):PAGE71_I14@PURE_QUANTA.Q_CAP(CHIPS)':
 'A': CDS_PINID='A';
NODE_NAME     C3903 1
 '@T6G_MB_LIB.T6G(SCH_1):PAGE71_I15@PURE_QUANTA.Q_CAP(CHIPS)':
 'A': CDS_PINID='A';
NODE_NAME     C3904 1
 '@T6G_MB_LIB.T6G(SCH_1):PAGE71_I16@PURE_QUANTA.Q_CAP(CHIPS)':
 'A': CDS_PINID='A';
NODE_NAME     C3905 1
 '@T6G_MB_LIB.T6G(SCH_1):PAGE71_I18@PURE_QUANTA.Q_CAP(CHIPS)':
 'A': CDS_PINID='A';
NODE_NAME     C2275 1
 '@T6G_MB_LIB.T6G(SCH_1):PAGE71_I19@PURE_QUANTA.Q_CAP(CHIPS)':
 'A': CDS_PINID='A';
NODE_NAME     C2279 1
 '@T6G_MB_LIB.T6G(SCH_1):PAGE71_I20@PURE_QUANTA.Q_CAP(CHIPS)':
 'A': CDS_PINID='A';
NODE_NAME     C2282 1
 '@T6G_MB_LIB.T6G(SCH_1):PAGE71_I21@PURE_QUANTA.Q_CAP(CHIPS)':
 'A': CDS_PINID='A';
NODE_NAME     C2285 1
 '@T6G_MB_LIB.T6G(SCH_1):PAGE71_I24@PURE_QUANTA.Q_CAP(CHIPS)':
 'A': CDS_PINID='A';
NODE_NAME     C2287 1
 '@T6G_MB_LIB.T6G(SCH_1):PAGE71_I25@PURE_QUANTA.Q_CAP(CHIPS)':
 'A': CDS_PINID='A';
NODE_NAME     C2289 1
 '@T6G_MB_LIB.T6G(SCH_1):PAGE71_I26@PURE_QUANTA.Q_CAP(CHIPS)':
 'A': CDS_PINID='A';
NODE_NAME     C2291 1
 '@T6G_MB_LIB.T6G(SCH_1):PAGE71_I28@PURE_QUANTA.Q_CAP(CHIPS)':
 'A': CDS_PINID='A';
NODE_NAME     C3919 1
 '@T6G_MB_LIB.T6G(SCH_1):PAGE73_I77@PURE_QUANTA.Q_CAP(CHIPS)':
 'A': CDS_PINID='A';
NODE_NAME     C2483 1
 '@T6G_MB_LIB.T6G(SCH_1):PAGE73_I81@PURE_QUANTA.Q_CAP(CHIPS)':
 'A': CDS_PINID='A';
NODE_NAME     C3920 1
 '@T6G_MB_LIB.T6G(SCH_1):PAGE73_I84@PURE_QUANTA.Q_CAP(CHIPS)':
 'A': CDS_PINID='A';
NODE_NAME     C2488 1
 '@T6G_MB_LIB.T6G(SCH_1):PAGE73_I85@PURE_QUANTA.Q_CAP(CHIPS)':
 'A': CDS_PINID='A';
NODE_NAME     C2492 1
 '@T6G_MB_LIB.T6G(SCH_1):PAGE73_I86@PURE_QUANTA.Q_CAP(CHIPS)':
 'A': CDS_PINID='A';
NODE_NAME     C2482 1
 '@T6G_MB_LIB.T6G(SCH_1):PAGE73_I90@PURE_QUANTA.Q_CAP(CHIPS)':
 'A': CDS_PINID='A';
NODE_NAME     C2481 1
 '@T6G_MB_LIB.T6G(SCH_1):PAGE73_I92@PURE_QUANTA.Q_CAP(CHIPS)':
 'A': CDS_PINID='A';
NODE_NAME     C2480 1
 '@T6G_MB_LIB.T6G(SCH_1):PAGE73_I97@PURE_QUANTA.Q_CAP(CHIPS)':
 'A': CDS_PINID='A';
NODE_NAME     C2487 1
 '@T6G_MB_LIB.T6G(SCH_1):PAGE73_I99@PURE_QUANTA.Q_CAP(CHIPS)':
 'A': CDS_PINID='A';
NODE_NAME     C2486 1
 '@T6G_MB_LIB.T6G(SCH_1):PAGE73_I100@PURE_QUANTA.Q_CAP(CHIPS)':
 'A': CDS_PINID='A';
NODE_NAME     C2491 1
 '@T6G_MB_LIB.T6G(SCH_1):PAGE73_I101@PURE_QUANTA.Q_CAP(CHIPS)':
 'A': CDS_PINID='A';
NODE_NAME     C2490 1
 '@T6G_MB_LIB.T6G(SCH_1):PAGE73_I102@PURE_QUANTA.Q_CAP(CHIPS)':
 'A': CDS_PINID='A';
NODE_NAME     C2485 1
 '@T6G_MB_LIB.T6G(SCH_1):PAGE73_I103@PURE_QUANTA.Q_CAP(CHIPS)':
 'A': CDS_PINID='A';
NODE_NAME     C2489 1
 '@T6G_MB_LIB.T6G(SCH_1):PAGE73_I104@PURE_QUANTA.Q_CAP(CHIPS)':
 'A': CDS_PINID='A';
NODE_NAME     C2497 1
 '@T6G_MB_LIB.T6G(SCH_1):PAGE73_I105@PURE_QUANTA.Q_CAP(CHIPS)':
 'A': CDS_PINID='A';
NODE_NAME     C2502 1
 '@T6G_MB_LIB.T6G(SCH_1):PAGE73_I106@PURE_QUANTA.Q_CAP(CHIPS)':
 'A': CDS_PINID='A';
NODE_NAME     C2506 1
 '@T6G_MB_LIB.T6G(SCH_1):PAGE73_I107@PURE_QUANTA.Q_CAP(CHIPS)':
 'A': CDS_PINID='A';
NODE_NAME     C2115 1
 '@T6G_MB_LIB.T6G(SCH_1):PAGE73_I108@PURE_QUANTA.Q_CAP(CHIPS)':
 'A': CDS_PINID='A';
NODE_NAME     C2121 1
 '@T6G_MB_LIB.T6G(SCH_1):PAGE73_I109@PURE_QUANTA.Q_CAP(CHIPS)':
 'A': CDS_PINID='A';
NODE_NAME     C2496 1
 '@T6G_MB_LIB.T6G(SCH_1):PAGE73_I110@PURE_QUANTA.Q_CAP(CHIPS)':
 'A': CDS_PINID='A';
NODE_NAME     C2495 1
 '@T6G_MB_LIB.T6G(SCH_1):PAGE73_I111@PURE_QUANTA.Q_CAP(CHIPS)':
 'A': CDS_PINID='A';
NODE_NAME     C2501 1
 '@T6G_MB_LIB.T6G(SCH_1):PAGE73_I112@PURE_QUANTA.Q_CAP(CHIPS)':
 'A': CDS_PINID='A';
NODE_NAME     C2500 1
 '@T6G_MB_LIB.T6G(SCH_1):PAGE73_I113@PURE_QUANTA.Q_CAP(CHIPS)':
 'A': CDS_PINID='A';
NODE_NAME     C2494 1
 '@T6G_MB_LIB.T6G(SCH_1):PAGE73_I114@PURE_QUANTA.Q_CAP(CHIPS)':
 'A': CDS_PINID='A';
NODE_NAME     C2499 1
 '@T6G_MB_LIB.T6G(SCH_1):PAGE73_I116@PURE_QUANTA.Q_CAP(CHIPS)':
 'A': CDS_PINID='A';
NODE_NAME     C2505 1
 '@T6G_MB_LIB.T6G(SCH_1):PAGE73_I117@PURE_QUANTA.Q_CAP(CHIPS)':
 'A': CDS_PINID='A';
NODE_NAME     C2504 1
 '@T6G_MB_LIB.T6G(SCH_1):PAGE73_I118@PURE_QUANTA.Q_CAP(CHIPS)':
 'A': CDS_PINID='A';
NODE_NAME     C2113 1
 '@T6G_MB_LIB.T6G(SCH_1):PAGE73_I119@PURE_QUANTA.Q_CAP(CHIPS)':
 'A': CDS_PINID='A';
NODE_NAME     C2114 1
 '@T6G_MB_LIB.T6G(SCH_1):PAGE73_I120@PURE_QUANTA.Q_CAP(CHIPS)':
 'A': CDS_PINID='A';
NODE_NAME     C2120 1
 '@T6G_MB_LIB.T6G(SCH_1):PAGE73_I121@PURE_QUANTA.Q_CAP(CHIPS)':
 'A': CDS_PINID='A';
NODE_NAME     C2119 1
 '@T6G_MB_LIB.T6G(SCH_1):PAGE73_I122@PURE_QUANTA.Q_CAP(CHIPS)':
 'A': CDS_PINID='A';
NODE_NAME     C2503 1
 '@T6G_MB_LIB.T6G(SCH_1):PAGE73_I123@PURE_QUANTA.Q_CAP(CHIPS)':
 'A': CDS_PINID='A';
NODE_NAME     C2508 1
 '@T6G_MB_LIB.T6G(SCH_1):PAGE73_I124@PURE_QUANTA.Q_CAP(CHIPS)':
 'A': CDS_PINID='A';
NODE_NAME     C2118 1
 '@T6G_MB_LIB.T6G(SCH_1):PAGE73_I125@PURE_QUANTA.Q_CAP(CHIPS)':
 'A': CDS_PINID='A';
NODE_NAME     C3921 1
 '@T6G_MB_LIB.T6G(SCH_1):PAGE73_I155@PURE_QUANTA.Q_CAP(CHIPS)':
 'A': CDS_PINID='A';
NODE_NAME     C3922 1
 '@T6G_MB_LIB.T6G(SCH_1):PAGE73_I157@PURE_QUANTA.Q_CAP(CHIPS)':
 'A': CDS_PINID='A';
NODE_NAME     C2126 1
 '@T6G_MB_LIB.T6G(SCH_1):PAGE73_I159@PURE_QUANTA.Q_CAP(CHIPS)':
 'A': CDS_PINID='A';
NODE_NAME     C2125 1
 '@T6G_MB_LIB.T6G(SCH_1):PAGE73_I160@PURE_QUANTA.Q_CAP(CHIPS)':
 'A': CDS_PINID='A';
NODE_NAME     C2511 1
 '@T6G_MB_LIB.T6G(SCH_1):PAGE73_I161@PURE_QUANTA.Q_CAP(CHIPS)':
 'A': CDS_PINID='A';
NODE_NAME     C2510 1
 '@T6G_MB_LIB.T6G(SCH_1):PAGE73_I163@PURE_QUANTA.Q_CAP(CHIPS)':
 'A': CDS_PINID='A';
NODE_NAME     C2124 1
 '@T6G_MB_LIB.T6G(SCH_1):PAGE73_I164@PURE_QUANTA.Q_CAP(CHIPS)':
 'A': CDS_PINID='A';
NODE_NAME     C2128 1
 '@T6G_MB_LIB.T6G(SCH_1):PAGE73_I166@PURE_QUANTA.Q_CAP(CHIPS)':
 'A': CDS_PINID='A';
NODE_NAME     R359 1
 '@T6G_MB_LIB.T6G(SCH_1):PAGE138_I52@PURE_QUANTA.Q_RES(CHIPS)':
 'A': CDS_PINID='A';
NODE_NAME     PC528 1
 '@T6G_MB_LIB.T6G(SCH_1):PAGE200_I63@PURE_QUANTA.Q_CAPP(CHIPS)':
 'A': CDS_PINID='A';
NODE_NAME     PC527_2 1
 '@T6G_MB_LIB.T6G(SCH_1):PAGE200_I67@PURE_QUANTA.Q_CAP(CHIPS)':
 'A': CDS_PINID='A';
NODE_NAME     PC530 1
 '@T6G_MB_LIB.T6G(SCH_1):PAGE200_I69@PURE_QUANTA.Q_CAPP(CHIPS)':
 'A': CDS_PINID='A';
NODE_NAME     R5010 1
 '@T6G_MB_LIB.T6G(SCH_1):PAGE136_I151@PURE_QUANTA.Q_RES(CHIPS)':
 'A': CDS_PINID='A';
NODE_NAME     R5011 1
 '@T6G_MB_LIB.T6G(SCH_1):PAGE136_I152@PURE_QUANTA.Q_RES(CHIPS)':
 'A': CDS_PINID='A';
NODE_NAME     R5013 1
 '@T6G_MB_LIB.T6G(SCH_1):PAGE136_I154@PURE_QUANTA.Q_RES(CHIPS)':
 'A': CDS_PINID='A';
NODE_NAME     R5012 1
 '@T6G_MB_LIB.T6G(SCH_1):PAGE136_I156@PURE_QUANTA.Q_RES(CHIPS)':
 'A': CDS_PINID='A';
NODE_NAME     R5018 1
 '@T6G_MB_LIB.T6G(SCH_1):PAGE136_I163@PURE_QUANTA.Q_RES(CHIPS)':
 'A': CDS_PINID='A';
NODE_NAME     R5019 1
 '@T6G_MB_LIB.T6G(SCH_1):PAGE136_I164@PURE_QUANTA.Q_RES(CHIPS)':
 'A': CDS_PINID='A';
NODE_NAME     R5021 1
 '@T6G_MB_LIB.T6G(SCH_1):PAGE136_I166@PURE_QUANTA.Q_RES(CHIPS)':
 'A': CDS_PINID='A';
NODE_NAME     R5020 1
 '@T6G_MB_LIB.T6G(SCH_1):PAGE136_I167@PURE_QUANTA.Q_RES(CHIPS)':
 'A': CDS_PINID='A';
NODE_NAME     R362 1
 '@T6G_MB_LIB.T6G(SCH_1):PAGE138_I53@PURE_QUANTA.Q_RES(CHIPS)':
 'A': CDS_PINID='A';
NODE_NAME     R541 1
 '@T6G_MB_LIB.T6G(SCH_1):PAGE55_I365@PURE_QUANTA.Q_RES(CHIPS)':
 'A': CDS_PINID='A';
NODE_NAME     R542 1
 '@T6G_MB_LIB.T6G(SCH_1):PAGE55_I366@PURE_QUANTA.Q_RES(CHIPS)':
 'A': CDS_PINID='A';
NODE_NAME     R543 1
 '@T6G_MB_LIB.T6G(SCH_1):PAGE55_I367@PURE_QUANTA.Q_RES(CHIPS)':
 'A': CDS_PINID='A';
NODE_NAME     R563 1
 '@T6G_MB_LIB.T6G(SCH_1):PAGE55_I368@PURE_QUANTA.Q_RES(CHIPS)':
 'A': CDS_PINID='A';
NODE_NAME     PR229 1
 '@T6G_MB_LIB.T6G(SCH_1):PAGE199_I29@PURE_QUANTA.Q_RES(CHIPS)':
 'A': CDS_PINID='A';
NODE_NAME     PR333 2
 '@T6G_MB_LIB.T6G(SCH_1):PAGE200_I53@PURE_QUANTA.Q_RES(CHIPS)':
 'B': CDS_PINID='B';
NODE_NAME     PL55 2
 '@T6G_MB_LIB.T6G(SCH_1):PAGE200_I55@PURE_QUANTA.Q_INDUCTOR(CHIPS)':
 '2': CDS_PINID='\2\';
NODE_NAME     PC523_2 1
 '@T6G_MB_LIB.T6G(SCH_1):PAGE200_I56@PURE_QUANTA.Q_CAP(CHIPS)':
 'A': CDS_PINID='A';
NODE_NAME     PR332 2
 '@T6G_MB_LIB.T6G(SCH_1):PAGE200_I60@PURE_QUANTA.Q_RES(CHIPS)':
 'B': CDS_PINID='B';
NODE_NAME     PC525 1
 '@T6G_MB_LIB.T6G(SCH_1):PAGE200_I62@PURE_QUANTA.Q_CAPP(CHIPS)':
 'A': CDS_PINID='A';
NODE_NAME     PC802 1
 '@T6G_MB_LIB.T6G(SCH_1):PAGE200_I65@PURE_QUANTA.Q_CAPP(CHIPS)':
 'A': CDS_PINID='A';
NODE_NAME     PC531 1
 '@T6G_MB_LIB.T6G(SCH_1):PAGE200_I72@PURE_QUANTA.Q_CAPP(CHIPS)':
 'A': CDS_PINID='A';
NODE_NAME     PC532 1
 '@T6G_MB_LIB.T6G(SCH_1):PAGE200_I73@PURE_QUANTA.Q_CAPP(CHIPS)':
 'A': CDS_PINID='A';
NODE_NAME     PC803 1
 '@T6G_MB_LIB.T6G(SCH_1):PAGE200_I75@PURE_QUANTA.Q_CAPP(CHIPS)':
 'A': CDS_PINID='A';
NODE_NAME     PL54 2
 '@T6G_MB_LIB.T6G(SCH_1):PAGE200_I78@PURE_QUANTA.Q_INDUCTOR(CHIPS)':
 '2': CDS_PINID='\2\';
NODE_NAME     PC524 1
 '@T6G_MB_LIB.T6G(SCH_1):PAGE200_I82@PURE_QUANTA.Q_CAP(CHIPS)':
 'A': CDS_PINID='A';
NODE_NAME     PC526_1 1
 '@T6G_MB_LIB.T6G(SCH_1):PAGE200_I87@PURE_QUANTA.Q_CAP(CHIPS)':
 'A': CDS_PINID='A';
NODE_NAME     PC529_1 1
 '@T6G_MB_LIB.T6G(SCH_1):PAGE200_I88@PURE_QUANTA.Q_CAP(CHIPS)':
 'A': CDS_PINID='A';
NODE_NAME     PR395 1
 '@T6G_MB_LIB.T6G(SCH_1):PAGE200_I89@PURE_QUANTA.Q_RES(CHIPS)':
 'A': CDS_PINID='A';
NET_NAME
'PVDD11_S3_P1_ADDR_CFG'
 '@T6G_MB_LIB.T6G(SCH_1):PVDD11_S3_P1_ADDR_CFG':
 C_SIGNAL='@t6g_mb_lib.t6g(sch_1):pvdd11_s3_p1_addr_cfg';
NODE_NAME     PU54 34
 '@T6G_MB_LIB.T6G(SCH_1):PAGE199_I86@PURE_QUANTA.RAA229621GNPHA0(CHIPS)':
 'EN1||ADDR_CFG': CDS_PINID='\en1||addr_cfg\';
NODE_NAME     PR464 2
 '@T6G_MB_LIB.T6G(SCH_1):PAGE199_I89@PURE_QUANTA.Q_RES(CHIPS)':
 'B': CDS_PINID='B';
NET_NAME
'PVDD11_S3_P1_EN'
 '@T6G_MB_LIB.T6G(SCH_1):PVDD11_S3_P1_EN':
 C_SIGNAL='@t6g_mb_lib.t6g(sch_1):pvdd11_s3_p1_en';
NODE_NAME     R279 1
 '@T6G_MB_LIB.T6G(SCH_1):PAGE80_I58@PURE_QUANTA.Q_RES(CHIPS)':
 'A': CDS_PINID='A';
NODE_NAME     R8386 1
 '@T6G_MB_LIB.T6G(SCH_1):PAGE199_I42@PURE_QUANTA.Q_RES(CHIPS)':
 'A': CDS_PINID='A';
NET_NAME
'PVDD11_S3_P1_EN_R'
 '@T6G_MB_LIB.T6G(SCH_1):PVDD11_S3_P1_EN_R':
 C_SIGNAL='@t6g_mb_lib.t6g(sch_1):pvdd11_s3_p1_en_r';
NODE_NAME     R8386 2
 '@T6G_MB_LIB.T6G(SCH_1):PAGE199_I42@PURE_QUANTA.Q_RES(CHIPS)':
 'B': CDS_PINID='B';
NODE_NAME     C642 1
 '@T6G_MB_LIB.T6G(SCH_1):PAGE199_I44@PURE_QUANTA.Q_CAP(CHIPS)':
 'A': CDS_PINID='A';
NODE_NAME     PU54 13
 '@T6G_MB_LIB.T6G(SCH_1):PAGE199_I86@PURE_QUANTA.RAA229621GNPHA0(CHIPS)':
 'EN0': CDS_PINID='EN0';
NET_NAME
'PVDD11_S3_P1_IMON1'
 '@T6G_MB_LIB.T6G(SCH_1):PVDD11_S3_P1_IMON1':
 C_SIGNAL='@t6g_mb_lib.t6g(sch_1):pvdd11_s3_p1_imon1';
NODE_NAME     PU54 23
 '@T6G_MB_LIB.T6G(SCH_1):PAGE199_I86@PURE_QUANTA.RAA229621GNPHA0(CHIPS)':
 'CS7': CDS_PINID='CS7';
NODE_NAME     PU44 38
 '@T6G_MB_LIB.T6G(SCH_1):PAGE200_I22@PURE_QUANTA.ISL99390FRZTR5935(CHIPS)':
 'IOUT': CDS_PINID='IOUT';
NET_NAME
'PVDD11_S3_P1_IMON2'
 '@T6G_MB_LIB.T6G(SCH_1):PVDD11_S3_P1_IMON2':
 C_SIGNAL='@t6g_mb_lib.t6g(sch_1):pvdd11_s3_p1_imon2';
NODE_NAME     PU54 24
 '@T6G_MB_LIB.T6G(SCH_1):PAGE199_I86@PURE_QUANTA.RAA229621GNPHA0(CHIPS)':
 'CS6': CDS_PINID='CS6';
NODE_NAME     PU45 38
 '@T6G_MB_LIB.T6G(SCH_1):PAGE200_I92@PURE_QUANTA.ISL99390FRZTR5935(CHIPS)':
 'IOUT': CDS_PINID='IOUT';
NET_NAME
'PVDD11_S3_P1_LSET1'
 '@T6G_MB_LIB.T6G(SCH_1):PVDD11_S3_P1_LSET1':
 C_SIGNAL='@t6g_mb_lib.t6g(sch_1):pvdd11_s3_p1_lset1';
NODE_NAME     PR328 2
 '@T6G_MB_LIB.T6G(SCH_1):PAGE200_I37@PURE_QUANTA.Q_RES(CHIPS)':
 'B': CDS_PINID='B';
NODE_NAME     PU44 37
 '@T6G_MB_LIB.T6G(SCH_1):PAGE200_I22@PURE_QUANTA.ISL99390FRZTR5935(CHIPS)':
 'LSET': CDS_PINID='LSET';
NET_NAME
'PVDD11_S3_P1_LSET2'
 '@T6G_MB_LIB.T6G(SCH_1):PVDD11_S3_P1_LSET2':
 C_SIGNAL='@t6g_mb_lib.t6g(sch_1):pvdd11_s3_p1_lset2';
NODE_NAME     PR329 2
 '@T6G_MB_LIB.T6G(SCH_1):PAGE200_I12@PURE_QUANTA.Q_RES(CHIPS)':
 'B': CDS_PINID='B';
NODE_NAME     PU45 37
 '@T6G_MB_LIB.T6G(SCH_1):PAGE200_I92@PURE_QUANTA.ISL99390FRZTR5935(CHIPS)':
 'LSET': CDS_PINID='LSET';
NET_NAME
'PVDD11_S3_P1_OCP_N'
 '@T6G_MB_LIB.T6G(SCH_1):PVDD11_S3_P1_OCP_N':
 C_SIGNAL='@t6g_mb_lib.t6g(sch_1):pvdd11_s3_p1_ocp_n';
NODE_NAME     R8010 1
 '@T6G_MB_LIB.T6G(SCH_1):PAGE199_I13@PURE_QUANTA.Q_RES(CHIPS)':
 'A': CDS_PINID='A';
NODE_NAME     R278 2
 '@T6G_MB_LIB.T6G(SCH_1):PAGE81_I113@PURE_QUANTA.Q_RES(CHIPS)':
 'B': CDS_PINID='B';
NET_NAME
'PVDD11_S3_P1_OCP_N_R'
 '@T6G_MB_LIB.T6G(SCH_1):PVDD11_S3_P1_OCP_N_R':
 C_SIGNAL='@t6g_mb_lib.t6g(sch_1):pvdd11_s3_p1_ocp_n_r';
NODE_NAME     R8010 2
 '@T6G_MB_LIB.T6G(SCH_1):PAGE199_I13@PURE_QUANTA.Q_RES(CHIPS)':
 'B': CDS_PINID='B';
NODE_NAME     R8011 2
 '@T6G_MB_LIB.T6G(SCH_1):PAGE199_I24@PURE_QUANTA.Q_RES(CHIPS)':
 'B': CDS_PINID='B';
NODE_NAME     PU54 33
 '@T6G_MB_LIB.T6G(SCH_1):PAGE199_I86@PURE_QUANTA.RAA229621GNPHA0(CHIPS)':
 'OCP_L': CDS_PINID='OCP_L';
NET_NAME
'PVDD11_S3_P1_PMALERT'
 '@T6G_MB_LIB.T6G(SCH_1):PVDD11_S3_P1_PMALERT':
 C_SIGNAL='@t6g_mb_lib.t6g(sch_1):pvdd11_s3_p1_pmalert';
NODE_NAME     R1190 1
 '@T6G_MB_LIB.T6G(SCH_1):PAGE82_I58@PURE_QUANTA.Q_RES(CHIPS)':
 'A': CDS_PINID='A';
NODE_NAME     U18 N1
 '@T6G_MB_LIB.T6G(SCH_1):PAGE81_I143@PURE_QUANTA.LCMXO3LF9400C5BG484C(CHIPS)':
 'PL17B': CDS_PINID='PL17B';
NODE_NAME     R8383 1
 '@T6G_MB_LIB.T6G(SCH_1):PAGE199_I38@PURE_QUANTA.Q_RES(CHIPS)':
 'A': CDS_PINID='A';
NODE_NAME     C5010 1
 '@T6G_MB_LIB.T6G(SCH_1):PAGE199_I88@PURE_QUANTA.Q_CAP(CHIPS)':
 'A': CDS_PINID='A';
NET_NAME
'PVDD11_S3_P1_PMALERT_R'
 '@T6G_MB_LIB.T6G(SCH_1):PVDD11_S3_P1_PMALERT_R':
 C_SIGNAL='@t6g_mb_lib.t6g(sch_1):pvdd11_s3_p1_pmalert_r';
NODE_NAME     R8383 2
 '@T6G_MB_LIB.T6G(SCH_1):PAGE199_I38@PURE_QUANTA.Q_RES(CHIPS)':
 'B': CDS_PINID='B';
NODE_NAME     PU54 11
 '@T6G_MB_LIB.T6G(SCH_1):PAGE199_I86@PURE_QUANTA.RAA229621GNPHA0(CHIPS)':
 'NPMALERT': CDS_PINID='NPMALERT';
NET_NAME
'PVDD11_S3_P1_PMSCL_R'
 '@T6G_MB_LIB.T6G(SCH_1):PVDD11_S3_P1_PMSCL_R':
 C_SIGNAL='@t6g_mb_lib.t6g(sch_1):pvdd11_s3_p1_pmscl_r';
NODE_NAME     R8381 2
 '@T6G_MB_LIB.T6G(SCH_1):PAGE199_I40@PURE_QUANTA.Q_RES(CHIPS)':
 'B': CDS_PINID='B';
NODE_NAME     PU54 10
 '@T6G_MB_LIB.T6G(SCH_1):PAGE199_I86@PURE_QUANTA.RAA229621GNPHA0(CHIPS)':
 'PMSCL': CDS_PINID='PMSCL';
NET_NAME
'PVDD11_S3_P1_PMSDA_R'
 '@T6G_MB_LIB.T6G(SCH_1):PVDD11_S3_P1_PMSDA_R':
 C_SIGNAL='@t6g_mb_lib.t6g(sch_1):pvdd11_s3_p1_pmsda_r';
NODE_NAME     R8382 2
 '@T6G_MB_LIB.T6G(SCH_1):PAGE199_I39@PURE_QUANTA.Q_RES(CHIPS)':
 'B': CDS_PINID='B';
NODE_NAME     PU54 9
 '@T6G_MB_LIB.T6G(SCH_1):PAGE199_I86@PURE_QUANTA.RAA229621GNPHA0(CHIPS)':
 'PMSDA': CDS_PINID='PMSDA';
NET_NAME
'PVDD11_S3_P1_PVCC'
 '@T6G_MB_LIB.T6G(SCH_1):PVDD11_S3_P1_PVCC':
 C_SIGNAL='@t6g_mb_lib.t6g(sch_1):pvdd11_s3_p1_pvcc',
 CDS_GLOBAL_NET='TRUE';
NODE_NAME     PC507_11P1_1 1
 '@T6G_MB_LIB.T6G(SCH_1):PAGE200_I43@PURE_QUANTA.Q_CAP(CHIPS)':
 'A': CDS_PINID='A';
NODE_NAME     PR387 1
 '@T6G_MB_LIB.T6G(SCH_1):PAGE200_I3@PURE_QUANTA.Q_RES(CHIPS)':
 'A': CDS_PINID='A';
NODE_NAME     PR327 1
 '@T6G_MB_LIB.T6G(SCH_1):PAGE200_I14@PURE_QUANTA.Q_RES(CHIPS)':
 'A': CDS_PINID='A';
NODE_NAME     PC508_11P1_2 1
 '@T6G_MB_LIB.T6G(SCH_1):PAGE200_I17@PURE_QUANTA.Q_CAP(CHIPS)':
 'A': CDS_PINID='A';
NODE_NAME     PU44 4
 '@T6G_MB_LIB.T6G(SCH_1):PAGE200_I22@PURE_QUANTA.ISL99390FRZTR5935(CHIPS)':
 'PVCC': CDS_PINID='PVCC';
NODE_NAME     PR326 1
 '@T6G_MB_LIB.T6G(SCH_1):PAGE200_I40@PURE_QUANTA.Q_RES(CHIPS)':
 'A': CDS_PINID='A';
NODE_NAME     PR394 1
 '@T6G_MB_LIB.T6G(SCH_1):PAGE200_I41@PURE_QUANTA.Q_RES(CHIPS)':
 'A': CDS_PINID='A';
NODE_NAME     PU45 4
 '@T6G_MB_LIB.T6G(SCH_1):PAGE200_I92@PURE_QUANTA.ISL99390FRZTR5935(CHIPS)':
 'PVCC': CDS_PINID='PVCC';
NET_NAME
'PVDD11_S3_P1_PWM1'
 '@T6G_MB_LIB.T6G(SCH_1):PVDD11_S3_P1_PWM1':
 C_SIGNAL='@t6g_mb_lib.t6g(sch_1):pvdd11_s3_p1_pwm1';
NODE_NAME     PU54 8
 '@T6G_MB_LIB.T6G(SCH_1):PAGE199_I86@PURE_QUANTA.RAA229621GNPHA0(CHIPS)':
 'PWM7': CDS_PINID='PWM7';
NODE_NAME     PU44 34
 '@T6G_MB_LIB.T6G(SCH_1):PAGE200_I22@PURE_QUANTA.ISL99390FRZTR5935(CHIPS)':
 'PWM': CDS_PINID='PWM';
NET_NAME
'PVDD11_S3_P1_PWM2'
 '@T6G_MB_LIB.T6G(SCH_1):PVDD11_S3_P1_PWM2':
 C_SIGNAL='@t6g_mb_lib.t6g(sch_1):pvdd11_s3_p1_pwm2';
NODE_NAME     PU54 7
 '@T6G_MB_LIB.T6G(SCH_1):PAGE199_I86@PURE_QUANTA.RAA229621GNPHA0(CHIPS)':
 'PWM6': CDS_PINID='PWM6';
NODE_NAME     PU45 34
 '@T6G_MB_LIB.T6G(SCH_1):PAGE200_I92@PURE_QUANTA.ISL99390FRZTR5935(CHIPS)':
 'PWM': CDS_PINID='PWM';
NET_NAME
'PVDD11_S3_P1_RESET_N'
 '@T6G_MB_LIB.T6G(SCH_1):PVDD11_S3_P1_RESET_N':
 C_SIGNAL='@t6g_mb_lib.t6g(sch_1):pvdd11_s3_p1_reset_n';
NODE_NAME     PR392 2
 '@T6G_MB_LIB.T6G(SCH_1):PAGE199_I66@PURE_QUANTA.Q_RES(CHIPS)':
 'B': CDS_PINID='B';
NODE_NAME     U18 H16
 '@T6G_MB_LIB.T6G(SCH_1):PAGE80_I217@PURE_QUANTA.LCMXO3LF9400C5BG484C(CHIPS)':
 'PR10D': CDS_PINID='PR10D';
NET_NAME
'PVDD11_S3_P1_RESET_N_R'
 '@T6G_MB_LIB.T6G(SCH_1):PVDD11_S3_P1_RESET_N_R':
 C_SIGNAL='@t6g_mb_lib.t6g(sch_1):pvdd11_s3_p1_reset_n_r';
NODE_NAME     PR390 1
 '@T6G_MB_LIB.T6G(SCH_1):PAGE199_I56@PURE_QUANTA.Q_RES(CHIPS)':
 'A': CDS_PINID='A';
NODE_NAME     PR392 1
 '@T6G_MB_LIB.T6G(SCH_1):PAGE199_I66@PURE_QUANTA.Q_RES(CHIPS)':
 'A': CDS_PINID='A';
NODE_NAME     PR391 1
 '@T6G_MB_LIB.T6G(SCH_1):PAGE199_I67@PURE_QUANTA.Q_RES(CHIPS)':
 'A': CDS_PINID='A';
NODE_NAME     PU54 14
 '@T6G_MB_LIB.T6G(SCH_1):PAGE199_I86@PURE_QUANTA.RAA229621GNPHA0(CHIPS)':
 'RESET_L': CDS_PINID='RESET_L';
NET_NAME
'PVDD11_S3_P1_TEMP0'
 '@T6G_MB_LIB.T6G(SCH_1):PVDD11_S3_P1_TEMP0':
 C_SIGNAL='@t6g_mb_lib.t6g(sch_1):pvdd11_s3_p1_temp0';
NODE_NAME     PC643 1
 '@T6G_MB_LIB.T6G(SCH_1):PAGE199_I49@PURE_QUANTA.Q_CAP(CHIPS)':
 'A': CDS_PINID='A';
NODE_NAME     PU54 36
 '@T6G_MB_LIB.T6G(SCH_1):PAGE199_I86@PURE_QUANTA.RAA229621GNPHA0(CHIPS)':
 'TEMP0': CDS_PINID='TEMP0';
NODE_NAME     PU44 36
 '@T6G_MB_LIB.T6G(SCH_1):PAGE200_I22@PURE_QUANTA.ISL99390FRZTR5935(CHIPS)':
 'TOUT_FLT': CDS_PINID='TOUT_FLT';
NODE_NAME     PU45 36
 '@T6G_MB_LIB.T6G(SCH_1):PAGE200_I92@PURE_QUANTA.ISL99390FRZTR5935(CHIPS)':
 'TOUT_FLT': CDS_PINID='TOUT_FLT';
NET_NAME
'PVDD11_S3_P1_TEMP1'
 '@T6G_MB_LIB.T6G(SCH_1):PVDD11_S3_P1_TEMP1':
 C_SIGNAL='@t6g_mb_lib.t6g(sch_1):pvdd11_s3_p1_temp1';
NODE_NAME     PR415 1
 '@T6G_MB_LIB.T6G(SCH_1):PAGE199_I51@PURE_QUANTA.Q_RES(CHIPS)':
 'A': CDS_PINID='A';
NODE_NAME     PU54 35
 '@T6G_MB_LIB.T6G(SCH_1):PAGE199_I86@PURE_QUANTA.RAA229621GNPHA0(CHIPS)':
 'TEMP1': CDS_PINID='TEMP1';
NET_NAME
'PVDD11_S3_P1_VCC'
 '@T6G_MB_LIB.T6G(SCH_1):PVDD11_S3_P1_VCC':
 C_SIGNAL='@t6g_mb_lib.t6g(sch_1):pvdd11_s3_p1_vcc';
NODE_NAME     PC95 1
 '@T6G_MB_LIB.T6G(SCH_1):PAGE199_I73@PURE_QUANTA.Q_CAP(CHIPS)':
 'A': CDS_PINID='A';
NODE_NAME     PC645 1
 '@T6G_MB_LIB.T6G(SCH_1):PAGE199_I81@PURE_QUANTA.Q_CAP(CHIPS)':
 'A': CDS_PINID='A';
NODE_NAME     PR393 1
 '@T6G_MB_LIB.T6G(SCH_1):PAGE199_I84@PURE_QUANTA.Q_RES(CHIPS)':
 'A': CDS_PINID='A';
NODE_NAME     PU54 39
 '@T6G_MB_LIB.T6G(SCH_1):PAGE199_I86@PURE_QUANTA.RAA229621GNPHA0(CHIPS)':
 'VCC': CDS_PINID='VCC';
NET_NAME
'PVDD11_S3_P1_VCC1'
 '@T6G_MB_LIB.T6G(SCH_1):PVDD11_S3_P1_VCC1':
 C_SIGNAL='@t6g_mb_lib.t6g(sch_1):pvdd11_s3_p1_vcc1';
NODE_NAME     PU44 35
 '@T6G_MB_LIB.T6G(SCH_1):PAGE200_I22@PURE_QUANTA.ISL99390FRZTR5935(CHIPS)':
 'EN': CDS_PINID='EN';
NODE_NAME     PU44 3
 '@T6G_MB_LIB.T6G(SCH_1):PAGE200_I22@PURE_QUANTA.ISL99390FRZTR5935(CHIPS)':
 'VCC': CDS_PINID='VCC';
NODE_NAME     PC505 1
 '@T6G_MB_LIB.T6G(SCH_1):PAGE200_I36@PURE_QUANTA.Q_CAP(CHIPS)':
 'A': CDS_PINID='A';
NODE_NAME     PR326 2
 '@T6G_MB_LIB.T6G(SCH_1):PAGE200_I40@PURE_QUANTA.Q_RES(CHIPS)':
 'B': CDS_PINID='B';
NET_NAME
'PVDD11_S3_P1_VCC2'
 '@T6G_MB_LIB.T6G(SCH_1):PVDD11_S3_P1_VCC2':
 C_SIGNAL='@t6g_mb_lib.t6g(sch_1):pvdd11_s3_p1_vcc2';
NODE_NAME     PC506 1
 '@T6G_MB_LIB.T6G(SCH_1):PAGE200_I10@PURE_QUANTA.Q_CAP(CHIPS)':
 'A': CDS_PINID='A';
NODE_NAME     PR327 2
 '@T6G_MB_LIB.T6G(SCH_1):PAGE200_I14@PURE_QUANTA.Q_RES(CHIPS)':
 'B': CDS_PINID='B';
NODE_NAME     PU45 35
 '@T6G_MB_LIB.T6G(SCH_1):PAGE200_I92@PURE_QUANTA.ISL99390FRZTR5935(CHIPS)':
 'EN': CDS_PINID='EN';
NODE_NAME     PU45 3
 '@T6G_MB_LIB.T6G(SCH_1):PAGE200_I92@PURE_QUANTA.ISL99390FRZTR5935(CHIPS)':
 'VCC': CDS_PINID='VCC';
NET_NAME
'PVDD11_S3_P1_VCCS'
 '@T6G_MB_LIB.T6G(SCH_1):PVDD11_S3_P1_VCCS':
 C_SIGNAL='@t6g_mb_lib.t6g(sch_1):pvdd11_s3_p1_vccs';
NODE_NAME     PC503_1 1
 '@T6G_MB_LIB.T6G(SCH_1):PAGE200_I34@PURE_QUANTA.Q_CAP(CHIPS)':
 'A': CDS_PINID='A';
NODE_NAME     PC96 1
 '@T6G_MB_LIB.T6G(SCH_1):PAGE199_I72@PURE_QUANTA.Q_CAP(CHIPS)':
 'A': CDS_PINID='A';
NODE_NAME     PC644 1
 '@T6G_MB_LIB.T6G(SCH_1):PAGE199_I80@PURE_QUANTA.Q_CAP(CHIPS)':
 'A': CDS_PINID='A';
NODE_NAME     PU54 40
 '@T6G_MB_LIB.T6G(SCH_1):PAGE199_I86@PURE_QUANTA.RAA229621GNPHA0(CHIPS)':
 'VCCS': CDS_PINID='VCCS';
NODE_NAME     PC504_2 1
 '@T6G_MB_LIB.T6G(SCH_1):PAGE200_I8@PURE_QUANTA.Q_CAP(CHIPS)':
 'A': CDS_PINID='A';
NODE_NAME     PU44 39
 '@T6G_MB_LIB.T6G(SCH_1):PAGE200_I22@PURE_QUANTA.ISL99390FRZTR5935(CHIPS)':
 'REFIN': CDS_PINID='REFIN';
NODE_NAME     PU45 39
 '@T6G_MB_LIB.T6G(SCH_1):PAGE200_I92@PURE_QUANTA.ISL99390FRZTR5935(CHIPS)':
 'REFIN': CDS_PINID='REFIN';
NET_NAME
'PVDD11_S3_P1_VDDIO'
 '@T6G_MB_LIB.T6G(SCH_1):PVDD11_S3_P1_VDDIO':
 C_SIGNAL='@t6g_mb_lib.t6g(sch_1):pvdd11_s3_p1_vddio';
NODE_NAME     R8146 2
 '@T6G_MB_LIB.T6G(SCH_1):PAGE199_I9@PURE_QUANTA.Q_RES(CHIPS)':
 'B': CDS_PINID='B';
NODE_NAME     PU54 15
 '@T6G_MB_LIB.T6G(SCH_1):PAGE199_I86@PURE_QUANTA.RAA229621GNPHA0(CHIPS)':
 'VDDIO': CDS_PINID='VDDIO';
NET_NAME
'PVDD11_S3_P1_VINSEN'
 '@T6G_MB_LIB.T6G(SCH_1):PVDD11_S3_P1_VINSEN':
 C_SIGNAL='@t6g_mb_lib.t6g(sch_1):pvdd11_s3_p1_vinsen';
NODE_NAME     PR604 1
 '@T6G_MB_LIB.T6G(SCH_1):PAGE199_I17@PURE_QUANTA.Q_RES(CHIPS)':
 'A': CDS_PINID='A';
NODE_NAME     PR388 2
 '@T6G_MB_LIB.T6G(SCH_1):PAGE199_I18@PURE_QUANTA.Q_RES(CHIPS)':
 'B': CDS_PINID='B';
NODE_NAME     PC8 1
 '@T6G_MB_LIB.T6G(SCH_1):PAGE199_I20@PURE_QUANTA.Q_CAP(CHIPS)':
 'A': CDS_PINID='A';
NODE_NAME     PU54 38
 '@T6G_MB_LIB.T6G(SCH_1):PAGE199_I86@PURE_QUANTA.RAA229621GNPHA0(CHIPS)':
 'VINSEN': CDS_PINID='VINSEN';
NET_NAME
'PVDD11_S3_P1_VMON'
 '@T6G_MB_LIB.T6G(SCH_1):PVDD11_S3_P1_VMON':
 C_SIGNAL='@t6g_mb_lib.t6g(sch_1):pvdd11_s3_p1_vmon';
NODE_NAME     PR376 2
 '@T6G_MB_LIB.T6G(SCH_1):PAGE199_I2@PURE_QUANTA.Q_RES(CHIPS)':
 'B': CDS_PINID='B';
NODE_NAME     PC638 1
 '@T6G_MB_LIB.T6G(SCH_1):PAGE199_I4@PURE_QUANTA.Q_CAP(CHIPS)':
 'A': CDS_PINID='A';
NODE_NAME     PR6 1
 '@T6G_MB_LIB.T6G(SCH_1):PAGE199_I6@PURE_QUANTA.Q_RES(CHIPS)':
 'A': CDS_PINID='A';
NODE_NAME     PU54 37
 '@T6G_MB_LIB.T6G(SCH_1):PAGE199_I86@PURE_QUANTA.RAA229621GNPHA0(CHIPS)':
 'VMON||IINSEN': CDS_PINID='\vmon||iinsen\';
NET_NAME
'PVDD11_S3_P1_VOS1'
 '@T6G_MB_LIB.T6G(SCH_1):PVDD11_S3_P1_VOS1':
 C_SIGNAL='@t6g_mb_lib.t6g(sch_1):pvdd11_s3_p1_vos1';
NODE_NAME     PU44 1
 '@T6G_MB_LIB.T6G(SCH_1):PAGE200_I22@PURE_QUANTA.ISL99390FRZTR5935(CHIPS)':
 'VOS': CDS_PINID='VOS';
NODE_NAME     PR332 1
 '@T6G_MB_LIB.T6G(SCH_1):PAGE200_I60@PURE_QUANTA.Q_RES(CHIPS)':
 'A': CDS_PINID='A';
NET_NAME
'PVDD11_S3_P1_VOS2'
 '@T6G_MB_LIB.T6G(SCH_1):PVDD11_S3_P1_VOS2':
 C_SIGNAL='@t6g_mb_lib.t6g(sch_1):pvdd11_s3_p1_vos2';
NODE_NAME     PR333 1
 '@T6G_MB_LIB.T6G(SCH_1):PAGE200_I53@PURE_QUANTA.Q_RES(CHIPS)':
 'A': CDS_PINID='A';
NODE_NAME     PU45 1
 '@T6G_MB_LIB.T6G(SCH_1):PAGE200_I92@PURE_QUANTA.ISL99390FRZTR5935(CHIPS)':
 'VOS': CDS_PINID='VOS';
NET_NAME
'PVDD18_S5_P0'
 '@T6G_MB_LIB.T6G(SCH_1):PVDD18_S5_P0':
 C_SIGNAL='@t6g_mb_lib.t6g(sch_1):pvdd18_s5_p0',
 CDS_GLOBAL_NET='TRUE';
NODE_NAME     R403 1
 '@T6G_MB_LIB.T6G(SCH_1):PAGE27_I294@PURE_QUANTA.Q_RES(CHIPS)':
 'A': CDS_PINID='A';
NODE_NAME     R402 1
 '@T6G_MB_LIB.T6G(SCH_1):PAGE27_I296@PURE_QUANTA.Q_RES(CHIPS)':
 'A': CDS_PINID='A';
NODE_NAME     R401 1
 '@T6G_MB_LIB.T6G(SCH_1):PAGE27_I300@PURE_QUANTA.Q_RES(CHIPS)':
 'A': CDS_PINID='A';
NODE_NAME     R400 1
 '@T6G_MB_LIB.T6G(SCH_1):PAGE27_I301@PURE_QUANTA.Q_RES(CHIPS)':
 'A': CDS_PINID='A';
NODE_NAME     R399 1
 '@T6G_MB_LIB.T6G(SCH_1):PAGE27_I304@PURE_QUANTA.Q_RES(CHIPS)':
 'A': CDS_PINID='A';
NODE_NAME     R398 1
 '@T6G_MB_LIB.T6G(SCH_1):PAGE27_I305@PURE_QUANTA.Q_RES(CHIPS)':
 'A': CDS_PINID='A';
NODE_NAME     R412 2
 '@T6G_MB_LIB.T6G(SCH_1):PAGE27_I377@PURE_QUANTA.Q_RES(CHIPS)':
 'B': CDS_PINID='B';
NODE_NAME     R418 2
 '@T6G_MB_LIB.T6G(SCH_1):PAGE27_I378@PURE_QUANTA.Q_RES(CHIPS)':
 'B': CDS_PINID='B';
NODE_NAME     R417 2
 '@T6G_MB_LIB.T6G(SCH_1):PAGE27_I379@PURE_QUANTA.Q_RES(CHIPS)':
 'B': CDS_PINID='B';
NODE_NAME     R408 2
 '@T6G_MB_LIB.T6G(SCH_1):PAGE27_I380@PURE_QUANTA.Q_RES(CHIPS)':
 'B': CDS_PINID='B';
NODE_NAME     R409 2
 '@T6G_MB_LIB.T6G(SCH_1):PAGE27_I381@PURE_QUANTA.Q_RES(CHIPS)':
 'B': CDS_PINID='B';
NODE_NAME     R410 2
 '@T6G_MB_LIB.T6G(SCH_1):PAGE27_I382@PURE_QUANTA.Q_RES(CHIPS)':
 'B': CDS_PINID='B';
NODE_NAME     R411 2
 '@T6G_MB_LIB.T6G(SCH_1):PAGE27_I383@PURE_QUANTA.Q_RES(CHIPS)':
 'B': CDS_PINID='B';
NODE_NAME     R413 2
 '@T6G_MB_LIB.T6G(SCH_1):PAGE27_I384@PURE_QUANTA.Q_RES(CHIPS)':
 'B': CDS_PINID='B';
NODE_NAME     R414 2
 '@T6G_MB_LIB.T6G(SCH_1):PAGE27_I385@PURE_QUANTA.Q_RES(CHIPS)':
 'B': CDS_PINID='B';
NODE_NAME     R415 2
 '@T6G_MB_LIB.T6G(SCH_1):PAGE27_I386@PURE_QUANTA.Q_RES(CHIPS)':
 'B': CDS_PINID='B';
NODE_NAME     R416 2
 '@T6G_MB_LIB.T6G(SCH_1):PAGE27_I387@PURE_QUANTA.Q_RES(CHIPS)':
 'B': CDS_PINID='B';
NODE_NAME     R392 1
 '@T6G_MB_LIB.T6G(SCH_1):PAGE27_I395@PURE_QUANTA.Q_RES(CHIPS)':
 'A': CDS_PINID='A';
NODE_NAME     R457 1
 '@T6G_MB_LIB.T6G(SCH_1):PAGE29_I282@PURE_QUANTA.Q_RES(CHIPS)':
 'A': CDS_PINID='A';
NODE_NAME     R455 1
 '@T6G_MB_LIB.T6G(SCH_1):PAGE29_I284@PURE_QUANTA.Q_RES(CHIPS)':
 'A': CDS_PINID='A';
NODE_NAME     R454 1
 '@T6G_MB_LIB.T6G(SCH_1):PAGE29_I383@PURE_QUANTA.Q_RES(CHIPS)':
 'A': CDS_PINID='A';
NODE_NAME     U25 AR52
 '@T6G_MB_LIB.T6G(SCH_1):PAGE30_I28@PURE_QUANTA.GENOA_SP5(CHIPS)':
 'VDD_18_S5_AR52': CDS_PINID='VDD_18_S5_AR52';
NODE_NAME     U25 AR54
 '@T6G_MB_LIB.T6G(SCH_1):PAGE30_I28@PURE_QUANTA.GENOA_SP5(CHIPS)':
 'VDD_18_S5_AR54': CDS_PINID='VDD_18_S5_AR54';
NODE_NAME     U25 AT51
 '@T6G_MB_LIB.T6G(SCH_1):PAGE30_I28@PURE_QUANTA.GENOA_SP5(CHIPS)':
 'VDD_18_S5_AT51': CDS_PINID='VDD_18_S5_AT51';
NODE_NAME     U25 AT53
 '@T6G_MB_LIB.T6G(SCH_1):PAGE30_I28@PURE_QUANTA.GENOA_SP5(CHIPS)':
 'VDD_18_S5_AT53': CDS_PINID='VDD_18_S5_AT53';
NODE_NAME     U25 AU50
 '@T6G_MB_LIB.T6G(SCH_1):PAGE30_I28@PURE_QUANTA.GENOA_SP5(CHIPS)':
 'VDD_18_S5_AU50': CDS_PINID='VDD_18_S5_AU50';
NODE_NAME     U25 AU52
 '@T6G_MB_LIB.T6G(SCH_1):PAGE30_I28@PURE_QUANTA.GENOA_SP5(CHIPS)':
 'VDD_18_S5_AU52': CDS_PINID='VDD_18_S5_AU52';
NODE_NAME     U25 AU54
 '@T6G_MB_LIB.T6G(SCH_1):PAGE30_I28@PURE_QUANTA.GENOA_SP5(CHIPS)':
 'VDD_18_S5_AU54': CDS_PINID='VDD_18_S5_AU54';
NODE_NAME     U25 AV49
 '@T6G_MB_LIB.T6G(SCH_1):PAGE30_I28@PURE_QUANTA.GENOA_SP5(CHIPS)':
 'VDD_18_S5_AV49': CDS_PINID='VDD_18_S5_AV49';
NODE_NAME     U25 AV51
 '@T6G_MB_LIB.T6G(SCH_1):PAGE30_I28@PURE_QUANTA.GENOA_SP5(CHIPS)':
 'VDD_18_S5_AV51': CDS_PINID='VDD_18_S5_AV51';
NODE_NAME     U25 AV53
 '@T6G_MB_LIB.T6G(SCH_1):PAGE30_I28@PURE_QUANTA.GENOA_SP5(CHIPS)':
 'VDD_18_S5_AV53': CDS_PINID='VDD_18_S5_AV53';
NODE_NAME     U25 AW50
 '@T6G_MB_LIB.T6G(SCH_1):PAGE30_I28@PURE_QUANTA.GENOA_SP5(CHIPS)':
 'VDD_18_S5_AW50': CDS_PINID='VDD_18_S5_AW50';
NODE_NAME     U25 AW52
 '@T6G_MB_LIB.T6G(SCH_1):PAGE30_I28@PURE_QUANTA.GENOA_SP5(CHIPS)':
 'VDD_18_S5_AW52': CDS_PINID='VDD_18_S5_AW52';
NODE_NAME     U25 AW54
 '@T6G_MB_LIB.T6G(SCH_1):PAGE30_I28@PURE_QUANTA.GENOA_SP5(CHIPS)':
 'VDD_18_S5_AW54': CDS_PINID='VDD_18_S5_AW54';
NODE_NAME     U25 AY51
 '@T6G_MB_LIB.T6G(SCH_1):PAGE30_I28@PURE_QUANTA.GENOA_SP5(CHIPS)':
 'VDD_18_S5_AY51': CDS_PINID='VDD_18_S5_AY51';
NODE_NAME     U25 AY53
 '@T6G_MB_LIB.T6G(SCH_1):PAGE30_I28@PURE_QUANTA.GENOA_SP5(CHIPS)':
 'VDD_18_S5_AY53': CDS_PINID='VDD_18_S5_AY53';
NODE_NAME     U25 BA50
 '@T6G_MB_LIB.T6G(SCH_1):PAGE30_I28@PURE_QUANTA.GENOA_SP5(CHIPS)':
 'VDD_18_S5_BA50': CDS_PINID='VDD_18_S5_BA50';
NODE_NAME     U25 BA52
 '@T6G_MB_LIB.T6G(SCH_1):PAGE30_I28@PURE_QUANTA.GENOA_SP5(CHIPS)':
 'VDD_18_S5_BA52': CDS_PINID='VDD_18_S5_BA52';
NODE_NAME     U25 BA54
 '@T6G_MB_LIB.T6G(SCH_1):PAGE30_I28@PURE_QUANTA.GENOA_SP5(CHIPS)':
 'VDD_18_S5_BA54': CDS_PINID='VDD_18_S5_BA54';
NODE_NAME     U25 BB51
 '@T6G_MB_LIB.T6G(SCH_1):PAGE30_I28@PURE_QUANTA.GENOA_SP5(CHIPS)':
 'VDD_18_S5_BB51': CDS_PINID='VDD_18_S5_BB51';
NODE_NAME     U25 BB53
 '@T6G_MB_LIB.T6G(SCH_1):PAGE30_I28@PURE_QUANTA.GENOA_SP5(CHIPS)':
 'VDD_18_S5_BB53': CDS_PINID='VDD_18_S5_BB53';
NODE_NAME     U25 BC52
 '@T6G_MB_LIB.T6G(SCH_1):PAGE30_I28@PURE_QUANTA.GENOA_SP5(CHIPS)':
 'VDD_18_S5_BC52': CDS_PINID='VDD_18_S5_BC52';
NODE_NAME     U25 BC54
 '@T6G_MB_LIB.T6G(SCH_1):PAGE30_I28@PURE_QUANTA.GENOA_SP5(CHIPS)':
 'VDD_18_S5_BC54': CDS_PINID='VDD_18_S5_BC54';
NODE_NAME     U25 BH27
 '@T6G_MB_LIB.T6G(SCH_1):PAGE30_I28@PURE_QUANTA.GENOA_SP5(CHIPS)':
 'VDDIO_AUDIO': CDS_PINID='VDDIO_AUDIO';
NODE_NAME     U27 1
 '@T6G_MB_LIB.T6G(SCH_1):PAGE34_I18@PURE_QUANTA.PCA9617ADP(CHIPS)':
 'VCCA': CDS_PINID='VCCA';
NODE_NAME     C42 1
 '@T6G_MB_LIB.T6G(SCH_1):PAGE34_I44@PURE_QUANTA.Q_CAP(CHIPS)':
 'A': CDS_PINID='A';
NODE_NAME     U101 5
 '@T6G_MB_LIB.T6G(SCH_1):PAGE34_I55@PURE_QUANTA.SN74LVC1G07DBVR(CHIPS)':
 'VCC': CDS_PINID='VCC';
NODE_NAME     C226 1
 '@T6G_MB_LIB.T6G(SCH_1):PAGE34_I59@PURE_QUANTA.Q_CAP(CHIPS)':
 'A': CDS_PINID='A';
NODE_NAME     R942 1
 '@T6G_MB_LIB.T6G(SCH_1):PAGE34_I60@PURE_QUANTA.Q_RES(CHIPS)':
 'A': CDS_PINID='A';
NODE_NAME     R495 1
 '@T6G_MB_LIB.T6G(SCH_1):PAGE34_I106@PURE_QUANTA.Q_RES(CHIPS)':
 'A': CDS_PINID='A';
NODE_NAME     R498 1
 '@T6G_MB_LIB.T6G(SCH_1):PAGE34_I107@PURE_QUANTA.Q_RES(CHIPS)':
 'A': CDS_PINID='A';
NODE_NAME     C2163 1
 '@T6G_MB_LIB.T6G(SCH_1):PAGE67_I131@PURE_QUANTA.Q_CAP(CHIPS)':
 'A': CDS_PINID='A';
NODE_NAME     C2164 1
 '@T6G_MB_LIB.T6G(SCH_1):PAGE67_I133@PURE_QUANTA.Q_CAP(CHIPS)':
 'A': CDS_PINID='A';
NODE_NAME     C3897 1
 '@T6G_MB_LIB.T6G(SCH_1):PAGE67_I134@PURE_QUANTA.Q_CAP(CHIPS)':
 'A': CDS_PINID='A';
NODE_NAME     C2514 1
 '@T6G_MB_LIB.T6G(SCH_1):PAGE70_I1@PURE_QUANTA.Q_CAP(CHIPS)':
 'A': CDS_PINID='A';
NODE_NAME     C2513 1
 '@T6G_MB_LIB.T6G(SCH_1):PAGE70_I3@PURE_QUANTA.Q_CAP(CHIPS)':
 'A': CDS_PINID='A';
NODE_NAME     C2517 1
 '@T6G_MB_LIB.T6G(SCH_1):PAGE70_I8@PURE_QUANTA.Q_CAP(CHIPS)':
 'A': CDS_PINID='A';
NODE_NAME     C2516 1
 '@T6G_MB_LIB.T6G(SCH_1):PAGE70_I9@PURE_QUANTA.Q_CAP(CHIPS)':
 'A': CDS_PINID='A';
NODE_NAME     C2518 1
 '@T6G_MB_LIB.T6G(SCH_1):PAGE70_I10@PURE_QUANTA.Q_CAP(CHIPS)':
 'A': CDS_PINID='A';
NODE_NAME     C2520 1
 '@T6G_MB_LIB.T6G(SCH_1):PAGE70_I11@PURE_QUANTA.Q_CAP(CHIPS)':
 'A': CDS_PINID='A';
NODE_NAME     C2521 1
 '@T6G_MB_LIB.T6G(SCH_1):PAGE70_I12@PURE_QUANTA.Q_CAP(CHIPS)':
 'A': CDS_PINID='A';
NODE_NAME     C2522 1
 '@T6G_MB_LIB.T6G(SCH_1):PAGE70_I13@PURE_QUANTA.Q_CAP(CHIPS)':
 'A': CDS_PINID='A';
NODE_NAME     C2523 1
 '@T6G_MB_LIB.T6G(SCH_1):PAGE70_I14@PURE_QUANTA.Q_CAP(CHIPS)':
 'A': CDS_PINID='A';
NODE_NAME     C2524 1
 '@T6G_MB_LIB.T6G(SCH_1):PAGE70_I15@PURE_QUANTA.Q_CAP(CHIPS)':
 'A': CDS_PINID='A';
NODE_NAME     C2525 1
 '@T6G_MB_LIB.T6G(SCH_1):PAGE70_I16@PURE_QUANTA.Q_CAP(CHIPS)':
 'A': CDS_PINID='A';
NODE_NAME     C2526 1
 '@T6G_MB_LIB.T6G(SCH_1):PAGE70_I18@PURE_QUANTA.Q_CAP(CHIPS)':
 'A': CDS_PINID='A';
NODE_NAME     R729 1
 '@T6G_MB_LIB.T6G(SCH_1):PAGE75_I41@PURE_QUANTA.Q_RES(CHIPS)':
 'A': CDS_PINID='A';
NODE_NAME     R737 1
 '@T6G_MB_LIB.T6G(SCH_1):PAGE75_I43@PURE_QUANTA.Q_RES(CHIPS)':
 'A': CDS_PINID='A';
NODE_NAME     R740 1
 '@T6G_MB_LIB.T6G(SCH_1):PAGE75_I44@PURE_QUANTA.Q_RES(CHIPS)':
 'A': CDS_PINID='A';
NODE_NAME     R739 1
 '@T6G_MB_LIB.T6G(SCH_1):PAGE75_I45@PURE_QUANTA.Q_RES(CHIPS)':
 'A': CDS_PINID='A';
NODE_NAME     R742 1
 '@T6G_MB_LIB.T6G(SCH_1):PAGE75_I46@PURE_QUANTA.Q_RES(CHIPS)':
 'A': CDS_PINID='A';
NODE_NAME     C1102 1
 '@T6G_MB_LIB.T6G(SCH_1):PAGE76_I53@PURE_QUANTA.Q_CAP(CHIPS)':
 'A': CDS_PINID='A';
NODE_NAME     U53 1
 '@T6G_MB_LIB.T6G(SCH_1):PAGE76_I63@PURE_QUANTA.SN74AVC4T774PWR(CHIPS)':
 'DIR1': CDS_PINID='DIR1';
NODE_NAME     U53 2
 '@T6G_MB_LIB.T6G(SCH_1):PAGE76_I63@PURE_QUANTA.SN74AVC4T774PWR(CHIPS)':
 'DIR2': CDS_PINID='DIR2';
NODE_NAME     U53 7
 '@T6G_MB_LIB.T6G(SCH_1):PAGE76_I63@PURE_QUANTA.SN74AVC4T774PWR(CHIPS)':
 'DIR3': CDS_PINID='DIR3';
NODE_NAME     U53 8
 '@T6G_MB_LIB.T6G(SCH_1):PAGE76_I63@PURE_QUANTA.SN74AVC4T774PWR(CHIPS)':
 'DIR4': CDS_PINID='DIR4';
NODE_NAME     U53 16
 '@T6G_MB_LIB.T6G(SCH_1):PAGE76_I63@PURE_QUANTA.SN74AVC4T774PWR(CHIPS)':
 'VCCA': CDS_PINID='VCCA';
NODE_NAME     C1103 1
 '@T6G_MB_LIB.T6G(SCH_1):PAGE76_I65@PURE_QUANTA.Q_CAP(CHIPS)':
 'A': CDS_PINID='A';
NODE_NAME     U54 1
 '@T6G_MB_LIB.T6G(SCH_1):PAGE76_I67@PURE_QUANTA.PI4ULS3V304AZMAEX(CHIPS)':
 'VCCA': CDS_PINID='VCCA';
NODE_NAME     R811 1
 '@T6G_MB_LIB.T6G(SCH_1):PAGE76_I106@PURE_QUANTA.Q_RES(CHIPS)':
 'A': CDS_PINID='A';
NODE_NAME     R659 1
 '@T6G_MB_LIB.T6G(SCH_1):PAGE76_I107@PURE_QUANTA.Q_RES(CHIPS)':
 'A': CDS_PINID='A';
NODE_NAME     R601 1
 '@T6G_MB_LIB.T6G(SCH_1):PAGE76_I108@PURE_QUANTA.Q_RES(CHIPS)':
 'A': CDS_PINID='A';
NODE_NAME     R139 2
 '@T6G_MB_LIB.T6G(SCH_1):PAGE138_I30@PURE_QUANTA.Q_RES(CHIPS)':
 'B': CDS_PINID='B';
NODE_NAME     R370 1
 '@T6G_MB_LIB.T6G(SCH_1):PAGE138_I60@PURE_QUANTA.Q_RES(CHIPS)':
 'A': CDS_PINID='A';
NODE_NAME     R1419 1
 '@T6G_MB_LIB.T6G(SCH_1):PAGE141_I91@PURE_QUANTA.Q_RES(CHIPS)':
 'A': CDS_PINID='A';
NODE_NAME     U116 1
 '@T6G_MB_LIB.T6G(SCH_1):PAGE141_I117@PURE_QUANTA.SN74AVC4T774PWR(CHIPS)':
 'DIR1': CDS_PINID='DIR1';
NODE_NAME     U116 7
 '@T6G_MB_LIB.T6G(SCH_1):PAGE141_I117@PURE_QUANTA.SN74AVC4T774PWR(CHIPS)':
 'DIR3': CDS_PINID='DIR3';
NODE_NAME     U116 16
 '@T6G_MB_LIB.T6G(SCH_1):PAGE141_I117@PURE_QUANTA.SN74AVC4T774PWR(CHIPS)':
 'VCCA': CDS_PINID='VCCA';
NODE_NAME     C1352 1
 '@T6G_MB_LIB.T6G(SCH_1):PAGE141_I137@PURE_QUANTA.Q_CAP(CHIPS)':
 'A': CDS_PINID='A';
NODE_NAME     R816 1
 '@T6G_MB_LIB.T6G(SCH_1):PAGE141_I196@PURE_QUANTA.Q_RES(CHIPS)':
 'A': CDS_PINID='A';
NODE_NAME     R815 1
 '@T6G_MB_LIB.T6G(SCH_1):PAGE141_I197@PURE_QUANTA.Q_RES(CHIPS)':
 'A': CDS_PINID='A';
NODE_NAME     R814 1
 '@T6G_MB_LIB.T6G(SCH_1):PAGE141_I198@PURE_QUANTA.Q_RES(CHIPS)':
 'A': CDS_PINID='A';
NODE_NAME     R813 1
 '@T6G_MB_LIB.T6G(SCH_1):PAGE141_I199@PURE_QUANTA.Q_RES(CHIPS)':
 'A': CDS_PINID='A';
NODE_NAME     U147 6
 '@T6G_MB_LIB.T6G(SCH_1):PAGE149_I1@PURE_QUANTA.SN74AVC2T245RSWR(CHIPS)':
 'VCCB': CDS_PINID='VCCB';
NODE_NAME     C1509 1
 '@T6G_MB_LIB.T6G(SCH_1):PAGE149_I10@PURE_QUANTA.Q_CAP(CHIPS)':
 'A': CDS_PINID='A';
NODE_NAME     C1508 1
 '@T6G_MB_LIB.T6G(SCH_1):PAGE149_I29@PURE_QUANTA.Q_CAP(CHIPS)':
 'A': CDS_PINID='A';
NODE_NAME     U149 1
 '@T6G_MB_LIB.T6G(SCH_1):PAGE149_I31@PURE_QUANTA.SN74AVC4T774PWR(CHIPS)':
 'DIR1': CDS_PINID='DIR1';
NODE_NAME     U149 2
 '@T6G_MB_LIB.T6G(SCH_1):PAGE149_I31@PURE_QUANTA.SN74AVC4T774PWR(CHIPS)':
 'DIR2': CDS_PINID='DIR2';
NODE_NAME     U149 7
 '@T6G_MB_LIB.T6G(SCH_1):PAGE149_I31@PURE_QUANTA.SN74AVC4T774PWR(CHIPS)':
 'DIR3': CDS_PINID='DIR3';
NODE_NAME     U149 8
 '@T6G_MB_LIB.T6G(SCH_1):PAGE149_I31@PURE_QUANTA.SN74AVC4T774PWR(CHIPS)':
 'DIR4': CDS_PINID='DIR4';
NODE_NAME     U149 16
 '@T6G_MB_LIB.T6G(SCH_1):PAGE149_I31@PURE_QUANTA.SN74AVC4T774PWR(CHIPS)':
 'VCCA': CDS_PINID='VCCA';
NODE_NAME     U149 15
 '@T6G_MB_LIB.T6G(SCH_1):PAGE149_I31@PURE_QUANTA.SN74AVC4T774PWR(CHIPS)':
 'VCCB': CDS_PINID='VCCB';
NODE_NAME     U148 15
 '@T6G_MB_LIB.T6G(SCH_1):PAGE149_I34@PURE_QUANTA.SN74AVC4T774PWR(CHIPS)':
 'VCCB': CDS_PINID='VCCB';
NODE_NAME     C1507 1
 '@T6G_MB_LIB.T6G(SCH_1):PAGE149_I41@PURE_QUANTA.Q_CAP(CHIPS)':
 'A': CDS_PINID='A';
NODE_NAME     C1504 1
 '@T6G_MB_LIB.T6G(SCH_1):PAGE149_I56@PURE_QUANTA.Q_CAP(CHIPS)':
 'A': CDS_PINID='A';
NODE_NAME     C1505 1
 '@T6G_MB_LIB.T6G(SCH_1):PAGE149_I74@PURE_QUANTA.Q_CAP(CHIPS)':
 'A': CDS_PINID='A';
NODE_NAME     U146 10
 '@T6G_MB_LIB.T6G(SCH_1):PAGE149_I76@PURE_QUANTA.SN74AVC2T245RSWR(CHIPS)':
 'DIR1': CDS_PINID='DIR1';
NODE_NAME     U146 7
 '@T6G_MB_LIB.T6G(SCH_1):PAGE149_I76@PURE_QUANTA.SN74AVC2T245RSWR(CHIPS)':
 'VCCA': CDS_PINID='VCCA';
NODE_NAME     U146 6
 '@T6G_MB_LIB.T6G(SCH_1):PAGE149_I76@PURE_QUANTA.SN74AVC2T245RSWR(CHIPS)':
 'VCCB': CDS_PINID='VCCB';
NODE_NAME     R617 1
 '@T6G_MB_LIB.T6G(SCH_1):PAGE149_I101@PURE_QUANTA.Q_RES(CHIPS)':
 'A': CDS_PINID='A';
NODE_NAME     R1624 1
 '@T6G_MB_LIB.T6G(SCH_1):PAGE149_I111@PURE_QUANTA.Q_RES(CHIPS)':
 'A': CDS_PINID='A';
NODE_NAME     R1626 1
 '@T6G_MB_LIB.T6G(SCH_1):PAGE149_I115@PURE_QUANTA.Q_RES(CHIPS)':
 'A': CDS_PINID='A';
NODE_NAME     R1627 1
 '@T6G_MB_LIB.T6G(SCH_1):PAGE149_I116@PURE_QUANTA.Q_RES(CHIPS)':
 'A': CDS_PINID='A';
NODE_NAME     R1628 1
 '@T6G_MB_LIB.T6G(SCH_1):PAGE149_I117@PURE_QUANTA.Q_RES(CHIPS)':
 'A': CDS_PINID='A';
NODE_NAME     R1630 1
 '@T6G_MB_LIB.T6G(SCH_1):PAGE149_I118@PURE_QUANTA.Q_RES(CHIPS)':
 'A': CDS_PINID='A';
NODE_NAME     J54 1
 '@T6G_MB_LIB.T6G(SCH_1):PAGE149_I142@PURE_QUANTA.SCONN20_HSU2101L00007H(CHIPS)':
 '1': CDS_PINID='\1\';
NODE_NAME     J54 19
 '@T6G_MB_LIB.T6G(SCH_1):PAGE149_I142@PURE_QUANTA.SCONN20_HSU2101L00007H(CHIPS)':
 '19': CDS_PINID='\19\';
NODE_NAME     R1621 1
 '@T6G_MB_LIB.T6G(SCH_1):PAGE149_I146@PURE_QUANTA.Q_RES(CHIPS)':
 'A': CDS_PINID='A';
NODE_NAME     U150 1
 '@T6G_MB_LIB.T6G(SCH_1):PAGE150_I8@PURE_QUANTA.SN74AVC4T774PWR(CHIPS)':
 'DIR1': CDS_PINID='DIR1';
NODE_NAME     U150 2
 '@T6G_MB_LIB.T6G(SCH_1):PAGE150_I8@PURE_QUANTA.SN74AVC4T774PWR(CHIPS)':
 'DIR2': CDS_PINID='DIR2';
NODE_NAME     U150 7
 '@T6G_MB_LIB.T6G(SCH_1):PAGE150_I8@PURE_QUANTA.SN74AVC4T774PWR(CHIPS)':
 'DIR3': CDS_PINID='DIR3';
NODE_NAME     U150 8
 '@T6G_MB_LIB.T6G(SCH_1):PAGE150_I8@PURE_QUANTA.SN74AVC4T774PWR(CHIPS)':
 'DIR4': CDS_PINID='DIR4';
NODE_NAME     U150 16
 '@T6G_MB_LIB.T6G(SCH_1):PAGE150_I8@PURE_QUANTA.SN74AVC4T774PWR(CHIPS)':
 'VCCA': CDS_PINID='VCCA';
NODE_NAME     U150 15
 '@T6G_MB_LIB.T6G(SCH_1):PAGE150_I8@PURE_QUANTA.SN74AVC4T774PWR(CHIPS)':
 'VCCB': CDS_PINID='VCCB';
NODE_NAME     C1516 1
 '@T6G_MB_LIB.T6G(SCH_1):PAGE150_I14@PURE_QUANTA.Q_CAP(CHIPS)':
 'A': CDS_PINID='A';
NODE_NAME     C1514 1
 '@T6G_MB_LIB.T6G(SCH_1):PAGE150_I19@PURE_QUANTA.Q_CAP(CHIPS)':
 'A': CDS_PINID='A';
NODE_NAME     U151 1
 '@T6G_MB_LIB.T6G(SCH_1):PAGE150_I28@PURE_QUANTA.SN74AVC4T774PWR(CHIPS)':
 'DIR1': CDS_PINID='DIR1';
NODE_NAME     U151 2
 '@T6G_MB_LIB.T6G(SCH_1):PAGE150_I28@PURE_QUANTA.SN74AVC4T774PWR(CHIPS)':
 'DIR2': CDS_PINID='DIR2';
NODE_NAME     U151 7
 '@T6G_MB_LIB.T6G(SCH_1):PAGE150_I28@PURE_QUANTA.SN74AVC4T774PWR(CHIPS)':
 'DIR3': CDS_PINID='DIR3';
NODE_NAME     U151 8
 '@T6G_MB_LIB.T6G(SCH_1):PAGE150_I28@PURE_QUANTA.SN74AVC4T774PWR(CHIPS)':
 'DIR4': CDS_PINID='DIR4';
NODE_NAME     U151 16
 '@T6G_MB_LIB.T6G(SCH_1):PAGE150_I28@PURE_QUANTA.SN74AVC4T774PWR(CHIPS)':
 'VCCA': CDS_PINID='VCCA';
NODE_NAME     C1515 1
 '@T6G_MB_LIB.T6G(SCH_1):PAGE150_I43@PURE_QUANTA.Q_CAP(CHIPS)':
 'A': CDS_PINID='A';
NODE_NAME     U152 10
 '@T6G_MB_LIB.T6G(SCH_1):PAGE150_I60@PURE_QUANTA.SN74AVC2T245RSWR(CHIPS)':
 'DIR1': CDS_PINID='DIR1';
NODE_NAME     U152 7
 '@T6G_MB_LIB.T6G(SCH_1):PAGE150_I60@PURE_QUANTA.SN74AVC2T245RSWR(CHIPS)':
 'VCCA': CDS_PINID='VCCA';
NODE_NAME     U152 6
 '@T6G_MB_LIB.T6G(SCH_1):PAGE150_I60@PURE_QUANTA.SN74AVC2T245RSWR(CHIPS)':
 'VCCB': CDS_PINID='VCCB';
NODE_NAME     C1518 1
 '@T6G_MB_LIB.T6G(SCH_1):PAGE150_I66@PURE_QUANTA.Q_CAP(CHIPS)':
 'A': CDS_PINID='A';
NODE_NAME     C1513 1
 '@T6G_MB_LIB.T6G(SCH_1):PAGE150_I69@PURE_QUANTA.Q_CAP(CHIPS)':
 'A': CDS_PINID='A';
NODE_NAME     U153 8
 '@T6G_MB_LIB.T6G(SCH_1):PAGE151_I1@PURE_QUANTA.SN74AUC2G66DCTR(CHIPS)':
 'VCC': CDS_PINID='VCC';
NODE_NAME     R1646 1
 '@T6G_MB_LIB.T6G(SCH_1):PAGE151_I10@PURE_QUANTA.Q_RES(CHIPS)':
 'A': CDS_PINID='A';
NODE_NAME     R1647 1
 '@T6G_MB_LIB.T6G(SCH_1):PAGE151_I11@PURE_QUANTA.Q_RES(CHIPS)':
 'A': CDS_PINID='A';
NODE_NAME     C1519 1
 '@T6G_MB_LIB.T6G(SCH_1):PAGE151_I15@PURE_QUANTA.Q_CAP(CHIPS)':
 'A': CDS_PINID='A';
NODE_NAME     U13 8
 '@T6G_MB_LIB.T6G(SCH_1):PAGE151_I17@PURE_QUANTA.SN74AUC2G66DCTR(CHIPS)':
 'VCC': CDS_PINID='VCC';
NODE_NAME     C1521 1
 '@T6G_MB_LIB.T6G(SCH_1):PAGE151_I22@PURE_QUANTA.Q_CAP(CHIPS)':
 'A': CDS_PINID='A';
NODE_NAME     U14 8
 '@T6G_MB_LIB.T6G(SCH_1):PAGE151_I23@PURE_QUANTA.SN74AUC2G66DCTR(CHIPS)':
 'VCC': CDS_PINID='VCC';
NODE_NAME     R1649 1
 '@T6G_MB_LIB.T6G(SCH_1):PAGE151_I25@PURE_QUANTA.Q_RES(CHIPS)':
 'A': CDS_PINID='A';
NODE_NAME     R1650 1
 '@T6G_MB_LIB.T6G(SCH_1):PAGE151_I27@PURE_QUANTA.Q_RES(CHIPS)':
 'A': CDS_PINID='A';
NODE_NAME     U154 8
 '@T6G_MB_LIB.T6G(SCH_1):PAGE151_I31@PURE_QUANTA.SN74AUC2G66DCTR(CHIPS)':
 'VCC': CDS_PINID='VCC';
NODE_NAME     C1522 1
 '@T6G_MB_LIB.T6G(SCH_1):PAGE151_I36@PURE_QUANTA.Q_CAP(CHIPS)':
 'A': CDS_PINID='A';
NODE_NAME     C1523 1
 '@T6G_MB_LIB.T6G(SCH_1):PAGE151_I42@PURE_QUANTA.Q_CAP(CHIPS)':
 'A': CDS_PINID='A';
NODE_NAME     R1503 1
 '@T6G_MB_LIB.T6G(SCH_1):PAGE29_I396@PURE_QUANTA.Q_RES(CHIPS)':
 'A': CDS_PINID='A';
NODE_NAME     R1504 1
 '@T6G_MB_LIB.T6G(SCH_1):PAGE29_I397@PURE_QUANTA.Q_RES(CHIPS)':
 'A': CDS_PINID='A';
NODE_NAME     R1505 1
 '@T6G_MB_LIB.T6G(SCH_1):PAGE29_I398@PURE_QUANTA.Q_RES(CHIPS)':
 'A': CDS_PINID='A';
NODE_NAME     R1506 1
 '@T6G_MB_LIB.T6G(SCH_1):PAGE29_I399@PURE_QUANTA.Q_RES(CHIPS)':
 'A': CDS_PINID='A';
NODE_NAME     R458 1
 '@T6G_MB_LIB.T6G(SCH_1):PAGE29_I405@PURE_QUANTA.Q_RES(CHIPS)':
 'A': CDS_PINID='A';
NODE_NAME     R1532 1
 '@T6G_MB_LIB.T6G(SCH_1):PAGE76_I131@PURE_QUANTA.Q_RES(CHIPS)':
 'A': CDS_PINID='A';
NODE_NAME     R1531 1
 '@T6G_MB_LIB.T6G(SCH_1):PAGE76_I132@PURE_QUANTA.Q_RES(CHIPS)':
 'A': CDS_PINID='A';
NODE_NAME     R1530 1
 '@T6G_MB_LIB.T6G(SCH_1):PAGE76_I133@PURE_QUANTA.Q_RES(CHIPS)':
 'A': CDS_PINID='A';
NODE_NAME     R1529 1
 '@T6G_MB_LIB.T6G(SCH_1):PAGE76_I134@PURE_QUANTA.Q_RES(CHIPS)':
 'A': CDS_PINID='A';
NODE_NAME     R8317 1
 '@T6G_MB_LIB.T6G(SCH_1):PAGE168_I42@PURE_QUANTA.Q_RES(CHIPS)':
 'A': CDS_PINID='A';
NODE_NAME     PR128 2
 '@T6G_MB_LIB.T6G(SCH_1):PAGE182_I68@PURE_QUANTA.Q_RES(CHIPS)':
 'B': CDS_PINID='B';
NODE_NAME     R1567 1
 '@T6G_MB_LIB.T6G(SCH_1):PAGE76_I150@PURE_QUANTA.Q_RES(CHIPS)':
 'A': CDS_PINID='A';
NODE_NAME     R367 1
 '@T6G_MB_LIB.T6G(SCH_1):PAGE138_I57@PURE_QUANTA.Q_RES(CHIPS)':
 'A': CDS_PINID='A';
NODE_NAME     C612 1
 '@T6G_MB_LIB.T6G(SCH_1):PAGE137_I8@PURE_QUANTA.Q_CAP(CHIPS)':
 'A': CDS_PINID='A';
NODE_NAME     R368 1
 '@T6G_MB_LIB.T6G(SCH_1):PAGE137_I44@PURE_QUANTA.Q_RES(CHIPS)':
 'A': CDS_PINID='A';
NODE_NAME     R406 1
 '@T6G_MB_LIB.T6G(SCH_1):PAGE137_I46@PURE_QUANTA.Q_RES(CHIPS)':
 'A': CDS_PINID='A';
NODE_NAME     R443 2
 '@T6G_MB_LIB.T6G(SCH_1):PAGE28_I53@PURE_QUANTA.Q_RES(CHIPS)':
 'B': CDS_PINID='B';
NODE_NAME     PR284 1
 '@T6G_MB_LIB.T6G(SCH_1):PAGE168_I10@PURE_QUANTA.Q_RES(CHIPS)':
 'A': CDS_PINID='A';
NODE_NAME     PC466 1
 '@T6G_MB_LIB.T6G(SCH_1):PAGE168_I52@PURE_QUANTA.Q_CAP(CHIPS)':
 'A': CDS_PINID='A';
NODE_NAME     R8313 1
 '@T6G_MB_LIB.T6G(SCH_1):PAGE168_I54@PURE_QUANTA.Q_RES(CHIPS)':
 'A': CDS_PINID='A';
NODE_NAME     R8287 1
 '@T6G_MB_LIB.T6G(SCH_1):PAGE168_I69@PURE_QUANTA.Q_RES(CHIPS)':
 'A': CDS_PINID='A';
NODE_NAME     R8289 1
 '@T6G_MB_LIB.T6G(SCH_1):PAGE168_I70@PURE_QUANTA.Q_RES(CHIPS)':
 'A': CDS_PINID='A';
NODE_NAME     R8293 1
 '@T6G_MB_LIB.T6G(SCH_1):PAGE168_I71@PURE_QUANTA.Q_RES(CHIPS)':
 'A': CDS_PINID='A';
NODE_NAME     PU42 19
 '@T6G_MB_LIB.T6G(SCH_1):PAGE168_I135@PURE_QUANTA.RAA229620GNPHA0(CHIPS)':
 'VDDIO': CDS_PINID='VDDIO';
NODE_NAME     PR41 1
 '@T6G_MB_LIB.T6G(SCH_1):PAGE175_I40@PURE_QUANTA.Q_RES(CHIPS)':
 'A': CDS_PINID='A';
NODE_NAME     R8043 1
 '@T6G_MB_LIB.T6G(SCH_1):PAGE175_I42@PURE_QUANTA.Q_RES(CHIPS)':
 'A': CDS_PINID='A';
NODE_NAME     R8045 1
 '@T6G_MB_LIB.T6G(SCH_1):PAGE175_I43@PURE_QUANTA.Q_RES(CHIPS)':
 'A': CDS_PINID='A';
NODE_NAME     R8048 1
 '@T6G_MB_LIB.T6G(SCH_1):PAGE175_I44@PURE_QUANTA.Q_RES(CHIPS)':
 'A': CDS_PINID='A';
NODE_NAME     PC73 1
 '@T6G_MB_LIB.T6G(SCH_1):PAGE175_I63@PURE_QUANTA.Q_CAP(CHIPS)':
 'A': CDS_PINID='A';
NODE_NAME     R8070 1
 '@T6G_MB_LIB.T6G(SCH_1):PAGE175_I68@PURE_QUANTA.Q_RES(CHIPS)':
 'A': CDS_PINID='A';
NODE_NAME     R8075 1
 '@T6G_MB_LIB.T6G(SCH_1):PAGE175_I71@PURE_QUANTA.Q_RES(CHIPS)':
 'A': CDS_PINID='A';
NODE_NAME     PU12 19
 '@T6G_MB_LIB.T6G(SCH_1):PAGE175_I128@PURE_QUANTA.RAA229620GNPHA0(CHIPS)':
 'VDDIO': CDS_PINID='VDDIO';
NODE_NAME     R124 1
 '@T6G_MB_LIB.T6G(SCH_1):PAGE182_I25@PURE_QUANTA.Q_RES(CHIPS)':
 'A': CDS_PINID='A';
NODE_NAME     PL78 2
 '@T6G_MB_LIB.T6G(SCH_1):PAGE184_I36@PURE_QUANTA.Q_INDUCTOR(CHIPS)':
 '2': CDS_PINID='\2\';
NODE_NAME     PC114 1
 '@T6G_MB_LIB.T6G(SCH_1):PAGE184_I39@PURE_QUANTA.Q_CAP(CHIPS)':
 'A': CDS_PINID='A';
NODE_NAME     PC288 1
 '@T6G_MB_LIB.T6G(SCH_1):PAGE184_I40@PURE_QUANTA.Q_CAP(CHIPS)':
 'A': CDS_PINID='A';
NODE_NAME     PC260 1
 '@T6G_MB_LIB.T6G(SCH_1):PAGE184_I41@PURE_QUANTA.Q_CAP(CHIPS)':
 'A': CDS_PINID='A';
NODE_NAME     PR438 2
 '@T6G_MB_LIB.T6G(SCH_1):PAGE184_I42@PURE_QUANTA.Q_RES(CHIPS)':
 'B': CDS_PINID='B';
NODE_NAME     PC261 1
 '@T6G_MB_LIB.T6G(SCH_1):PAGE184_I46@PURE_QUANTA.Q_CAP(CHIPS)':
 'A': CDS_PINID='A';
NODE_NAME     PC115 1
 '@T6G_MB_LIB.T6G(SCH_1):PAGE184_I47@PURE_QUANTA.Q_CAPP(CHIPS)':
 'A': CDS_PINID='A';
NODE_NAME     PC215 1
 '@T6G_MB_LIB.T6G(SCH_1):PAGE184_I48@PURE_QUANTA.Q_CAP(CHIPS)':
 'A': CDS_PINID='A';
NODE_NAME     PR439 1
 '@T6G_MB_LIB.T6G(SCH_1):PAGE184_I51@PURE_QUANTA.Q_RES(CHIPS)':
 'A': CDS_PINID='A';
NODE_NAME     PC285 1
 '@T6G_MB_LIB.T6G(SCH_1):PAGE184_I54@PURE_QUANTA.Q_CAP(CHIPS)':
 'A': CDS_PINID='A';
NODE_NAME     R1351 2
 '@T6G_MB_LIB.T6G(SCH_1):PAGE82_I72@PURE_QUANTA.Q_RES(CHIPS)':
 'B': CDS_PINID='B';
NODE_NAME     R1288 2
 '@T6G_MB_LIB.T6G(SCH_1):PAGE82_I73@PURE_QUANTA.Q_RES(CHIPS)':
 'B': CDS_PINID='B';
NODE_NAME     R1287 2
 '@T6G_MB_LIB.T6G(SCH_1):PAGE82_I74@PURE_QUANTA.Q_RES(CHIPS)':
 'B': CDS_PINID='B';
NODE_NAME     R6122 1
 '@T6G_MB_LIB.T6G(SCH_1):PAGE83_I50@PURE_QUANTA.Q_RES(CHIPS)':
 'A': CDS_PINID='A';
NODE_NAME     R633 1
 '@T6G_MB_LIB.T6G(SCH_1):PAGE349_I17@PURE_QUANTA.Q_RES(CHIPS)':
 'A': CDS_PINID='A';
NODE_NAME     R632 1
 '@T6G_MB_LIB.T6G(SCH_1):PAGE349_I18@PURE_QUANTA.Q_RES(CHIPS)':
 'A': CDS_PINID='A';
NODE_NAME     R422 1
 '@T6G_MB_LIB.T6G(SCH_1):PAGE28_I29@PURE_QUANTA.Q_RES(CHIPS)':
 'A': CDS_PINID='A';
NODE_NAME     R424 1
 '@T6G_MB_LIB.T6G(SCH_1):PAGE28_I30@PURE_QUANTA.Q_RES(CHIPS)':
 'A': CDS_PINID='A';
NODE_NAME     R581 2
 '@T6G_MB_LIB.T6G(SCH_1):PAGE28_I34@PURE_QUANTA.Q_RES(CHIPS)':
 'B': CDS_PINID='B';
NODE_NAME     R276 2
 '@T6G_MB_LIB.T6G(SCH_1):PAGE28_I41@PURE_QUANTA.Q_RES(CHIPS)':
 'B': CDS_PINID='B';
NODE_NAME     R288 2
 '@T6G_MB_LIB.T6G(SCH_1):PAGE28_I42@PURE_QUANTA.Q_RES(CHIPS)':
 'B': CDS_PINID='B';
NODE_NAME     R444 2
 '@T6G_MB_LIB.T6G(SCH_1):PAGE28_I43@PURE_QUANTA.Q_RES(CHIPS)':
 'B': CDS_PINID='B';
NODE_NAME     R207 2
 '@T6G_MB_LIB.T6G(SCH_1):PAGE28_I44@PURE_QUANTA.Q_RES(CHIPS)':
 'B': CDS_PINID='B';
NODE_NAME     R452 2
 '@T6G_MB_LIB.T6G(SCH_1):PAGE28_I45@PURE_QUANTA.Q_RES(CHIPS)':
 'B': CDS_PINID='B';
NODE_NAME     R451 2
 '@T6G_MB_LIB.T6G(SCH_1):PAGE28_I46@PURE_QUANTA.Q_RES(CHIPS)':
 'B': CDS_PINID='B';
NODE_NAME     R450 2
 '@T6G_MB_LIB.T6G(SCH_1):PAGE28_I47@PURE_QUANTA.Q_RES(CHIPS)':
 'B': CDS_PINID='B';
NODE_NAME     R449 2
 '@T6G_MB_LIB.T6G(SCH_1):PAGE28_I48@PURE_QUANTA.Q_RES(CHIPS)':
 'B': CDS_PINID='B';
NODE_NAME     R448 2
 '@T6G_MB_LIB.T6G(SCH_1):PAGE28_I49@PURE_QUANTA.Q_RES(CHIPS)':
 'B': CDS_PINID='B';
NODE_NAME     R441 2
 '@T6G_MB_LIB.T6G(SCH_1):PAGE28_I55@PURE_QUANTA.Q_RES(CHIPS)':
 'B': CDS_PINID='B';
NODE_NAME     R442 2
 '@T6G_MB_LIB.T6G(SCH_1):PAGE28_I56@PURE_QUANTA.Q_RES(CHIPS)':
 'B': CDS_PINID='B';
NODE_NAME     R446 2
 '@T6G_MB_LIB.T6G(SCH_1):PAGE28_I64@PURE_QUANTA.Q_RES(CHIPS)':
 'B': CDS_PINID='B';
NODE_NAME     R447 2
 '@T6G_MB_LIB.T6G(SCH_1):PAGE28_I65@PURE_QUANTA.Q_RES(CHIPS)':
 'B': CDS_PINID='B';
NODE_NAME     R445 2
 '@T6G_MB_LIB.T6G(SCH_1):PAGE28_I66@PURE_QUANTA.Q_RES(CHIPS)':
 'B': CDS_PINID='B';
NODE_NAME     R938 2
 '@T6G_MB_LIB.T6G(SCH_1):PAGE28_I69@PURE_QUANTA.Q_RES(CHIPS)':
 'B': CDS_PINID='B';
NODE_NAME     R437 1
 '@T6G_MB_LIB.T6G(SCH_1):PAGE132_I18@PURE_QUANTA.Q_RES(CHIPS)':
 'A': CDS_PINID='A';
NODE_NAME     R743 1
 '@T6G_MB_LIB.T6G(SCH_1):PAGE75_I97@PURE_QUANTA.Q_RES(CHIPS)':
 'A': CDS_PINID='A';
NODE_NAME     R6106 1
 '@T6G_MB_LIB.T6G(SCH_1):PAGE144_I81@PURE_QUANTA.Q_RES(CHIPS)':
 'A': CDS_PINID='A';
NODE_NAME     R6107 1
 '@T6G_MB_LIB.T6G(SCH_1):PAGE144_I83@PURE_QUANTA.Q_RES(CHIPS)':
 'A': CDS_PINID='A';
NODE_NAME     R6123 1
 '@T6G_MB_LIB.T6G(SCH_1):PAGE83_I71@PURE_QUANTA.Q_RES(CHIPS)':
 'A': CDS_PINID='A';
NODE_NAME     R6124 1
 '@T6G_MB_LIB.T6G(SCH_1):PAGE83_I72@PURE_QUANTA.Q_RES(CHIPS)':
 'A': CDS_PINID='A';
NODE_NAME     U96 1
 '@T6G_MB_LIB.T6G(SCH_1):PAGE137_I51@PURE_QUANTA.PCA9617ADP(CHIPS)':
 'VCCA': CDS_PINID='VCCA';
NODE_NAME     R6120 1
 '@T6G_MB_LIB.T6G(SCH_1):PAGE83_I115@PURE_QUANTA.Q_RES(CHIPS)':
 'A': CDS_PINID='A';
NODE_NAME     R6121 1
 '@T6G_MB_LIB.T6G(SCH_1):PAGE83_I120@PURE_QUANTA.Q_RES(CHIPS)':
 'A': CDS_PINID='A';
NODE_NAME     R438 2
 '@T6G_MB_LIB.T6G(SCH_1):PAGE28_I222@PURE_QUANTA.Q_RES(CHIPS)':
 'B': CDS_PINID='B';
NODE_NAME     R8036 1
 '@T6G_MB_LIB.T6G(SCH_1):PAGE130_I12@PURE_QUANTA.Q_RES(CHIPS)':
 'A': CDS_PINID='A';
NODE_NAME     R1233 1
 '@T6G_MB_LIB.T6G(SCH_1):PAGE263_I227@PURE_QUANTA.Q_RES(CHIPS)':
 'A': CDS_PINID='A';
NODE_NAME     U213 5
 '@T6G_MB_LIB.T6G(SCH_1):PAGE138_I111@PURE_QUANTA.IML3112Y2B000NCG8(CHIPS)':
 'VDD': CDS_PINID='VDD';
NODE_NAME     C24 1
 '@T6G_MB_LIB.T6G(SCH_1):PAGE138_I112@PURE_QUANTA.Q_CAP(CHIPS)':
 'A': CDS_PINID='A';
NODE_NAME     R6130 1
 '@T6G_MB_LIB.T6G(SCH_1):PAGE83_I131@PURE_QUANTA.Q_RES(CHIPS)':
 'A': CDS_PINID='A';
NODE_NAME     R6131 1
 '@T6G_MB_LIB.T6G(SCH_1):PAGE83_I134@PURE_QUANTA.Q_RES(CHIPS)':
 'A': CDS_PINID='A';
NODE_NAME     R6132 1
 '@T6G_MB_LIB.T6G(SCH_1):PAGE83_I135@PURE_QUANTA.Q_RES(CHIPS)':
 'A': CDS_PINID='A';
NET_NAME
'PVDD18_S5_P0_ADC'
 '@T6G_MB_LIB.T6G(SCH_1):PVDD18_S5_P0_ADC':
 C_SIGNAL='@t6g_mb_lib.t6g(sch_1):pvdd18_s5_p0_adc';
NODE_NAME     R1247 1
 '@T6G_MB_LIB.T6G(SCH_1):PAGE263_I225@PURE_QUANTA.Q_RES(CHIPS)':
 'A': CDS_PINID='A';
NODE_NAME     R1254 1
 '@T6G_MB_LIB.T6G(SCH_1):PAGE263_I226@PURE_QUANTA.Q_RES(CHIPS)':
 'A': CDS_PINID='A';
NODE_NAME     R1233 2
 '@T6G_MB_LIB.T6G(SCH_1):PAGE263_I227@PURE_QUANTA.Q_RES(CHIPS)':
 'B': CDS_PINID='B';
NODE_NAME     R1222 1
 '@T6G_MB_LIB.T6G(SCH_1):PAGE263_I246@PURE_QUANTA.Q_RES(CHIPS)':
 'A': CDS_PINID='A';
NET_NAME
'PVDD18_S5_P0_ADC_MAM'
 '@T6G_MB_LIB.T6G(SCH_1):PVDD18_S5_P0_ADC_MAM':
 C_SIGNAL='@t6g_mb_lib.t6g(sch_1):pvdd18_s5_p0_adc_mam';
NODE_NAME     U50 11
 '@T6G_MB_LIB.T6G(SCH_1):PAGE263_I156@PURE_QUANTA.MAX11617EEET(CHIPS)':
 'AIN6': CDS_PINID='AIN6';
NODE_NAME     C1080 1
 '@T6G_MB_LIB.T6G(SCH_1):PAGE263_I221@PURE_QUANTA.Q_CAP(CHIPS)':
 'A': CDS_PINID='A';
NODE_NAME     R1247 2
 '@T6G_MB_LIB.T6G(SCH_1):PAGE263_I225@PURE_QUANTA.Q_RES(CHIPS)':
 'B': CDS_PINID='B';
NET_NAME
'PVDD18_S5_P0_ADC_TIC'
 '@T6G_MB_LIB.T6G(SCH_1):PVDD18_S5_P0_ADC_TIC':
 C_SIGNAL='@t6g_mb_lib.t6g(sch_1):pvdd18_s5_p0_adc_tic';
NODE_NAME     U51 10
 '@T6G_MB_LIB.T6G(SCH_1):PAGE263_I142@PURE_QUANTA.ADC128D818CIMTXNOPB(CHIPS)':
 'IN6': CDS_PINID='IN6';
NODE_NAME     C1088 1
 '@T6G_MB_LIB.T6G(SCH_1):PAGE263_I223@PURE_QUANTA.Q_CAP(CHIPS)':
 'A': CDS_PINID='A';
NODE_NAME     R1254 2
 '@T6G_MB_LIB.T6G(SCH_1):PAGE263_I226@PURE_QUANTA.Q_RES(CHIPS)':
 'B': CDS_PINID='B';
NET_NAME
'PVDD18_S5_P0_CS'
 '@T6G_MB_LIB.T6G(SCH_1):PVDD18_S5_P0_CS':
 C_SIGNAL='@t6g_mb_lib.t6g(sch_1):pvdd18_s5_p0_cs';
NODE_NAME     PR448 1
 '@T6G_MB_LIB.T6G(SCH_1):PAGE184_I17@PURE_QUANTA.Q_RES(CHIPS)':
 'A': CDS_PINID='A';
NODE_NAME     PU57 3
 '@T6G_MB_LIB.T6G(SCH_1):PAGE184_I18@PURE_QUANTA.MPQ8633BGLEC838Z(CHIPS)':
 'CS': CDS_PINID='CS';
NET_NAME
'PVDD18_S5_P0_EN'
 '@T6G_MB_LIB.T6G(SCH_1):PVDD18_S5_P0_EN':
 C_SIGNAL='@t6g_mb_lib.t6g(sch_1):pvdd18_s5_p0_en';
NODE_NAME     R176 1
 '@T6G_MB_LIB.T6G(SCH_1):PAGE80_I33@PURE_QUANTA.Q_RES(CHIPS)':
 'A': CDS_PINID='A';
NODE_NAME     C674 1
 '@T6G_MB_LIB.T6G(SCH_1):PAGE184_I4@PURE_QUANTA.Q_CAP(CHIPS)':
 'A': CDS_PINID='A';
NODE_NAME     PU57 8
 '@T6G_MB_LIB.T6G(SCH_1):PAGE184_I18@PURE_QUANTA.MPQ8633BGLEC838Z(CHIPS)':
 'EN': CDS_PINID='EN';
NET_NAME
'PVDD18_S5_P0_FB'
 '@T6G_MB_LIB.T6G(SCH_1):PVDD18_S5_P0_FB':
 C_SIGNAL='@t6g_mb_lib.t6g(sch_1):pvdd18_s5_p0_fb';
NODE_NAME     PU57 7
 '@T6G_MB_LIB.T6G(SCH_1):PAGE184_I18@PURE_QUANTA.MPQ8633BGLEC838Z(CHIPS)':
 'FB': CDS_PINID='FB';
NODE_NAME     PR470 1
 '@T6G_MB_LIB.T6G(SCH_1):PAGE184_I23@PURE_QUANTA.Q_RES(CHIPS)':
 'A': CDS_PINID='A';
NODE_NAME     PC259 1
 '@T6G_MB_LIB.T6G(SCH_1):PAGE184_I33@PURE_QUANTA.Q_CAP(CHIPS)':
 'A': CDS_PINID='A';
NODE_NAME     PR471 1
 '@T6G_MB_LIB.T6G(SCH_1):PAGE184_I35@PURE_QUANTA.Q_RES(CHIPS)':
 'A': CDS_PINID='A';
NET_NAME
'PVDD18_S5_P0_FB_RC'
 '@T6G_MB_LIB.T6G(SCH_1):PVDD18_S5_P0_FB_RC':
 C_SIGNAL='@t6g_mb_lib.t6g(sch_1):pvdd18_s5_p0_fb_rc';
NODE_NAME     PC259 2
 '@T6G_MB_LIB.T6G(SCH_1):PAGE184_I33@PURE_QUANTA.Q_CAP(CHIPS)':
 'B': CDS_PINID='B';
NODE_NAME     PC6005 1
 '@T6G_MB_LIB.T6G(SCH_1):PAGE184_I34@PURE_QUANTA.Q_CAP(CHIPS)':
 'A': CDS_PINID='A';
NODE_NAME     PR471 2
 '@T6G_MB_LIB.T6G(SCH_1):PAGE184_I35@PURE_QUANTA.Q_RES(CHIPS)':
 'B': CDS_PINID='B';
NODE_NAME     PR434 1
 '@T6G_MB_LIB.T6G(SCH_1):PAGE184_I38@PURE_QUANTA.Q_RES(CHIPS)':
 'A': CDS_PINID='A';
NODE_NAME     PR438 1
 '@T6G_MB_LIB.T6G(SCH_1):PAGE184_I42@PURE_QUANTA.Q_RES(CHIPS)':
 'A': CDS_PINID='A';
NET_NAME
'PVDD18_S5_P0_MODE'
 '@T6G_MB_LIB.T6G(SCH_1):PVDD18_S5_P0_MODE':
 C_SIGNAL='@t6g_mb_lib.t6g(sch_1):pvdd18_s5_p0_mode';
NODE_NAME     PR417 2
 '@T6G_MB_LIB.T6G(SCH_1):PAGE184_I15@PURE_QUANTA.Q_RES(CHIPS)':
 'B': CDS_PINID='B';
NODE_NAME     PU57 4
 '@T6G_MB_LIB.T6G(SCH_1):PAGE184_I18@PURE_QUANTA.MPQ8633BGLEC838Z(CHIPS)':
 'MODE': CDS_PINID='MODE';
NET_NAME
'PVDD18_S5_P0_REF'
 '@T6G_MB_LIB.T6G(SCH_1):PVDD18_S5_P0_REF':
 C_SIGNAL='@t6g_mb_lib.t6g(sch_1):pvdd18_s5_p0_ref';
NODE_NAME     PU57 5
 '@T6G_MB_LIB.T6G(SCH_1):PAGE184_I18@PURE_QUANTA.MPQ8633BGLEC838Z(CHIPS)':
 'TRK_REF': CDS_PINID='TRK_REF';
NODE_NAME     PC258 1
 '@T6G_MB_LIB.T6G(SCH_1):PAGE184_I21@PURE_QUANTA.Q_CAP(CHIPS)':
 'A': CDS_PINID='A';
NODE_NAME     PC113 1
 '@T6G_MB_LIB.T6G(SCH_1):PAGE184_I22@PURE_QUANTA.Q_CAP(CHIPS)':
 'A': CDS_PINID='A';
NET_NAME
'PVDD18_S5_P0_RGND'
 '@T6G_MB_LIB.T6G(SCH_1):PVDD18_S5_P0_RGND':
 C_SIGNAL='@t6g_mb_lib.t6g(sch_1):pvdd18_s5_p0_rgnd';
NODE_NAME     PU57 6
 '@T6G_MB_LIB.T6G(SCH_1):PAGE184_I18@PURE_QUANTA.MPQ8633BGLEC838Z(CHIPS)':
 'RGND': CDS_PINID='RGND';
NODE_NAME     PC113 2
 '@T6G_MB_LIB.T6G(SCH_1):PAGE184_I22@PURE_QUANTA.Q_CAP(CHIPS)':
 'B': CDS_PINID='B';
NODE_NAME     PR470 2
 '@T6G_MB_LIB.T6G(SCH_1):PAGE184_I23@PURE_QUANTA.Q_RES(CHIPS)':
 'B': CDS_PINID='B';
NODE_NAME     PR418 2
 '@T6G_MB_LIB.T6G(SCH_1):PAGE184_I31@PURE_QUANTA.Q_RES(CHIPS)':
 'B': CDS_PINID='B';
NODE_NAME     PC6005 2
 '@T6G_MB_LIB.T6G(SCH_1):PAGE184_I34@PURE_QUANTA.Q_CAP(CHIPS)':
 'B': CDS_PINID='B';
NODE_NAME     PR435 1
 '@T6G_MB_LIB.T6G(SCH_1):PAGE184_I37@PURE_QUANTA.Q_RES(CHIPS)':
 'A': CDS_PINID='A';
NET_NAME
'PVDD18_S5_P0_VCC'
 '@T6G_MB_LIB.T6G(SCH_1):PVDD18_S5_P0_VCC':
 C_SIGNAL='@t6g_mb_lib.t6g(sch_1):pvdd18_s5_p0_vcc';
NODE_NAME     PC212 1
 '@T6G_MB_LIB.T6G(SCH_1):PAGE184_I11@PURE_QUANTA.Q_CAP(CHIPS)':
 'A': CDS_PINID='A';
NODE_NAME     PR477 2
 '@T6G_MB_LIB.T6G(SCH_1):PAGE184_I12@PURE_QUANTA.Q_RES(CHIPS)':
 'B': CDS_PINID='B';
NODE_NAME     PU57 19
 '@T6G_MB_LIB.T6G(SCH_1):PAGE184_I18@PURE_QUANTA.MPQ8633BGLEC838Z(CHIPS)':
 'VCC': CDS_PINID='VCC';
NET_NAME
'PVDD18_S5_P1'
 '@T6G_MB_LIB.T6G(SCH_1):PVDD18_S5_P1':
 C_SIGNAL='@t6g_mb_lib.t6g(sch_1):pvdd18_s5_p1',
 CDS_GLOBAL_NET='TRUE';
NODE_NAME     R528 1
 '@T6G_MB_LIB.T6G(SCH_1):PAGE54_I308@PURE_QUANTA.Q_RES(CHIPS)':
 'A': CDS_PINID='A';
NODE_NAME     R527 1
 '@T6G_MB_LIB.T6G(SCH_1):PAGE54_I309@PURE_QUANTA.Q_RES(CHIPS)':
 'A': CDS_PINID='A';
NODE_NAME     R526 1
 '@T6G_MB_LIB.T6G(SCH_1):PAGE54_I314@PURE_QUANTA.Q_RES(CHIPS)':
 'A': CDS_PINID='A';
NODE_NAME     R525 1
 '@T6G_MB_LIB.T6G(SCH_1):PAGE54_I316@PURE_QUANTA.Q_RES(CHIPS)':
 'A': CDS_PINID='A';
NODE_NAME     R524 1
 '@T6G_MB_LIB.T6G(SCH_1):PAGE54_I317@PURE_QUANTA.Q_RES(CHIPS)':
 'A': CDS_PINID='A';
NODE_NAME     R523 1
 '@T6G_MB_LIB.T6G(SCH_1):PAGE54_I324@PURE_QUANTA.Q_RES(CHIPS)':
 'A': CDS_PINID='A';
NODE_NAME     R520 2
 '@T6G_MB_LIB.T6G(SCH_1):PAGE54_I396@PURE_QUANTA.Q_RES(CHIPS)':
 'B': CDS_PINID='B';
NODE_NAME     R535 2
 '@T6G_MB_LIB.T6G(SCH_1):PAGE54_I398@PURE_QUANTA.Q_RES(CHIPS)':
 'B': CDS_PINID='B';
NODE_NAME     R518 1
 '@T6G_MB_LIB.T6G(SCH_1):PAGE54_I403@PURE_QUANTA.Q_RES(CHIPS)':
 'A': CDS_PINID='A';
NODE_NAME     R1424 1
 '@T6G_MB_LIB.T6G(SCH_1):PAGE55_I292@PURE_QUANTA.Q_RES(CHIPS)':
 'A': CDS_PINID='A';
NODE_NAME     U26 AR52
 '@T6G_MB_LIB.T6G(SCH_1):PAGE57_I45@PURE_QUANTA.GENOA_SP5(CHIPS)':
 'VDD_18_S5_AR52': CDS_PINID='VDD_18_S5_AR52';
NODE_NAME     U26 AR54
 '@T6G_MB_LIB.T6G(SCH_1):PAGE57_I45@PURE_QUANTA.GENOA_SP5(CHIPS)':
 'VDD_18_S5_AR54': CDS_PINID='VDD_18_S5_AR54';
NODE_NAME     U26 AT51
 '@T6G_MB_LIB.T6G(SCH_1):PAGE57_I45@PURE_QUANTA.GENOA_SP5(CHIPS)':
 'VDD_18_S5_AT51': CDS_PINID='VDD_18_S5_AT51';
NODE_NAME     U26 AT53
 '@T6G_MB_LIB.T6G(SCH_1):PAGE57_I45@PURE_QUANTA.GENOA_SP5(CHIPS)':
 'VDD_18_S5_AT53': CDS_PINID='VDD_18_S5_AT53';
NODE_NAME     U26 AU50
 '@T6G_MB_LIB.T6G(SCH_1):PAGE57_I45@PURE_QUANTA.GENOA_SP5(CHIPS)':
 'VDD_18_S5_AU50': CDS_PINID='VDD_18_S5_AU50';
NODE_NAME     U26 AU52
 '@T6G_MB_LIB.T6G(SCH_1):PAGE57_I45@PURE_QUANTA.GENOA_SP5(CHIPS)':
 'VDD_18_S5_AU52': CDS_PINID='VDD_18_S5_AU52';
NODE_NAME     U26 AU54
 '@T6G_MB_LIB.T6G(SCH_1):PAGE57_I45@PURE_QUANTA.GENOA_SP5(CHIPS)':
 'VDD_18_S5_AU54': CDS_PINID='VDD_18_S5_AU54';
NODE_NAME     U26 AV49
 '@T6G_MB_LIB.T6G(SCH_1):PAGE57_I45@PURE_QUANTA.GENOA_SP5(CHIPS)':
 'VDD_18_S5_AV49': CDS_PINID='VDD_18_S5_AV49';
NODE_NAME     U26 AV51
 '@T6G_MB_LIB.T6G(SCH_1):PAGE57_I45@PURE_QUANTA.GENOA_SP5(CHIPS)':
 'VDD_18_S5_AV51': CDS_PINID='VDD_18_S5_AV51';
NODE_NAME     U26 AV53
 '@T6G_MB_LIB.T6G(SCH_1):PAGE57_I45@PURE_QUANTA.GENOA_SP5(CHIPS)':
 'VDD_18_S5_AV53': CDS_PINID='VDD_18_S5_AV53';
NODE_NAME     U26 AW50
 '@T6G_MB_LIB.T6G(SCH_1):PAGE57_I45@PURE_QUANTA.GENOA_SP5(CHIPS)':
 'VDD_18_S5_AW50': CDS_PINID='VDD_18_S5_AW50';
NODE_NAME     U26 AW52
 '@T6G_MB_LIB.T6G(SCH_1):PAGE57_I45@PURE_QUANTA.GENOA_SP5(CHIPS)':
 'VDD_18_S5_AW52': CDS_PINID='VDD_18_S5_AW52';
NODE_NAME     U26 AW54
 '@T6G_MB_LIB.T6G(SCH_1):PAGE57_I45@PURE_QUANTA.GENOA_SP5(CHIPS)':
 'VDD_18_S5_AW54': CDS_PINID='VDD_18_S5_AW54';
NODE_NAME     U26 AY51
 '@T6G_MB_LIB.T6G(SCH_1):PAGE57_I45@PURE_QUANTA.GENOA_SP5(CHIPS)':
 'VDD_18_S5_AY51': CDS_PINID='VDD_18_S5_AY51';
NODE_NAME     U26 AY53
 '@T6G_MB_LIB.T6G(SCH_1):PAGE57_I45@PURE_QUANTA.GENOA_SP5(CHIPS)':
 'VDD_18_S5_AY53': CDS_PINID='VDD_18_S5_AY53';
NODE_NAME     U26 BA50
 '@T6G_MB_LIB.T6G(SCH_1):PAGE57_I45@PURE_QUANTA.GENOA_SP5(CHIPS)':
 'VDD_18_S5_BA50': CDS_PINID='VDD_18_S5_BA50';
NODE_NAME     U26 BA52
 '@T6G_MB_LIB.T6G(SCH_1):PAGE57_I45@PURE_QUANTA.GENOA_SP5(CHIPS)':
 'VDD_18_S5_BA52': CDS_PINID='VDD_18_S5_BA52';
NODE_NAME     U26 BA54
 '@T6G_MB_LIB.T6G(SCH_1):PAGE57_I45@PURE_QUANTA.GENOA_SP5(CHIPS)':
 'VDD_18_S5_BA54': CDS_PINID='VDD_18_S5_BA54';
NODE_NAME     U26 BB51
 '@T6G_MB_LIB.T6G(SCH_1):PAGE57_I45@PURE_QUANTA.GENOA_SP5(CHIPS)':
 'VDD_18_S5_BB51': CDS_PINID='VDD_18_S5_BB51';
NODE_NAME     U26 BB53
 '@T6G_MB_LIB.T6G(SCH_1):PAGE57_I45@PURE_QUANTA.GENOA_SP5(CHIPS)':
 'VDD_18_S5_BB53': CDS_PINID='VDD_18_S5_BB53';
NODE_NAME     U26 BC52
 '@T6G_MB_LIB.T6G(SCH_1):PAGE57_I45@PURE_QUANTA.GENOA_SP5(CHIPS)':
 'VDD_18_S5_BC52': CDS_PINID='VDD_18_S5_BC52';
NODE_NAME     U26 BC54
 '@T6G_MB_LIB.T6G(SCH_1):PAGE57_I45@PURE_QUANTA.GENOA_SP5(CHIPS)':
 'VDD_18_S5_BC54': CDS_PINID='VDD_18_S5_BC54';
NODE_NAME     U26 BH27
 '@T6G_MB_LIB.T6G(SCH_1):PAGE57_I45@PURE_QUANTA.GENOA_SP5(CHIPS)':
 'VDDIO_AUDIO': CDS_PINID='VDDIO_AUDIO';
NODE_NAME     R374 1
 '@T6G_MB_LIB.T6G(SCH_1):PAGE57_I51@PURE_QUANTA.Q_RES(CHIPS)':
 'A': CDS_PINID='A';
NODE_NAME     C2292 1
 '@T6G_MB_LIB.T6G(SCH_1):PAGE71_I49@PURE_QUANTA.Q_CAP(CHIPS)':
 'A': CDS_PINID='A';
NODE_NAME     C2293 1
 '@T6G_MB_LIB.T6G(SCH_1):PAGE71_I50@PURE_QUANTA.Q_CAP(CHIPS)':
 'A': CDS_PINID='A';
NODE_NAME     C3909 1
 '@T6G_MB_LIB.T6G(SCH_1):PAGE71_I52@PURE_QUANTA.Q_CAP(CHIPS)':
 'A': CDS_PINID='A';
NODE_NAME     C2661 1
 '@T6G_MB_LIB.T6G(SCH_1):PAGE74_I1@PURE_QUANTA.Q_CAP(CHIPS)':
 'A': CDS_PINID='A';
NODE_NAME     C2660 1
 '@T6G_MB_LIB.T6G(SCH_1):PAGE74_I3@PURE_QUANTA.Q_CAP(CHIPS)':
 'A': CDS_PINID='A';
NODE_NAME     C2664 1
 '@T6G_MB_LIB.T6G(SCH_1):PAGE74_I8@PURE_QUANTA.Q_CAP(CHIPS)':
 'A': CDS_PINID='A';
NODE_NAME     C2663 1
 '@T6G_MB_LIB.T6G(SCH_1):PAGE74_I9@PURE_QUANTA.Q_CAP(CHIPS)':
 'A': CDS_PINID='A';
NODE_NAME     C2665 1
 '@T6G_MB_LIB.T6G(SCH_1):PAGE74_I10@PURE_QUANTA.Q_CAP(CHIPS)':
 'A': CDS_PINID='A';
NODE_NAME     C2667 1
 '@T6G_MB_LIB.T6G(SCH_1):PAGE74_I11@PURE_QUANTA.Q_CAP(CHIPS)':
 'A': CDS_PINID='A';
NODE_NAME     C2668 1
 '@T6G_MB_LIB.T6G(SCH_1):PAGE74_I12@PURE_QUANTA.Q_CAP(CHIPS)':
 'A': CDS_PINID='A';
NODE_NAME     C2669 1
 '@T6G_MB_LIB.T6G(SCH_1):PAGE74_I13@PURE_QUANTA.Q_CAP(CHIPS)':
 'A': CDS_PINID='A';
NODE_NAME     C2670 1
 '@T6G_MB_LIB.T6G(SCH_1):PAGE74_I14@PURE_QUANTA.Q_CAP(CHIPS)':
 'A': CDS_PINID='A';
NODE_NAME     C2671 1
 '@T6G_MB_LIB.T6G(SCH_1):PAGE74_I15@PURE_QUANTA.Q_CAP(CHIPS)':
 'A': CDS_PINID='A';
NODE_NAME     C2672 1
 '@T6G_MB_LIB.T6G(SCH_1):PAGE74_I16@PURE_QUANTA.Q_CAP(CHIPS)':
 'A': CDS_PINID='A';
NODE_NAME     C2673 1
 '@T6G_MB_LIB.T6G(SCH_1):PAGE74_I18@PURE_QUANTA.Q_CAP(CHIPS)':
 'A': CDS_PINID='A';
NODE_NAME     R366 1
 '@T6G_MB_LIB.T6G(SCH_1):PAGE138_I54@PURE_QUANTA.Q_RES(CHIPS)':
 'A': CDS_PINID='A';
NODE_NAME     R369 1
 '@T6G_MB_LIB.T6G(SCH_1):PAGE138_I58@PURE_QUANTA.Q_RES(CHIPS)':
 'A': CDS_PINID='A';
NODE_NAME     U151 15
 '@T6G_MB_LIB.T6G(SCH_1):PAGE150_I28@PURE_QUANTA.SN74AVC4T774PWR(CHIPS)':
 'VCCB': CDS_PINID='VCCB';
NODE_NAME     C1517 1
 '@T6G_MB_LIB.T6G(SCH_1):PAGE150_I40@PURE_QUANTA.Q_CAP(CHIPS)':
 'A': CDS_PINID='A';
NODE_NAME     R531 2
 '@T6G_MB_LIB.T6G(SCH_1):PAGE54_I406@PURE_QUANTA.Q_RES(CHIPS)':
 'B': CDS_PINID='B';
NODE_NAME     R532 2
 '@T6G_MB_LIB.T6G(SCH_1):PAGE54_I407@PURE_QUANTA.Q_RES(CHIPS)':
 'B': CDS_PINID='B';
NODE_NAME     R533 2
 '@T6G_MB_LIB.T6G(SCH_1):PAGE54_I408@PURE_QUANTA.Q_RES(CHIPS)':
 'B': CDS_PINID='B';
NODE_NAME     R534 2
 '@T6G_MB_LIB.T6G(SCH_1):PAGE54_I409@PURE_QUANTA.Q_RES(CHIPS)':
 'B': CDS_PINID='B';
NODE_NAME     R537 2
 '@T6G_MB_LIB.T6G(SCH_1):PAGE54_I410@PURE_QUANTA.Q_RES(CHIPS)':
 'B': CDS_PINID='B';
NODE_NAME     R538 2
 '@T6G_MB_LIB.T6G(SCH_1):PAGE54_I411@PURE_QUANTA.Q_RES(CHIPS)':
 'B': CDS_PINID='B';
NODE_NAME     R539 2
 '@T6G_MB_LIB.T6G(SCH_1):PAGE54_I412@PURE_QUANTA.Q_RES(CHIPS)':
 'B': CDS_PINID='B';
NODE_NAME     R540 2
 '@T6G_MB_LIB.T6G(SCH_1):PAGE54_I413@PURE_QUANTA.Q_RES(CHIPS)':
 'B': CDS_PINID='B';
NODE_NAME     PC65 1
 '@T6G_MB_LIB.T6G(SCH_1):PAGE201_I37@PURE_QUANTA.Q_CAP(CHIPS)':
 'A': CDS_PINID='A';
NODE_NAME     PC83 1
 '@T6G_MB_LIB.T6G(SCH_1):PAGE201_I38@PURE_QUANTA.Q_CAP(CHIPS)':
 'A': CDS_PINID='A';
NODE_NAME     PR402 1
 '@T6G_MB_LIB.T6G(SCH_1):PAGE201_I39@PURE_QUANTA.Q_RES(CHIPS)':
 'A': CDS_PINID='A';
NODE_NAME     PC88 1
 '@T6G_MB_LIB.T6G(SCH_1):PAGE201_I42@PURE_QUANTA.Q_CAP(CHIPS)':
 'A': CDS_PINID='A';
NODE_NAME     PC89 1
 '@T6G_MB_LIB.T6G(SCH_1):PAGE201_I43@PURE_QUANTA.Q_CAPP(CHIPS)':
 'A': CDS_PINID='A';
NODE_NAME     PR403 1
 '@T6G_MB_LIB.T6G(SCH_1):PAGE201_I50@PURE_QUANTA.Q_RES(CHIPS)':
 'A': CDS_PINID='A';
NODE_NAME     R730 1
 '@T6G_MB_LIB.T6G(SCH_1):PAGE75_I87@PURE_QUANTA.Q_RES(CHIPS)':
 'A': CDS_PINID='A';
NODE_NAME     R736 1
 '@T6G_MB_LIB.T6G(SCH_1):PAGE75_I89@PURE_QUANTA.Q_RES(CHIPS)':
 'A': CDS_PINID='A';
NODE_NAME     R1501 1
 '@T6G_MB_LIB.T6G(SCH_1):PAGE75_I90@PURE_QUANTA.Q_RES(CHIPS)':
 'A': CDS_PINID='A';
NODE_NAME     R154 1
 '@T6G_MB_LIB.T6G(SCH_1):PAGE185_I67@PURE_QUANTA.Q_RES(CHIPS)':
 'A': CDS_PINID='A';
NODE_NAME     R8156 1
 '@T6G_MB_LIB.T6G(SCH_1):PAGE185_I68@PURE_QUANTA.Q_RES(CHIPS)':
 'A': CDS_PINID='A';
NODE_NAME     R1286 2
 '@T6G_MB_LIB.T6G(SCH_1):PAGE82_I76@PURE_QUANTA.Q_RES(CHIPS)':
 'B': CDS_PINID='B';
NODE_NAME     R1285 2
 '@T6G_MB_LIB.T6G(SCH_1):PAGE82_I77@PURE_QUANTA.Q_RES(CHIPS)':
 'B': CDS_PINID='B';
NODE_NAME     R544 2
 '@T6G_MB_LIB.T6G(SCH_1):PAGE55_I336@PURE_QUANTA.Q_RES(CHIPS)':
 'B': CDS_PINID='B';
NODE_NAME     R545 2
 '@T6G_MB_LIB.T6G(SCH_1):PAGE55_I337@PURE_QUANTA.Q_RES(CHIPS)':
 'B': CDS_PINID='B';
NODE_NAME     R546 2
 '@T6G_MB_LIB.T6G(SCH_1):PAGE55_I338@PURE_QUANTA.Q_RES(CHIPS)':
 'B': CDS_PINID='B';
NODE_NAME     R456 2
 '@T6G_MB_LIB.T6G(SCH_1):PAGE55_I339@PURE_QUANTA.Q_RES(CHIPS)':
 'B': CDS_PINID='B';
NODE_NAME     R583 2
 '@T6G_MB_LIB.T6G(SCH_1):PAGE55_I342@PURE_QUANTA.Q_RES(CHIPS)':
 'B': CDS_PINID='B';
NODE_NAME     R548 2
 '@T6G_MB_LIB.T6G(SCH_1):PAGE55_I352@PURE_QUANTA.Q_RES(CHIPS)':
 'B': CDS_PINID='B';
NODE_NAME     R549 2
 '@T6G_MB_LIB.T6G(SCH_1):PAGE55_I353@PURE_QUANTA.Q_RES(CHIPS)':
 'B': CDS_PINID='B';
NODE_NAME     R562 1
 '@T6G_MB_LIB.T6G(SCH_1):PAGE55_I355@PURE_QUANTA.Q_RES(CHIPS)':
 'A': CDS_PINID='A';
NODE_NAME     R559 1
 '@T6G_MB_LIB.T6G(SCH_1):PAGE55_I356@PURE_QUANTA.Q_RES(CHIPS)':
 'A': CDS_PINID='A';
NODE_NAME     R556 1
 '@T6G_MB_LIB.T6G(SCH_1):PAGE55_I357@PURE_QUANTA.Q_RES(CHIPS)':
 'A': CDS_PINID='A';
NODE_NAME     R553 2
 '@T6G_MB_LIB.T6G(SCH_1):PAGE55_I359@PURE_QUANTA.Q_RES(CHIPS)':
 'B': CDS_PINID='B';
NODE_NAME     R551 2
 '@T6G_MB_LIB.T6G(SCH_1):PAGE55_I360@PURE_QUANTA.Q_RES(CHIPS)':
 'B': CDS_PINID='B';
NODE_NAME     R547 2
 '@T6G_MB_LIB.T6G(SCH_1):PAGE55_I362@PURE_QUANTA.Q_RES(CHIPS)':
 'B': CDS_PINID='B';
NODE_NAME     R550 2
 '@T6G_MB_LIB.T6G(SCH_1):PAGE55_I363@PURE_QUANTA.Q_RES(CHIPS)':
 'B': CDS_PINID='B';
NODE_NAME     R557 1
 '@T6G_MB_LIB.T6G(SCH_1):PAGE55_I364@PURE_QUANTA.Q_RES(CHIPS)':
 'A': CDS_PINID='A';
NODE_NAME     PR151 1
 '@T6G_MB_LIB.T6G(SCH_1):PAGE185_I10@PURE_QUANTA.Q_RES(CHIPS)':
 'A': CDS_PINID='A';
NODE_NAME     R8184 1
 '@T6G_MB_LIB.T6G(SCH_1):PAGE185_I41@PURE_QUANTA.Q_RES(CHIPS)':
 'A': CDS_PINID='A';
NODE_NAME     R8180 1
 '@T6G_MB_LIB.T6G(SCH_1):PAGE185_I54@PURE_QUANTA.Q_RES(CHIPS)':
 'A': CDS_PINID='A';
NODE_NAME     R8160 1
 '@T6G_MB_LIB.T6G(SCH_1):PAGE185_I69@PURE_QUANTA.Q_RES(CHIPS)':
 'A': CDS_PINID='A';
NODE_NAME     PC247 1
 '@T6G_MB_LIB.T6G(SCH_1):PAGE185_I132@PURE_QUANTA.Q_CAP(CHIPS)':
 'A': CDS_PINID='A';
NODE_NAME     PU25 19
 '@T6G_MB_LIB.T6G(SCH_1):PAGE185_I133@PURE_QUANTA.RAA229620GNPHA0(CHIPS)':
 'VDDIO': CDS_PINID='VDDIO';
NODE_NAME     PR218 1
 '@T6G_MB_LIB.T6G(SCH_1):PAGE192_I38@PURE_QUANTA.Q_RES(CHIPS)':
 'A': CDS_PINID='A';
NODE_NAME     R8220 1
 '@T6G_MB_LIB.T6G(SCH_1):PAGE192_I40@PURE_QUANTA.Q_RES(CHIPS)':
 'A': CDS_PINID='A';
NODE_NAME     R8222 1
 '@T6G_MB_LIB.T6G(SCH_1):PAGE192_I41@PURE_QUANTA.Q_RES(CHIPS)':
 'A': CDS_PINID='A';
NODE_NAME     R8225 1
 '@T6G_MB_LIB.T6G(SCH_1):PAGE192_I42@PURE_QUANTA.Q_RES(CHIPS)':
 'A': CDS_PINID='A';
NODE_NAME     PC363 1
 '@T6G_MB_LIB.T6G(SCH_1):PAGE192_I60@PURE_QUANTA.Q_CAP(CHIPS)':
 'A': CDS_PINID='A';
NODE_NAME     R8247 1
 '@T6G_MB_LIB.T6G(SCH_1):PAGE192_I66@PURE_QUANTA.Q_RES(CHIPS)':
 'A': CDS_PINID='A';
NODE_NAME     R8252 1
 '@T6G_MB_LIB.T6G(SCH_1):PAGE192_I71@PURE_QUANTA.Q_RES(CHIPS)':
 'A': CDS_PINID='A';
NODE_NAME     PU34 19
 '@T6G_MB_LIB.T6G(SCH_1):PAGE192_I128@PURE_QUANTA.RAA229620GNPHA0(CHIPS)':
 'VDDIO': CDS_PINID='VDDIO';
NODE_NAME     R8011 1
 '@T6G_MB_LIB.T6G(SCH_1):PAGE199_I24@PURE_QUANTA.Q_RES(CHIPS)':
 'A': CDS_PINID='A';
NODE_NAME     PR391 2
 '@T6G_MB_LIB.T6G(SCH_1):PAGE199_I67@PURE_QUANTA.Q_RES(CHIPS)':
 'B': CDS_PINID='B';
NODE_NAME     PL57 2
 '@T6G_MB_LIB.T6G(SCH_1):PAGE201_I33@PURE_QUANTA.Q_INDUCTOR(CHIPS)':
 '2': CDS_PINID='\2\';
NODE_NAME     PC84 1
 '@T6G_MB_LIB.T6G(SCH_1):PAGE201_I40@PURE_QUANTA.Q_CAP(CHIPS)':
 'A': CDS_PINID='A';
NODE_NAME     PC87 1
 '@T6G_MB_LIB.T6G(SCH_1):PAGE201_I41@PURE_QUANTA.Q_CAP(CHIPS)':
 'A': CDS_PINID='A';
NODE_NAME     PC21 1
 '@T6G_MB_LIB.T6G(SCH_1):PAGE201_I47@PURE_QUANTA.Q_CAP(CHIPS)':
 'A': CDS_PINID='A';
NODE_NAME     R558 2
 '@T6G_MB_LIB.T6G(SCH_1):PAGE55_I390@PURE_QUANTA.Q_RES(CHIPS)':
 'B': CDS_PINID='B';
NODE_NAME     R1236 1
 '@T6G_MB_LIB.T6G(SCH_1):PAGE263_I230@PURE_QUANTA.Q_RES(CHIPS)':
 'A': CDS_PINID='A';
NODE_NAME     R536 2
 '@T6G_MB_LIB.T6G(SCH_1):PAGE54_I421@PURE_QUANTA.Q_RES(CHIPS)':
 'B': CDS_PINID='B';
NET_NAME
'PVDD18_S5_P1_ADC'
 '@T6G_MB_LIB.T6G(SCH_1):PVDD18_S5_P1_ADC':
 C_SIGNAL='@t6g_mb_lib.t6g(sch_1):pvdd18_s5_p1_adc';
NODE_NAME     R1236 2
 '@T6G_MB_LIB.T6G(SCH_1):PAGE263_I230@PURE_QUANTA.Q_RES(CHIPS)':
 'B': CDS_PINID='B';
NODE_NAME     R1249 1
 '@T6G_MB_LIB.T6G(SCH_1):PAGE263_I231@PURE_QUANTA.Q_RES(CHIPS)':
 'A': CDS_PINID='A';
NODE_NAME     R1256 1
 '@T6G_MB_LIB.T6G(SCH_1):PAGE263_I239@PURE_QUANTA.Q_RES(CHIPS)':
 'A': CDS_PINID='A';
NODE_NAME     R1225 1
 '@T6G_MB_LIB.T6G(SCH_1):PAGE263_I247@PURE_QUANTA.Q_RES(CHIPS)':
 'A': CDS_PINID='A';
NET_NAME
'PVDD18_S5_P1_ADC_MAM'
 '@T6G_MB_LIB.T6G(SCH_1):PVDD18_S5_P1_ADC_MAM':
 C_SIGNAL='@t6g_mb_lib.t6g(sch_1):pvdd18_s5_p1_adc_mam';
NODE_NAME     U50 12
 '@T6G_MB_LIB.T6G(SCH_1):PAGE263_I156@PURE_QUANTA.MAX11617EEET(CHIPS)':
 'AIN7': CDS_PINID='AIN7';
NODE_NAME     R1249 2
 '@T6G_MB_LIB.T6G(SCH_1):PAGE263_I231@PURE_QUANTA.Q_RES(CHIPS)':
 'B': CDS_PINID='B';
NODE_NAME     C1081 1
 '@T6G_MB_LIB.T6G(SCH_1):PAGE263_I232@PURE_QUANTA.Q_CAP(CHIPS)':
 'A': CDS_PINID='A';
NET_NAME
'PVDD18_S5_P1_ADC_TIC'
 '@T6G_MB_LIB.T6G(SCH_1):PVDD18_S5_P1_ADC_TIC':
 C_SIGNAL='@t6g_mb_lib.t6g(sch_1):pvdd18_s5_p1_adc_tic';
NODE_NAME     U51 9
 '@T6G_MB_LIB.T6G(SCH_1):PAGE263_I142@PURE_QUANTA.ADC128D818CIMTXNOPB(CHIPS)':
 'IN7': CDS_PINID='IN7';
NODE_NAME     C1090 1
 '@T6G_MB_LIB.T6G(SCH_1):PAGE263_I237@PURE_QUANTA.Q_CAP(CHIPS)':
 'A': CDS_PINID='A';
NODE_NAME     R1256 2
 '@T6G_MB_LIB.T6G(SCH_1):PAGE263_I239@PURE_QUANTA.Q_RES(CHIPS)':
 'B': CDS_PINID='B';
NET_NAME
'PVDD18_S5_P1_CS'
 '@T6G_MB_LIB.T6G(SCH_1):PVDD18_S5_P1_CS':
 C_SIGNAL='@t6g_mb_lib.t6g(sch_1):pvdd18_s5_p1_cs';
NODE_NAME     PR8 1
 '@T6G_MB_LIB.T6G(SCH_1):PAGE201_I11@PURE_QUANTA.Q_RES(CHIPS)':
 'A': CDS_PINID='A';
NODE_NAME     PU3 3
 '@T6G_MB_LIB.T6G(SCH_1):PAGE201_I15@PURE_QUANTA.MPQ8633BGLEC838Z(CHIPS)':
 'CS': CDS_PINID='CS';
NET_NAME
'PVDD18_S5_P1_EN'
 '@T6G_MB_LIB.T6G(SCH_1):PVDD18_S5_P1_EN':
 C_SIGNAL='@t6g_mb_lib.t6g(sch_1):pvdd18_s5_p1_en';
NODE_NAME     C675 1
 '@T6G_MB_LIB.T6G(SCH_1):PAGE201_I6@PURE_QUANTA.Q_CAP(CHIPS)':
 'A': CDS_PINID='A';
NODE_NAME     PU3 8
 '@T6G_MB_LIB.T6G(SCH_1):PAGE201_I15@PURE_QUANTA.MPQ8633BGLEC838Z(CHIPS)':
 'EN': CDS_PINID='EN';
NODE_NAME     R289 1
 '@T6G_MB_LIB.T6G(SCH_1):PAGE80_I57@PURE_QUANTA.Q_RES(CHIPS)':
 'A': CDS_PINID='A';
NET_NAME
'PVDD18_S5_P1_FB'
 '@T6G_MB_LIB.T6G(SCH_1):PVDD18_S5_P1_FB':
 C_SIGNAL='@t6g_mb_lib.t6g(sch_1):pvdd18_s5_p1_fb';
NODE_NAME     PU3 7
 '@T6G_MB_LIB.T6G(SCH_1):PAGE201_I15@PURE_QUANTA.MPQ8633BGLEC838Z(CHIPS)':
 'FB': CDS_PINID='FB';
NODE_NAME     PR147 1
 '@T6G_MB_LIB.T6G(SCH_1):PAGE201_I30@PURE_QUANTA.Q_RES(CHIPS)':
 'A': CDS_PINID='A';
NODE_NAME     PC64 1
 '@T6G_MB_LIB.T6G(SCH_1):PAGE201_I31@PURE_QUANTA.Q_CAP(CHIPS)':
 'A': CDS_PINID='A';
NODE_NAME     PR148 1
 '@T6G_MB_LIB.T6G(SCH_1):PAGE201_I32@PURE_QUANTA.Q_RES(CHIPS)':
 'A': CDS_PINID='A';
NET_NAME
'PVDD18_S5_P1_FB_RC'
 '@T6G_MB_LIB.T6G(SCH_1):PVDD18_S5_P1_FB_RC':
 C_SIGNAL='@t6g_mb_lib.t6g(sch_1):pvdd18_s5_p1_fb_rc';
NODE_NAME     PR402 2
 '@T6G_MB_LIB.T6G(SCH_1):PAGE201_I39@PURE_QUANTA.Q_RES(CHIPS)':
 'B': CDS_PINID='B';
NODE_NAME     PC64 2
 '@T6G_MB_LIB.T6G(SCH_1):PAGE201_I31@PURE_QUANTA.Q_CAP(CHIPS)':
 'B': CDS_PINID='B';
NODE_NAME     PR148 2
 '@T6G_MB_LIB.T6G(SCH_1):PAGE201_I32@PURE_QUANTA.Q_RES(CHIPS)':
 'B': CDS_PINID='B';
NODE_NAME     PC6006 1
 '@T6G_MB_LIB.T6G(SCH_1):PAGE201_I34@PURE_QUANTA.Q_CAP(CHIPS)':
 'A': CDS_PINID='A';
NODE_NAME     PR400 1
 '@T6G_MB_LIB.T6G(SCH_1):PAGE201_I36@PURE_QUANTA.Q_RES(CHIPS)':
 'A': CDS_PINID='A';
NET_NAME
'PVDD18_S5_P1_MODE'
 '@T6G_MB_LIB.T6G(SCH_1):PVDD18_S5_P1_MODE':
 C_SIGNAL='@t6g_mb_lib.t6g(sch_1):pvdd18_s5_p1_mode';
NODE_NAME     PU3 4
 '@T6G_MB_LIB.T6G(SCH_1):PAGE201_I15@PURE_QUANTA.MPQ8633BGLEC838Z(CHIPS)':
 'MODE': CDS_PINID='MODE';
NODE_NAME     PR398 2
 '@T6G_MB_LIB.T6G(SCH_1):PAGE201_I14@PURE_QUANTA.Q_RES(CHIPS)':
 'B': CDS_PINID='B';
NET_NAME
'PVDD18_S5_P1_REF'
 '@T6G_MB_LIB.T6G(SCH_1):PVDD18_S5_P1_REF':
 C_SIGNAL='@t6g_mb_lib.t6g(sch_1):pvdd18_s5_p1_ref';
NODE_NAME     PU3 5
 '@T6G_MB_LIB.T6G(SCH_1):PAGE201_I15@PURE_QUANTA.MPQ8633BGLEC838Z(CHIPS)':
 'TRK_REF': CDS_PINID='TRK_REF';
NODE_NAME     PC153 1
 '@T6G_MB_LIB.T6G(SCH_1):PAGE201_I18@PURE_QUANTA.Q_CAP(CHIPS)':
 'A': CDS_PINID='A';
NODE_NAME     PC62 1
 '@T6G_MB_LIB.T6G(SCH_1):PAGE201_I19@PURE_QUANTA.Q_CAP(CHIPS)':
 'A': CDS_PINID='A';
NET_NAME
'PVDD18_S5_P1_R_EN'
 '@T6G_MB_LIB.T6G(SCH_1):PVDD18_S5_P1_R_EN':
 C_SIGNAL='@t6g_mb_lib.t6g(sch_1):pvdd18_s5_p1_r_en';
NODE_NAME     R289 2
 '@T6G_MB_LIB.T6G(SCH_1):PAGE80_I57@PURE_QUANTA.Q_RES(CHIPS)':
 'B': CDS_PINID='B';
NODE_NAME     U18 V8
 '@T6G_MB_LIB.T6G(SCH_1):PAGE80_I216@PURE_QUANTA.LCMXO3LF9400C5BG484C(CHIPS)':
 'PB13C': CDS_PINID='PB13C';
NET_NAME
'PVDD18_S5_P1_VCC'
 '@T6G_MB_LIB.T6G(SCH_1):PVDD18_S5_P1_VCC':
 C_SIGNAL='@t6g_mb_lib.t6g(sch_1):pvdd18_s5_p1_vcc';
NODE_NAME     PR397 2
 '@T6G_MB_LIB.T6G(SCH_1):PAGE201_I12@PURE_QUANTA.Q_RES(CHIPS)':
 'B': CDS_PINID='B';
NODE_NAME     PU3 19
 '@T6G_MB_LIB.T6G(SCH_1):PAGE201_I15@PURE_QUANTA.MPQ8633BGLEC838Z(CHIPS)':
 'VCC': CDS_PINID='VCC';
NODE_NAME     PC20 1
 '@T6G_MB_LIB.T6G(SCH_1):PAGE201_I53@PURE_QUANTA.Q_CAP(CHIPS)':
 'A': CDS_PINID='A';
NET_NAME
'PVDD18_SS_P1_RGND'
 '@T6G_MB_LIB.T6G(SCH_1):PVDD18_SS_P1_RGND':
 C_SIGNAL='@t6g_mb_lib.t6g(sch_1):pvdd18_ss_p1_rgnd';
NODE_NAME     PU3 6
 '@T6G_MB_LIB.T6G(SCH_1):PAGE201_I15@PURE_QUANTA.MPQ8633BGLEC838Z(CHIPS)':
 'RGND': CDS_PINID='RGND';
NODE_NAME     PC62 2
 '@T6G_MB_LIB.T6G(SCH_1):PAGE201_I19@PURE_QUANTA.Q_CAP(CHIPS)':
 'B': CDS_PINID='B';
NODE_NAME     PR399 2
 '@T6G_MB_LIB.T6G(SCH_1):PAGE201_I29@PURE_QUANTA.Q_RES(CHIPS)':
 'B': CDS_PINID='B';
NODE_NAME     PR147 2
 '@T6G_MB_LIB.T6G(SCH_1):PAGE201_I30@PURE_QUANTA.Q_RES(CHIPS)':
 'B': CDS_PINID='B';
NODE_NAME     PC6006 2
 '@T6G_MB_LIB.T6G(SCH_1):PAGE201_I34@PURE_QUANTA.Q_CAP(CHIPS)':
 'B': CDS_PINID='B';
NODE_NAME     PR401 1
 '@T6G_MB_LIB.T6G(SCH_1):PAGE201_I35@PURE_QUANTA.Q_RES(CHIPS)':
 'A': CDS_PINID='A';
NET_NAME
'PVDD33_S5_EN'
 '@T6G_MB_LIB.T6G(SCH_1):PVDD33_S5_EN':
 C_SIGNAL='@t6g_mb_lib.t6g(sch_1):pvdd33_s5_en';
NODE_NAME     R224 1
 '@T6G_MB_LIB.T6G(SCH_1):PAGE80_I36@PURE_QUANTA.Q_RES(CHIPS)':
 'A': CDS_PINID='A';
NODE_NAME     C348 1
 '@T6G_MB_LIB.T6G(SCH_1):PAGE167_I5@PURE_QUANTA.Q_CAP(CHIPS)':
 'A': CDS_PINID='A';
NODE_NAME     PU55 8
 '@T6G_MB_LIB.T6G(SCH_1):PAGE167_I41@PURE_QUANTA.MPQ8633AGLEC807Z(CHIPS)':
 'EN': CDS_PINID='EN';
NET_NAME
'PVDDCR_CPU0_P0'
 '@T6G_MB_LIB.T6G(SCH_1):PVDDCR_CPU0_P0':
 C_SIGNAL='@t6g_mb_lib.t6g(sch_1):pvddcr_cpu0_p0',
 CDS_GLOBAL_NET='TRUE';
NODE_NAME     U25 AB23
 '@T6G_MB_LIB.T6G(SCH_1):PAGE30_I42@PURE_QUANTA.GENOA_SP5(CHIPS)':
 'VDDCR_CPU0_AB23': CDS_PINID='VDDCR_CPU0_AB23';
NODE_NAME     U25 AB24
 '@T6G_MB_LIB.T6G(SCH_1):PAGE30_I42@PURE_QUANTA.GENOA_SP5(CHIPS)':
 'VDDCR_CPU0_AB24': CDS_PINID='VDDCR_CPU0_AB24';
NODE_NAME     U25 AB26
 '@T6G_MB_LIB.T6G(SCH_1):PAGE30_I42@PURE_QUANTA.GENOA_SP5(CHIPS)':
 'VDDCR_CPU0_AB26': CDS_PINID='VDDCR_CPU0_AB26';
NODE_NAME     U25 AB27
 '@T6G_MB_LIB.T6G(SCH_1):PAGE30_I42@PURE_QUANTA.GENOA_SP5(CHIPS)':
 'VDDCR_CPU0_AB27': CDS_PINID='VDDCR_CPU0_AB27';
NODE_NAME     U25 AB29
 '@T6G_MB_LIB.T6G(SCH_1):PAGE30_I42@PURE_QUANTA.GENOA_SP5(CHIPS)':
 'VDDCR_CPU0_AB29': CDS_PINID='VDDCR_CPU0_AB29';
NODE_NAME     U25 AB30
 '@T6G_MB_LIB.T6G(SCH_1):PAGE30_I42@PURE_QUANTA.GENOA_SP5(CHIPS)':
 'VDDCR_CPU0_AB30': CDS_PINID='VDDCR_CPU0_AB30';
NODE_NAME     U25 AB32
 '@T6G_MB_LIB.T6G(SCH_1):PAGE30_I42@PURE_QUANTA.GENOA_SP5(CHIPS)':
 'VDDCR_CPU0_AB32': CDS_PINID='VDDCR_CPU0_AB32';
NODE_NAME     U25 AB33
 '@T6G_MB_LIB.T6G(SCH_1):PAGE30_I42@PURE_QUANTA.GENOA_SP5(CHIPS)':
 'VDDCR_CPU0_AB33': CDS_PINID='VDDCR_CPU0_AB33';
NODE_NAME     U25 AB43
 '@T6G_MB_LIB.T6G(SCH_1):PAGE30_I42@PURE_QUANTA.GENOA_SP5(CHIPS)':
 'VDDCR_CPU0_AB43': CDS_PINID='VDDCR_CPU0_AB43';
NODE_NAME     U25 AB44
 '@T6G_MB_LIB.T6G(SCH_1):PAGE30_I42@PURE_QUANTA.GENOA_SP5(CHIPS)':
 'VDDCR_CPU0_AB44': CDS_PINID='VDDCR_CPU0_AB44';
NODE_NAME     U25 AB46
 '@T6G_MB_LIB.T6G(SCH_1):PAGE30_I42@PURE_QUANTA.GENOA_SP5(CHIPS)':
 'VDDCR_CPU0_AB46': CDS_PINID='VDDCR_CPU0_AB46';
NODE_NAME     U25 AB47
 '@T6G_MB_LIB.T6G(SCH_1):PAGE30_I42@PURE_QUANTA.GENOA_SP5(CHIPS)':
 'VDDCR_CPU0_AB47': CDS_PINID='VDDCR_CPU0_AB47';
NODE_NAME     U25 AB49
 '@T6G_MB_LIB.T6G(SCH_1):PAGE30_I42@PURE_QUANTA.GENOA_SP5(CHIPS)':
 'VDDCR_CPU0_AB49': CDS_PINID='VDDCR_CPU0_AB49';
NODE_NAME     U25 AB50
 '@T6G_MB_LIB.T6G(SCH_1):PAGE30_I42@PURE_QUANTA.GENOA_SP5(CHIPS)':
 'VDDCR_CPU0_AB50': CDS_PINID='VDDCR_CPU0_AB50';
NODE_NAME     U25 AB52
 '@T6G_MB_LIB.T6G(SCH_1):PAGE30_I42@PURE_QUANTA.GENOA_SP5(CHIPS)':
 'VDDCR_CPU0_AB52': CDS_PINID='VDDCR_CPU0_AB52';
NODE_NAME     U25 AB53
 '@T6G_MB_LIB.T6G(SCH_1):PAGE30_I42@PURE_QUANTA.GENOA_SP5(CHIPS)':
 'VDDCR_CPU0_AB53': CDS_PINID='VDDCR_CPU0_AB53';
NODE_NAME     U25 AC35
 '@T6G_MB_LIB.T6G(SCH_1):PAGE30_I42@PURE_QUANTA.GENOA_SP5(CHIPS)':
 'VDDCR_CPU0_AC35': CDS_PINID='VDDCR_CPU0_AC35';
NODE_NAME     U25 AC36
 '@T6G_MB_LIB.T6G(SCH_1):PAGE30_I42@PURE_QUANTA.GENOA_SP5(CHIPS)':
 'VDDCR_CPU0_AC36': CDS_PINID='VDDCR_CPU0_AC36';
NODE_NAME     U25 AC40
 '@T6G_MB_LIB.T6G(SCH_1):PAGE30_I42@PURE_QUANTA.GENOA_SP5(CHIPS)':
 'VDDCR_CPU0_AC40': CDS_PINID='VDDCR_CPU0_AC40';
NODE_NAME     U25 AC41
 '@T6G_MB_LIB.T6G(SCH_1):PAGE30_I42@PURE_QUANTA.GENOA_SP5(CHIPS)':
 'VDDCR_CPU0_AC41': CDS_PINID='VDDCR_CPU0_AC41';
NODE_NAME     U25 AF23
 '@T6G_MB_LIB.T6G(SCH_1):PAGE30_I42@PURE_QUANTA.GENOA_SP5(CHIPS)':
 'VDDCR_CPU0_AF23': CDS_PINID='VDDCR_CPU0_AF23';
NODE_NAME     U25 AF24
 '@T6G_MB_LIB.T6G(SCH_1):PAGE30_I42@PURE_QUANTA.GENOA_SP5(CHIPS)':
 'VDDCR_CPU0_AF24': CDS_PINID='VDDCR_CPU0_AF24';
NODE_NAME     U25 AF26
 '@T6G_MB_LIB.T6G(SCH_1):PAGE30_I42@PURE_QUANTA.GENOA_SP5(CHIPS)':
 'VDDCR_CPU0_AF26': CDS_PINID='VDDCR_CPU0_AF26';
NODE_NAME     U25 AF27
 '@T6G_MB_LIB.T6G(SCH_1):PAGE30_I42@PURE_QUANTA.GENOA_SP5(CHIPS)':
 'VDDCR_CPU0_AF27': CDS_PINID='VDDCR_CPU0_AF27';
NODE_NAME     U25 AF29
 '@T6G_MB_LIB.T6G(SCH_1):PAGE30_I42@PURE_QUANTA.GENOA_SP5(CHIPS)':
 'VDDCR_CPU0_AF29': CDS_PINID='VDDCR_CPU0_AF29';
NODE_NAME     U25 AF30
 '@T6G_MB_LIB.T6G(SCH_1):PAGE30_I42@PURE_QUANTA.GENOA_SP5(CHIPS)':
 'VDDCR_CPU0_AF30': CDS_PINID='VDDCR_CPU0_AF30';
NODE_NAME     U25 AF32
 '@T6G_MB_LIB.T6G(SCH_1):PAGE30_I42@PURE_QUANTA.GENOA_SP5(CHIPS)':
 'VDDCR_CPU0_AF32': CDS_PINID='VDDCR_CPU0_AF32';
NODE_NAME     U25 AF33
 '@T6G_MB_LIB.T6G(SCH_1):PAGE30_I42@PURE_QUANTA.GENOA_SP5(CHIPS)':
 'VDDCR_CPU0_AF33': CDS_PINID='VDDCR_CPU0_AF33';
NODE_NAME     U25 AF43
 '@T6G_MB_LIB.T6G(SCH_1):PAGE30_I42@PURE_QUANTA.GENOA_SP5(CHIPS)':
 'VDDCR_CPU0_AF43': CDS_PINID='VDDCR_CPU0_AF43';
NODE_NAME     U25 AF44
 '@T6G_MB_LIB.T6G(SCH_1):PAGE30_I42@PURE_QUANTA.GENOA_SP5(CHIPS)':
 'VDDCR_CPU0_AF44': CDS_PINID='VDDCR_CPU0_AF44';
NODE_NAME     U25 AF46
 '@T6G_MB_LIB.T6G(SCH_1):PAGE30_I42@PURE_QUANTA.GENOA_SP5(CHIPS)':
 'VDDCR_CPU0_AF46': CDS_PINID='VDDCR_CPU0_AF46';
NODE_NAME     U25 AF47
 '@T6G_MB_LIB.T6G(SCH_1):PAGE30_I42@PURE_QUANTA.GENOA_SP5(CHIPS)':
 'VDDCR_CPU0_AF47': CDS_PINID='VDDCR_CPU0_AF47';
NODE_NAME     U25 AF49
 '@T6G_MB_LIB.T6G(SCH_1):PAGE30_I42@PURE_QUANTA.GENOA_SP5(CHIPS)':
 'VDDCR_CPU0_AF49': CDS_PINID='VDDCR_CPU0_AF49';
NODE_NAME     U25 AF50
 '@T6G_MB_LIB.T6G(SCH_1):PAGE30_I42@PURE_QUANTA.GENOA_SP5(CHIPS)':
 'VDDCR_CPU0_AF50': CDS_PINID='VDDCR_CPU0_AF50';
NODE_NAME     U25 AF52
 '@T6G_MB_LIB.T6G(SCH_1):PAGE30_I42@PURE_QUANTA.GENOA_SP5(CHIPS)':
 'VDDCR_CPU0_AF52': CDS_PINID='VDDCR_CPU0_AF52';
NODE_NAME     U25 AF53
 '@T6G_MB_LIB.T6G(SCH_1):PAGE30_I42@PURE_QUANTA.GENOA_SP5(CHIPS)':
 'VDDCR_CPU0_AF53': CDS_PINID='VDDCR_CPU0_AF53';
NODE_NAME     U25 AG35
 '@T6G_MB_LIB.T6G(SCH_1):PAGE30_I42@PURE_QUANTA.GENOA_SP5(CHIPS)':
 'VDDCR_CPU0_AG35': CDS_PINID='VDDCR_CPU0_AG35';
NODE_NAME     U25 AG36
 '@T6G_MB_LIB.T6G(SCH_1):PAGE30_I42@PURE_QUANTA.GENOA_SP5(CHIPS)':
 'VDDCR_CPU0_AG36': CDS_PINID='VDDCR_CPU0_AG36';
NODE_NAME     U25 AG40
 '@T6G_MB_LIB.T6G(SCH_1):PAGE30_I42@PURE_QUANTA.GENOA_SP5(CHIPS)':
 'VDDCR_CPU0_AG40': CDS_PINID='VDDCR_CPU0_AG40';
NODE_NAME     U25 AG41
 '@T6G_MB_LIB.T6G(SCH_1):PAGE30_I42@PURE_QUANTA.GENOA_SP5(CHIPS)':
 'VDDCR_CPU0_AG41': CDS_PINID='VDDCR_CPU0_AG41';
NODE_NAME     U25 AK23
 '@T6G_MB_LIB.T6G(SCH_1):PAGE30_I42@PURE_QUANTA.GENOA_SP5(CHIPS)':
 'VDDCR_CPU0_AK23': CDS_PINID='VDDCR_CPU0_AK23';
NODE_NAME     U25 AK24
 '@T6G_MB_LIB.T6G(SCH_1):PAGE30_I42@PURE_QUANTA.GENOA_SP5(CHIPS)':
 'VDDCR_CPU0_AK24': CDS_PINID='VDDCR_CPU0_AK24';
NODE_NAME     U25 AK26
 '@T6G_MB_LIB.T6G(SCH_1):PAGE30_I42@PURE_QUANTA.GENOA_SP5(CHIPS)':
 'VDDCR_CPU0_AK26': CDS_PINID='VDDCR_CPU0_AK26';
NODE_NAME     U25 AK27
 '@T6G_MB_LIB.T6G(SCH_1):PAGE30_I42@PURE_QUANTA.GENOA_SP5(CHIPS)':
 'VDDCR_CPU0_AK27': CDS_PINID='VDDCR_CPU0_AK27';
NODE_NAME     U25 AK29
 '@T6G_MB_LIB.T6G(SCH_1):PAGE30_I42@PURE_QUANTA.GENOA_SP5(CHIPS)':
 'VDDCR_CPU0_AK29': CDS_PINID='VDDCR_CPU0_AK29';
NODE_NAME     U25 AK30
 '@T6G_MB_LIB.T6G(SCH_1):PAGE30_I42@PURE_QUANTA.GENOA_SP5(CHIPS)':
 'VDDCR_CPU0_AK30': CDS_PINID='VDDCR_CPU0_AK30';
NODE_NAME     U25 AK32
 '@T6G_MB_LIB.T6G(SCH_1):PAGE30_I42@PURE_QUANTA.GENOA_SP5(CHIPS)':
 'VDDCR_CPU0_AK32': CDS_PINID='VDDCR_CPU0_AK32';
NODE_NAME     U25 AK33
 '@T6G_MB_LIB.T6G(SCH_1):PAGE30_I42@PURE_QUANTA.GENOA_SP5(CHIPS)':
 'VDDCR_CPU0_AK33': CDS_PINID='VDDCR_CPU0_AK33';
NODE_NAME     U25 AK43
 '@T6G_MB_LIB.T6G(SCH_1):PAGE30_I42@PURE_QUANTA.GENOA_SP5(CHIPS)':
 'VDDCR_CPU0_AK43': CDS_PINID='VDDCR_CPU0_AK43';
NODE_NAME     U25 AK44
 '@T6G_MB_LIB.T6G(SCH_1):PAGE30_I42@PURE_QUANTA.GENOA_SP5(CHIPS)':
 'VDDCR_CPU0_AK44': CDS_PINID='VDDCR_CPU0_AK44';
NODE_NAME     U25 AK46
 '@T6G_MB_LIB.T6G(SCH_1):PAGE30_I42@PURE_QUANTA.GENOA_SP5(CHIPS)':
 'VDDCR_CPU0_AK46': CDS_PINID='VDDCR_CPU0_AK46';
NODE_NAME     U25 AK47
 '@T6G_MB_LIB.T6G(SCH_1):PAGE30_I42@PURE_QUANTA.GENOA_SP5(CHIPS)':
 'VDDCR_CPU0_AK47': CDS_PINID='VDDCR_CPU0_AK47';
NODE_NAME     U25 AK49
 '@T6G_MB_LIB.T6G(SCH_1):PAGE30_I42@PURE_QUANTA.GENOA_SP5(CHIPS)':
 'VDDCR_CPU0_AK49': CDS_PINID='VDDCR_CPU0_AK49';
NODE_NAME     U25 AK50
 '@T6G_MB_LIB.T6G(SCH_1):PAGE30_I42@PURE_QUANTA.GENOA_SP5(CHIPS)':
 'VDDCR_CPU0_AK50': CDS_PINID='VDDCR_CPU0_AK50';
NODE_NAME     U25 AK52
 '@T6G_MB_LIB.T6G(SCH_1):PAGE30_I42@PURE_QUANTA.GENOA_SP5(CHIPS)':
 'VDDCR_CPU0_AK52': CDS_PINID='VDDCR_CPU0_AK52';
NODE_NAME     U25 AK53
 '@T6G_MB_LIB.T6G(SCH_1):PAGE30_I42@PURE_QUANTA.GENOA_SP5(CHIPS)':
 'VDDCR_CPU0_AK53': CDS_PINID='VDDCR_CPU0_AK53';
NODE_NAME     U25 AL35
 '@T6G_MB_LIB.T6G(SCH_1):PAGE30_I42@PURE_QUANTA.GENOA_SP5(CHIPS)':
 'VDDCR_CPU0_AL35': CDS_PINID='VDDCR_CPU0_AL35';
NODE_NAME     U25 AL36
 '@T6G_MB_LIB.T6G(SCH_1):PAGE30_I42@PURE_QUANTA.GENOA_SP5(CHIPS)':
 'VDDCR_CPU0_AL36': CDS_PINID='VDDCR_CPU0_AL36';
NODE_NAME     U25 AL40
 '@T6G_MB_LIB.T6G(SCH_1):PAGE30_I42@PURE_QUANTA.GENOA_SP5(CHIPS)':
 'VDDCR_CPU0_AL40': CDS_PINID='VDDCR_CPU0_AL40';
NODE_NAME     U25 AL41
 '@T6G_MB_LIB.T6G(SCH_1):PAGE30_I42@PURE_QUANTA.GENOA_SP5(CHIPS)':
 'VDDCR_CPU0_AL41': CDS_PINID='VDDCR_CPU0_AL41';
NODE_NAME     U25 AP23
 '@T6G_MB_LIB.T6G(SCH_1):PAGE30_I42@PURE_QUANTA.GENOA_SP5(CHIPS)':
 'VDDCR_CPU0_AP23': CDS_PINID='VDDCR_CPU0_AP23';
NODE_NAME     U25 AP24
 '@T6G_MB_LIB.T6G(SCH_1):PAGE30_I42@PURE_QUANTA.GENOA_SP5(CHIPS)':
 'VDDCR_CPU0_AP24': CDS_PINID='VDDCR_CPU0_AP24';
NODE_NAME     U25 AP26
 '@T6G_MB_LIB.T6G(SCH_1):PAGE30_I42@PURE_QUANTA.GENOA_SP5(CHIPS)':
 'VDDCR_CPU0_AP26': CDS_PINID='VDDCR_CPU0_AP26';
NODE_NAME     U25 AP27
 '@T6G_MB_LIB.T6G(SCH_1):PAGE30_I42@PURE_QUANTA.GENOA_SP5(CHIPS)':
 'VDDCR_CPU0_AP27': CDS_PINID='VDDCR_CPU0_AP27';
NODE_NAME     U25 AP29
 '@T6G_MB_LIB.T6G(SCH_1):PAGE30_I42@PURE_QUANTA.GENOA_SP5(CHIPS)':
 'VDDCR_CPU0_AP29': CDS_PINID='VDDCR_CPU0_AP29';
NODE_NAME     U25 AP30
 '@T6G_MB_LIB.T6G(SCH_1):PAGE30_I42@PURE_QUANTA.GENOA_SP5(CHIPS)':
 'VDDCR_CPU0_AP30': CDS_PINID='VDDCR_CPU0_AP30';
NODE_NAME     U25 AP32
 '@T6G_MB_LIB.T6G(SCH_1):PAGE30_I42@PURE_QUANTA.GENOA_SP5(CHIPS)':
 'VDDCR_CPU0_AP32': CDS_PINID='VDDCR_CPU0_AP32';
NODE_NAME     U25 AP33
 '@T6G_MB_LIB.T6G(SCH_1):PAGE30_I42@PURE_QUANTA.GENOA_SP5(CHIPS)':
 'VDDCR_CPU0_AP33': CDS_PINID='VDDCR_CPU0_AP33';
NODE_NAME     U25 AP43
 '@T6G_MB_LIB.T6G(SCH_1):PAGE30_I42@PURE_QUANTA.GENOA_SP5(CHIPS)':
 'VDDCR_CPU0_AP43': CDS_PINID='VDDCR_CPU0_AP43';
NODE_NAME     U25 AP44
 '@T6G_MB_LIB.T6G(SCH_1):PAGE30_I42@PURE_QUANTA.GENOA_SP5(CHIPS)':
 'VDDCR_CPU0_AP44': CDS_PINID='VDDCR_CPU0_AP44';
NODE_NAME     U25 AP46
 '@T6G_MB_LIB.T6G(SCH_1):PAGE30_I42@PURE_QUANTA.GENOA_SP5(CHIPS)':
 'VDDCR_CPU0_AP46': CDS_PINID='VDDCR_CPU0_AP46';
NODE_NAME     U25 AP47
 '@T6G_MB_LIB.T6G(SCH_1):PAGE30_I42@PURE_QUANTA.GENOA_SP5(CHIPS)':
 'VDDCR_CPU0_AP47': CDS_PINID='VDDCR_CPU0_AP47';
NODE_NAME     U25 AP49
 '@T6G_MB_LIB.T6G(SCH_1):PAGE30_I42@PURE_QUANTA.GENOA_SP5(CHIPS)':
 'VDDCR_CPU0_AP49': CDS_PINID='VDDCR_CPU0_AP49';
NODE_NAME     U25 AP50
 '@T6G_MB_LIB.T6G(SCH_1):PAGE30_I42@PURE_QUANTA.GENOA_SP5(CHIPS)':
 'VDDCR_CPU0_AP50': CDS_PINID='VDDCR_CPU0_AP50';
NODE_NAME     U25 AP52
 '@T6G_MB_LIB.T6G(SCH_1):PAGE30_I42@PURE_QUANTA.GENOA_SP5(CHIPS)':
 'VDDCR_CPU0_AP52': CDS_PINID='VDDCR_CPU0_AP52';
NODE_NAME     U25 AP53
 '@T6G_MB_LIB.T6G(SCH_1):PAGE30_I42@PURE_QUANTA.GENOA_SP5(CHIPS)':
 'VDDCR_CPU0_AP53': CDS_PINID='VDDCR_CPU0_AP53';
NODE_NAME     U25 AR23
 '@T6G_MB_LIB.T6G(SCH_1):PAGE30_I42@PURE_QUANTA.GENOA_SP5(CHIPS)':
 'VDDCR_CPU0_AR23': CDS_PINID='VDDCR_CPU0_AR23';
NODE_NAME     U25 AR25
 '@T6G_MB_LIB.T6G(SCH_1):PAGE30_I42@PURE_QUANTA.GENOA_SP5(CHIPS)':
 'VDDCR_CPU0_AR25': CDS_PINID='VDDCR_CPU0_AR25';
NODE_NAME     U25 AR27
 '@T6G_MB_LIB.T6G(SCH_1):PAGE30_I42@PURE_QUANTA.GENOA_SP5(CHIPS)':
 'VDDCR_CPU0_AR27': CDS_PINID='VDDCR_CPU0_AR27';
NODE_NAME     U25 AR29
 '@T6G_MB_LIB.T6G(SCH_1):PAGE30_I42@PURE_QUANTA.GENOA_SP5(CHIPS)':
 'VDDCR_CPU0_AR29': CDS_PINID='VDDCR_CPU0_AR29';
NODE_NAME     U25 AR31
 '@T6G_MB_LIB.T6G(SCH_1):PAGE30_I42@PURE_QUANTA.GENOA_SP5(CHIPS)':
 'VDDCR_CPU0_AR31': CDS_PINID='VDDCR_CPU0_AR31';
NODE_NAME     U25 AR33
 '@T6G_MB_LIB.T6G(SCH_1):PAGE30_I42@PURE_QUANTA.GENOA_SP5(CHIPS)':
 'VDDCR_CPU0_AR33': CDS_PINID='VDDCR_CPU0_AR33';
NODE_NAME     U25 AR35
 '@T6G_MB_LIB.T6G(SCH_1):PAGE30_I42@PURE_QUANTA.GENOA_SP5(CHIPS)':
 'VDDCR_CPU0_AR35': CDS_PINID='VDDCR_CPU0_AR35';
NODE_NAME     U25 AR40
 '@T6G_MB_LIB.T6G(SCH_1):PAGE30_I42@PURE_QUANTA.GENOA_SP5(CHIPS)':
 'VDDCR_CPU0_AR40': CDS_PINID='VDDCR_CPU0_AR40';
NODE_NAME     U25 AR42
 '@T6G_MB_LIB.T6G(SCH_1):PAGE30_I42@PURE_QUANTA.GENOA_SP5(CHIPS)':
 'VDDCR_CPU0_AR42': CDS_PINID='VDDCR_CPU0_AR42';
NODE_NAME     U25 AR44
 '@T6G_MB_LIB.T6G(SCH_1):PAGE30_I42@PURE_QUANTA.GENOA_SP5(CHIPS)':
 'VDDCR_CPU0_AR44': CDS_PINID='VDDCR_CPU0_AR44';
NODE_NAME     U25 AR46
 '@T6G_MB_LIB.T6G(SCH_1):PAGE30_I42@PURE_QUANTA.GENOA_SP5(CHIPS)':
 'VDDCR_CPU0_AR46': CDS_PINID='VDDCR_CPU0_AR46';
NODE_NAME     U25 AR48
 '@T6G_MB_LIB.T6G(SCH_1):PAGE30_I42@PURE_QUANTA.GENOA_SP5(CHIPS)':
 'VDDCR_CPU0_AR48': CDS_PINID='VDDCR_CPU0_AR48';
NODE_NAME     U25 AR50
 '@T6G_MB_LIB.T6G(SCH_1):PAGE30_I42@PURE_QUANTA.GENOA_SP5(CHIPS)':
 'VDDCR_CPU0_AR50': CDS_PINID='VDDCR_CPU0_AR50';
NODE_NAME     U25 AT24
 '@T6G_MB_LIB.T6G(SCH_1):PAGE30_I42@PURE_QUANTA.GENOA_SP5(CHIPS)':
 'VDDCR_CPU0_AT24': CDS_PINID='VDDCR_CPU0_AT24';
NODE_NAME     U25 AT26
 '@T6G_MB_LIB.T6G(SCH_1):PAGE30_I42@PURE_QUANTA.GENOA_SP5(CHIPS)':
 'VDDCR_CPU0_AT26': CDS_PINID='VDDCR_CPU0_AT26';
NODE_NAME     U25 AT28
 '@T6G_MB_LIB.T6G(SCH_1):PAGE30_I42@PURE_QUANTA.GENOA_SP5(CHIPS)':
 'VDDCR_CPU0_AT28': CDS_PINID='VDDCR_CPU0_AT28';
NODE_NAME     U25 AT30
 '@T6G_MB_LIB.T6G(SCH_1):PAGE30_I42@PURE_QUANTA.GENOA_SP5(CHIPS)':
 'VDDCR_CPU0_AT30': CDS_PINID='VDDCR_CPU0_AT30';
NODE_NAME     U25 AT32
 '@T6G_MB_LIB.T6G(SCH_1):PAGE30_I42@PURE_QUANTA.GENOA_SP5(CHIPS)':
 'VDDCR_CPU0_AT32': CDS_PINID='VDDCR_CPU0_AT32';
NODE_NAME     U25 AT34
 '@T6G_MB_LIB.T6G(SCH_1):PAGE30_I42@PURE_QUANTA.GENOA_SP5(CHIPS)':
 'VDDCR_CPU0_AT34': CDS_PINID='VDDCR_CPU0_AT34';
NODE_NAME     U25 AT36
 '@T6G_MB_LIB.T6G(SCH_1):PAGE30_I42@PURE_QUANTA.GENOA_SP5(CHIPS)':
 'VDDCR_CPU0_AT36': CDS_PINID='VDDCR_CPU0_AT36';
NODE_NAME     U25 AT39
 '@T6G_MB_LIB.T6G(SCH_1):PAGE30_I42@PURE_QUANTA.GENOA_SP5(CHIPS)':
 'VDDCR_CPU0_AT39': CDS_PINID='VDDCR_CPU0_AT39';
NODE_NAME     U25 AT41
 '@T6G_MB_LIB.T6G(SCH_1):PAGE30_I42@PURE_QUANTA.GENOA_SP5(CHIPS)':
 'VDDCR_CPU0_AT41': CDS_PINID='VDDCR_CPU0_AT41';
NODE_NAME     U25 AT43
 '@T6G_MB_LIB.T6G(SCH_1):PAGE30_I42@PURE_QUANTA.GENOA_SP5(CHIPS)':
 'VDDCR_CPU0_AT43': CDS_PINID='VDDCR_CPU0_AT43';
NODE_NAME     U25 AT45
 '@T6G_MB_LIB.T6G(SCH_1):PAGE30_I42@PURE_QUANTA.GENOA_SP5(CHIPS)':
 'VDDCR_CPU0_AT45': CDS_PINID='VDDCR_CPU0_AT45';
NODE_NAME     U25 AT47
 '@T6G_MB_LIB.T6G(SCH_1):PAGE30_I42@PURE_QUANTA.GENOA_SP5(CHIPS)':
 'VDDCR_CPU0_AT47': CDS_PINID='VDDCR_CPU0_AT47';
NODE_NAME     U25 AT49
 '@T6G_MB_LIB.T6G(SCH_1):PAGE30_I42@PURE_QUANTA.GENOA_SP5(CHIPS)':
 'VDDCR_CPU0_AT49': CDS_PINID='VDDCR_CPU0_AT49';
NODE_NAME     U25 AU25
 '@T6G_MB_LIB.T6G(SCH_1):PAGE30_I42@PURE_QUANTA.GENOA_SP5(CHIPS)':
 'VDDCR_CPU0_AU25': CDS_PINID='VDDCR_CPU0_AU25';
NODE_NAME     U25 AU29
 '@T6G_MB_LIB.T6G(SCH_1):PAGE30_I42@PURE_QUANTA.GENOA_SP5(CHIPS)':
 'VDDCR_CPU0_AU29': CDS_PINID='VDDCR_CPU0_AU29';
NODE_NAME     U25 AU33
 '@T6G_MB_LIB.T6G(SCH_1):PAGE30_I42@PURE_QUANTA.GENOA_SP5(CHIPS)':
 'VDDCR_CPU0_AU33': CDS_PINID='VDDCR_CPU0_AU33';
NODE_NAME     U25 AU42
 '@T6G_MB_LIB.T6G(SCH_1):PAGE30_I42@PURE_QUANTA.GENOA_SP5(CHIPS)':
 'VDDCR_CPU0_AU42': CDS_PINID='VDDCR_CPU0_AU42';
NODE_NAME     U25 AU44
 '@T6G_MB_LIB.T6G(SCH_1):PAGE30_I42@PURE_QUANTA.GENOA_SP5(CHIPS)':
 'VDDCR_CPU0_AU44': CDS_PINID='VDDCR_CPU0_AU44';
NODE_NAME     U25 AU46
 '@T6G_MB_LIB.T6G(SCH_1):PAGE30_I42@PURE_QUANTA.GENOA_SP5(CHIPS)':
 'VDDCR_CPU0_AU46': CDS_PINID='VDDCR_CPU0_AU46';
NODE_NAME     U25 AU48
 '@T6G_MB_LIB.T6G(SCH_1):PAGE30_I42@PURE_QUANTA.GENOA_SP5(CHIPS)':
 'VDDCR_CPU0_AU48': CDS_PINID='VDDCR_CPU0_AU48';
NODE_NAME     U25 B19
 '@T6G_MB_LIB.T6G(SCH_1):PAGE30_I42@PURE_QUANTA.GENOA_SP5(CHIPS)':
 'VDDCR_CPU0_B19': CDS_PINID='VDDCR_CPU0_B19';
NODE_NAME     U25 B20
 '@T6G_MB_LIB.T6G(SCH_1):PAGE30_I42@PURE_QUANTA.GENOA_SP5(CHIPS)':
 'VDDCR_CPU0_B20': CDS_PINID='VDDCR_CPU0_B20';
NODE_NAME     U25 B22
 '@T6G_MB_LIB.T6G(SCH_1):PAGE30_I42@PURE_QUANTA.GENOA_SP5(CHIPS)':
 'VDDCR_CPU0_B22': CDS_PINID='VDDCR_CPU0_B22';
NODE_NAME     U25 B23
 '@T6G_MB_LIB.T6G(SCH_1):PAGE30_I42@PURE_QUANTA.GENOA_SP5(CHIPS)':
 'VDDCR_CPU0_B23': CDS_PINID='VDDCR_CPU0_B23';
NODE_NAME     U25 B25
 '@T6G_MB_LIB.T6G(SCH_1):PAGE30_I42@PURE_QUANTA.GENOA_SP5(CHIPS)':
 'VDDCR_CPU0_B25': CDS_PINID='VDDCR_CPU0_B25';
NODE_NAME     U25 B26
 '@T6G_MB_LIB.T6G(SCH_1):PAGE30_I42@PURE_QUANTA.GENOA_SP5(CHIPS)':
 'VDDCR_CPU0_B26': CDS_PINID='VDDCR_CPU0_B26';
NODE_NAME     U25 B28
 '@T6G_MB_LIB.T6G(SCH_1):PAGE30_I42@PURE_QUANTA.GENOA_SP5(CHIPS)':
 'VDDCR_CPU0_B28': CDS_PINID='VDDCR_CPU0_B28';
NODE_NAME     U25 B29
 '@T6G_MB_LIB.T6G(SCH_1):PAGE30_I42@PURE_QUANTA.GENOA_SP5(CHIPS)':
 'VDDCR_CPU0_B29': CDS_PINID='VDDCR_CPU0_B29';
NODE_NAME     U25 B31
 '@T6G_MB_LIB.T6G(SCH_1):PAGE30_I42@PURE_QUANTA.GENOA_SP5(CHIPS)':
 'VDDCR_CPU0_B31': CDS_PINID='VDDCR_CPU0_B31';
NODE_NAME     U25 B32
 '@T6G_MB_LIB.T6G(SCH_1):PAGE30_I42@PURE_QUANTA.GENOA_SP5(CHIPS)':
 'VDDCR_CPU0_B32': CDS_PINID='VDDCR_CPU0_B32';
NODE_NAME     U25 B34
 '@T6G_MB_LIB.T6G(SCH_1):PAGE30_I42@PURE_QUANTA.GENOA_SP5(CHIPS)':
 'VDDCR_CPU0_B34': CDS_PINID='VDDCR_CPU0_B34';
NODE_NAME     U25 B35
 '@T6G_MB_LIB.T6G(SCH_1):PAGE30_I42@PURE_QUANTA.GENOA_SP5(CHIPS)':
 'VDDCR_CPU0_B35': CDS_PINID='VDDCR_CPU0_B35';
NODE_NAME     U25 B41
 '@T6G_MB_LIB.T6G(SCH_1):PAGE30_I42@PURE_QUANTA.GENOA_SP5(CHIPS)':
 'VDDCR_CPU0_B41': CDS_PINID='VDDCR_CPU0_B41';
NODE_NAME     U25 B42
 '@T6G_MB_LIB.T6G(SCH_1):PAGE30_I42@PURE_QUANTA.GENOA_SP5(CHIPS)':
 'VDDCR_CPU0_B42': CDS_PINID='VDDCR_CPU0_B42';
NODE_NAME     U25 B44
 '@T6G_MB_LIB.T6G(SCH_1):PAGE30_I42@PURE_QUANTA.GENOA_SP5(CHIPS)':
 'VDDCR_CPU0_B44': CDS_PINID='VDDCR_CPU0_B44';
NODE_NAME     U25 B45
 '@T6G_MB_LIB.T6G(SCH_1):PAGE30_I42@PURE_QUANTA.GENOA_SP5(CHIPS)':
 'VDDCR_CPU0_B45': CDS_PINID='VDDCR_CPU0_B45';
NODE_NAME     U25 B47
 '@T6G_MB_LIB.T6G(SCH_1):PAGE30_I42@PURE_QUANTA.GENOA_SP5(CHIPS)':
 'VDDCR_CPU0_B47': CDS_PINID='VDDCR_CPU0_B47';
NODE_NAME     U25 B48
 '@T6G_MB_LIB.T6G(SCH_1):PAGE30_I42@PURE_QUANTA.GENOA_SP5(CHIPS)':
 'VDDCR_CPU0_B48': CDS_PINID='VDDCR_CPU0_B48';
NODE_NAME     U25 B50
 '@T6G_MB_LIB.T6G(SCH_1):PAGE30_I42@PURE_QUANTA.GENOA_SP5(CHIPS)':
 'VDDCR_CPU0_B50': CDS_PINID='VDDCR_CPU0_B50';
NODE_NAME     U25 B51
 '@T6G_MB_LIB.T6G(SCH_1):PAGE30_I42@PURE_QUANTA.GENOA_SP5(CHIPS)':
 'VDDCR_CPU0_B51': CDS_PINID='VDDCR_CPU0_B51';
NODE_NAME     U25 B53
 '@T6G_MB_LIB.T6G(SCH_1):PAGE30_I42@PURE_QUANTA.GENOA_SP5(CHIPS)':
 'VDDCR_CPU0_B53': CDS_PINID='VDDCR_CPU0_B53';
NODE_NAME     U25 B54
 '@T6G_MB_LIB.T6G(SCH_1):PAGE30_I42@PURE_QUANTA.GENOA_SP5(CHIPS)':
 'VDDCR_CPU0_B54': CDS_PINID='VDDCR_CPU0_B54';
NODE_NAME     U25 B56
 '@T6G_MB_LIB.T6G(SCH_1):PAGE30_I42@PURE_QUANTA.GENOA_SP5(CHIPS)':
 'VDDCR_CPU0_B56': CDS_PINID='VDDCR_CPU0_B56';
NODE_NAME     U25 B57
 '@T6G_MB_LIB.T6G(SCH_1):PAGE30_I42@PURE_QUANTA.GENOA_SP5(CHIPS)':
 'VDDCR_CPU0_B57': CDS_PINID='VDDCR_CPU0_B57';
NODE_NAME     U25 C20
 '@T6G_MB_LIB.T6G(SCH_1):PAGE30_I42@PURE_QUANTA.GENOA_SP5(CHIPS)':
 'VDDCR_CPU0_C20': CDS_PINID='VDDCR_CPU0_C20';
NODE_NAME     U25 D55
 '@T6G_MB_LIB.T6G(SCH_1):PAGE30_I42@PURE_QUANTA.GENOA_SP5(CHIPS)':
 'VDDCR_CPU0_D55': CDS_PINID='VDDCR_CPU0_D55';
NODE_NAME     U25 D56
 '@T6G_MB_LIB.T6G(SCH_1):PAGE30_I42@PURE_QUANTA.GENOA_SP5(CHIPS)':
 'VDDCR_CPU0_D56': CDS_PINID='VDDCR_CPU0_D56';
NODE_NAME     U25 E22
 '@T6G_MB_LIB.T6G(SCH_1):PAGE30_I42@PURE_QUANTA.GENOA_SP5(CHIPS)':
 'VDDCR_CPU0_E22': CDS_PINID='VDDCR_CPU0_E22';
NODE_NAME     U25 E25
 '@T6G_MB_LIB.T6G(SCH_1):PAGE30_I42@PURE_QUANTA.GENOA_SP5(CHIPS)':
 'VDDCR_CPU0_E25': CDS_PINID='VDDCR_CPU0_E25';
NODE_NAME     U25 E28
 '@T6G_MB_LIB.T6G(SCH_1):PAGE30_I42@PURE_QUANTA.GENOA_SP5(CHIPS)':
 'VDDCR_CPU0_E28': CDS_PINID='VDDCR_CPU0_E28';
NODE_NAME     U25 E31
 '@T6G_MB_LIB.T6G(SCH_1):PAGE30_I42@PURE_QUANTA.GENOA_SP5(CHIPS)':
 'VDDCR_CPU0_E31': CDS_PINID='VDDCR_CPU0_E31';
NODE_NAME     U25 E34
 '@T6G_MB_LIB.T6G(SCH_1):PAGE30_I42@PURE_QUANTA.GENOA_SP5(CHIPS)':
 'VDDCR_CPU0_E34': CDS_PINID='VDDCR_CPU0_E34';
NODE_NAME     U25 E35
 '@T6G_MB_LIB.T6G(SCH_1):PAGE30_I42@PURE_QUANTA.GENOA_SP5(CHIPS)':
 'VDDCR_CPU0_E35': CDS_PINID='VDDCR_CPU0_E35';
NODE_NAME     U25 E42
 '@T6G_MB_LIB.T6G(SCH_1):PAGE30_I42@PURE_QUANTA.GENOA_SP5(CHIPS)':
 'VDDCR_CPU0_E42': CDS_PINID='VDDCR_CPU0_E42';
NODE_NAME     U25 E45
 '@T6G_MB_LIB.T6G(SCH_1):PAGE30_I42@PURE_QUANTA.GENOA_SP5(CHIPS)':
 'VDDCR_CPU0_E45': CDS_PINID='VDDCR_CPU0_E45';
NODE_NAME     U25 E48
 '@T6G_MB_LIB.T6G(SCH_1):PAGE30_I42@PURE_QUANTA.GENOA_SP5(CHIPS)':
 'VDDCR_CPU0_E48': CDS_PINID='VDDCR_CPU0_E48';
NODE_NAME     U25 E51
 '@T6G_MB_LIB.T6G(SCH_1):PAGE30_I42@PURE_QUANTA.GENOA_SP5(CHIPS)':
 'VDDCR_CPU0_E51': CDS_PINID='VDDCR_CPU0_E51';
NODE_NAME     U25 E54
 '@T6G_MB_LIB.T6G(SCH_1):PAGE30_I42@PURE_QUANTA.GENOA_SP5(CHIPS)':
 'VDDCR_CPU0_E54': CDS_PINID='VDDCR_CPU0_E54';
NODE_NAME     U25 F22
 '@T6G_MB_LIB.T6G(SCH_1):PAGE30_I42@PURE_QUANTA.GENOA_SP5(CHIPS)':
 'VDDCR_CPU0_F22': CDS_PINID='VDDCR_CPU0_F22';
NODE_NAME     U25 F25
 '@T6G_MB_LIB.T6G(SCH_1):PAGE30_I42@PURE_QUANTA.GENOA_SP5(CHIPS)':
 'VDDCR_CPU0_F25': CDS_PINID='VDDCR_CPU0_F25';
NODE_NAME     U25 F28
 '@T6G_MB_LIB.T6G(SCH_1):PAGE30_I42@PURE_QUANTA.GENOA_SP5(CHIPS)':
 'VDDCR_CPU0_F28': CDS_PINID='VDDCR_CPU0_F28';
NODE_NAME     U25 F31
 '@T6G_MB_LIB.T6G(SCH_1):PAGE30_I42@PURE_QUANTA.GENOA_SP5(CHIPS)':
 'VDDCR_CPU0_F31': CDS_PINID='VDDCR_CPU0_F31';
NODE_NAME     U25 F34
 '@T6G_MB_LIB.T6G(SCH_1):PAGE30_I42@PURE_QUANTA.GENOA_SP5(CHIPS)':
 'VDDCR_CPU0_F34': CDS_PINID='VDDCR_CPU0_F34';
NODE_NAME     U25 F42
 '@T6G_MB_LIB.T6G(SCH_1):PAGE30_I42@PURE_QUANTA.GENOA_SP5(CHIPS)':
 'VDDCR_CPU0_F42': CDS_PINID='VDDCR_CPU0_F42';
NODE_NAME     U25 F45
 '@T6G_MB_LIB.T6G(SCH_1):PAGE30_I42@PURE_QUANTA.GENOA_SP5(CHIPS)':
 'VDDCR_CPU0_F45': CDS_PINID='VDDCR_CPU0_F45';
NODE_NAME     U25 F48
 '@T6G_MB_LIB.T6G(SCH_1):PAGE30_I42@PURE_QUANTA.GENOA_SP5(CHIPS)':
 'VDDCR_CPU0_F48': CDS_PINID='VDDCR_CPU0_F48';
NODE_NAME     U25 F51
 '@T6G_MB_LIB.T6G(SCH_1):PAGE30_I42@PURE_QUANTA.GENOA_SP5(CHIPS)':
 'VDDCR_CPU0_F51': CDS_PINID='VDDCR_CPU0_F51';
NODE_NAME     U25 F54
 '@T6G_MB_LIB.T6G(SCH_1):PAGE30_I42@PURE_QUANTA.GENOA_SP5(CHIPS)':
 'VDDCR_CPU0_F54': CDS_PINID='VDDCR_CPU0_F54';
NODE_NAME     U25 G35
 '@T6G_MB_LIB.T6G(SCH_1):PAGE30_I42@PURE_QUANTA.GENOA_SP5(CHIPS)':
 'VDDCR_CPU0_G35': CDS_PINID='VDDCR_CPU0_G35';
NODE_NAME     U25 G36
 '@T6G_MB_LIB.T6G(SCH_1):PAGE30_I42@PURE_QUANTA.GENOA_SP5(CHIPS)':
 'VDDCR_CPU0_G36': CDS_PINID='VDDCR_CPU0_G36';
NODE_NAME     U25 G40
 '@T6G_MB_LIB.T6G(SCH_1):PAGE30_I42@PURE_QUANTA.GENOA_SP5(CHIPS)':
 'VDDCR_CPU0_G40': CDS_PINID='VDDCR_CPU0_G40';
NODE_NAME     U25 G41
 '@T6G_MB_LIB.T6G(SCH_1):PAGE30_I42@PURE_QUANTA.GENOA_SP5(CHIPS)':
 'VDDCR_CPU0_G41': CDS_PINID='VDDCR_CPU0_G41';
NODE_NAME     U25 H23
 '@T6G_MB_LIB.T6G(SCH_1):PAGE30_I42@PURE_QUANTA.GENOA_SP5(CHIPS)':
 'VDDCR_CPU0_H23': CDS_PINID='VDDCR_CPU0_H23';
NODE_NAME     U25 H24
 '@T6G_MB_LIB.T6G(SCH_1):PAGE30_I42@PURE_QUANTA.GENOA_SP5(CHIPS)':
 'VDDCR_CPU0_H24': CDS_PINID='VDDCR_CPU0_H24';
NODE_NAME     U25 H26
 '@T6G_MB_LIB.T6G(SCH_1):PAGE30_I42@PURE_QUANTA.GENOA_SP5(CHIPS)':
 'VDDCR_CPU0_H26': CDS_PINID='VDDCR_CPU0_H26';
NODE_NAME     U25 H27
 '@T6G_MB_LIB.T6G(SCH_1):PAGE30_I42@PURE_QUANTA.GENOA_SP5(CHIPS)':
 'VDDCR_CPU0_H27': CDS_PINID='VDDCR_CPU0_H27';
NODE_NAME     U25 H29
 '@T6G_MB_LIB.T6G(SCH_1):PAGE30_I42@PURE_QUANTA.GENOA_SP5(CHIPS)':
 'VDDCR_CPU0_H29': CDS_PINID='VDDCR_CPU0_H29';
NODE_NAME     U25 H30
 '@T6G_MB_LIB.T6G(SCH_1):PAGE30_I42@PURE_QUANTA.GENOA_SP5(CHIPS)':
 'VDDCR_CPU0_H30': CDS_PINID='VDDCR_CPU0_H30';
NODE_NAME     U25 H32
 '@T6G_MB_LIB.T6G(SCH_1):PAGE30_I42@PURE_QUANTA.GENOA_SP5(CHIPS)':
 'VDDCR_CPU0_H32': CDS_PINID='VDDCR_CPU0_H32';
NODE_NAME     U25 H33
 '@T6G_MB_LIB.T6G(SCH_1):PAGE30_I42@PURE_QUANTA.GENOA_SP5(CHIPS)':
 'VDDCR_CPU0_H33': CDS_PINID='VDDCR_CPU0_H33';
NODE_NAME     U25 H43
 '@T6G_MB_LIB.T6G(SCH_1):PAGE30_I42@PURE_QUANTA.GENOA_SP5(CHIPS)':
 'VDDCR_CPU0_H43': CDS_PINID='VDDCR_CPU0_H43';
NODE_NAME     U25 H44
 '@T6G_MB_LIB.T6G(SCH_1):PAGE30_I42@PURE_QUANTA.GENOA_SP5(CHIPS)':
 'VDDCR_CPU0_H44': CDS_PINID='VDDCR_CPU0_H44';
NODE_NAME     U25 H46
 '@T6G_MB_LIB.T6G(SCH_1):PAGE30_I42@PURE_QUANTA.GENOA_SP5(CHIPS)':
 'VDDCR_CPU0_H46': CDS_PINID='VDDCR_CPU0_H46';
NODE_NAME     U25 H47
 '@T6G_MB_LIB.T6G(SCH_1):PAGE30_I42@PURE_QUANTA.GENOA_SP5(CHIPS)':
 'VDDCR_CPU0_H47': CDS_PINID='VDDCR_CPU0_H47';
NODE_NAME     U25 H49
 '@T6G_MB_LIB.T6G(SCH_1):PAGE30_I42@PURE_QUANTA.GENOA_SP5(CHIPS)':
 'VDDCR_CPU0_H49': CDS_PINID='VDDCR_CPU0_H49';
NODE_NAME     U25 H50
 '@T6G_MB_LIB.T6G(SCH_1):PAGE30_I42@PURE_QUANTA.GENOA_SP5(CHIPS)':
 'VDDCR_CPU0_H50': CDS_PINID='VDDCR_CPU0_H50';
NODE_NAME     U25 H52
 '@T6G_MB_LIB.T6G(SCH_1):PAGE30_I42@PURE_QUANTA.GENOA_SP5(CHIPS)':
 'VDDCR_CPU0_H52': CDS_PINID='VDDCR_CPU0_H52';
NODE_NAME     U25 H53
 '@T6G_MB_LIB.T6G(SCH_1):PAGE30_I42@PURE_QUANTA.GENOA_SP5(CHIPS)':
 'VDDCR_CPU0_H53': CDS_PINID='VDDCR_CPU0_H53';
NODE_NAME     U25 J35
 '@T6G_MB_LIB.T6G(SCH_1):PAGE30_I42@PURE_QUANTA.GENOA_SP5(CHIPS)':
 'VDDCR_CPU0_J35': CDS_PINID='VDDCR_CPU0_J35';
NODE_NAME     U25 J36
 '@T6G_MB_LIB.T6G(SCH_1):PAGE30_I42@PURE_QUANTA.GENOA_SP5(CHIPS)':
 'VDDCR_CPU0_J36': CDS_PINID='VDDCR_CPU0_J36';
NODE_NAME     U25 J40
 '@T6G_MB_LIB.T6G(SCH_1):PAGE30_I42@PURE_QUANTA.GENOA_SP5(CHIPS)':
 'VDDCR_CPU0_J40': CDS_PINID='VDDCR_CPU0_J40';
NODE_NAME     U25 J41
 '@T6G_MB_LIB.T6G(SCH_1):PAGE30_I42@PURE_QUANTA.GENOA_SP5(CHIPS)':
 'VDDCR_CPU0_J41': CDS_PINID='VDDCR_CPU0_J41';
NODE_NAME     U25 M23
 '@T6G_MB_LIB.T6G(SCH_1):PAGE30_I42@PURE_QUANTA.GENOA_SP5(CHIPS)':
 'VDDCR_CPU0_M23': CDS_PINID='VDDCR_CPU0_M23';
NODE_NAME     U25 M24
 '@T6G_MB_LIB.T6G(SCH_1):PAGE30_I42@PURE_QUANTA.GENOA_SP5(CHIPS)':
 'VDDCR_CPU0_M24': CDS_PINID='VDDCR_CPU0_M24';
NODE_NAME     U25 M26
 '@T6G_MB_LIB.T6G(SCH_1):PAGE30_I42@PURE_QUANTA.GENOA_SP5(CHIPS)':
 'VDDCR_CPU0_M26': CDS_PINID='VDDCR_CPU0_M26';
NODE_NAME     U25 M27
 '@T6G_MB_LIB.T6G(SCH_1):PAGE30_I42@PURE_QUANTA.GENOA_SP5(CHIPS)':
 'VDDCR_CPU0_M27': CDS_PINID='VDDCR_CPU0_M27';
NODE_NAME     U25 M29
 '@T6G_MB_LIB.T6G(SCH_1):PAGE30_I42@PURE_QUANTA.GENOA_SP5(CHIPS)':
 'VDDCR_CPU0_M29': CDS_PINID='VDDCR_CPU0_M29';
NODE_NAME     U25 M30
 '@T6G_MB_LIB.T6G(SCH_1):PAGE30_I42@PURE_QUANTA.GENOA_SP5(CHIPS)':
 'VDDCR_CPU0_M30': CDS_PINID='VDDCR_CPU0_M30';
NODE_NAME     U25 M32
 '@T6G_MB_LIB.T6G(SCH_1):PAGE30_I42@PURE_QUANTA.GENOA_SP5(CHIPS)':
 'VDDCR_CPU0_M32': CDS_PINID='VDDCR_CPU0_M32';
NODE_NAME     U25 M33
 '@T6G_MB_LIB.T6G(SCH_1):PAGE30_I42@PURE_QUANTA.GENOA_SP5(CHIPS)':
 'VDDCR_CPU0_M33': CDS_PINID='VDDCR_CPU0_M33';
NODE_NAME     U25 M43
 '@T6G_MB_LIB.T6G(SCH_1):PAGE30_I42@PURE_QUANTA.GENOA_SP5(CHIPS)':
 'VDDCR_CPU0_M43': CDS_PINID='VDDCR_CPU0_M43';
NODE_NAME     U25 M44
 '@T6G_MB_LIB.T6G(SCH_1):PAGE30_I42@PURE_QUANTA.GENOA_SP5(CHIPS)':
 'VDDCR_CPU0_M44': CDS_PINID='VDDCR_CPU0_M44';
NODE_NAME     U25 M46
 '@T6G_MB_LIB.T6G(SCH_1):PAGE30_I42@PURE_QUANTA.GENOA_SP5(CHIPS)':
 'VDDCR_CPU0_M46': CDS_PINID='VDDCR_CPU0_M46';
NODE_NAME     U25 M47
 '@T6G_MB_LIB.T6G(SCH_1):PAGE30_I42@PURE_QUANTA.GENOA_SP5(CHIPS)':
 'VDDCR_CPU0_M47': CDS_PINID='VDDCR_CPU0_M47';
NODE_NAME     U25 M49
 '@T6G_MB_LIB.T6G(SCH_1):PAGE30_I42@PURE_QUANTA.GENOA_SP5(CHIPS)':
 'VDDCR_CPU0_M49': CDS_PINID='VDDCR_CPU0_M49';
NODE_NAME     U25 M50
 '@T6G_MB_LIB.T6G(SCH_1):PAGE30_I42@PURE_QUANTA.GENOA_SP5(CHIPS)':
 'VDDCR_CPU0_M50': CDS_PINID='VDDCR_CPU0_M50';
NODE_NAME     U25 M52
 '@T6G_MB_LIB.T6G(SCH_1):PAGE30_I42@PURE_QUANTA.GENOA_SP5(CHIPS)':
 'VDDCR_CPU0_M52': CDS_PINID='VDDCR_CPU0_M52';
NODE_NAME     U25 M53
 '@T6G_MB_LIB.T6G(SCH_1):PAGE30_I42@PURE_QUANTA.GENOA_SP5(CHIPS)':
 'VDDCR_CPU0_M53': CDS_PINID='VDDCR_CPU0_M53';
NODE_NAME     U25 N35
 '@T6G_MB_LIB.T6G(SCH_1):PAGE30_I42@PURE_QUANTA.GENOA_SP5(CHIPS)':
 'VDDCR_CPU0_N35': CDS_PINID='VDDCR_CPU0_N35';
NODE_NAME     U25 N36
 '@T6G_MB_LIB.T6G(SCH_1):PAGE30_I42@PURE_QUANTA.GENOA_SP5(CHIPS)':
 'VDDCR_CPU0_N36': CDS_PINID='VDDCR_CPU0_N36';
NODE_NAME     U25 N40
 '@T6G_MB_LIB.T6G(SCH_1):PAGE30_I42@PURE_QUANTA.GENOA_SP5(CHIPS)':
 'VDDCR_CPU0_N40': CDS_PINID='VDDCR_CPU0_N40';
NODE_NAME     U25 N41
 '@T6G_MB_LIB.T6G(SCH_1):PAGE30_I42@PURE_QUANTA.GENOA_SP5(CHIPS)':
 'VDDCR_CPU0_N41': CDS_PINID='VDDCR_CPU0_N41';
NODE_NAME     U25 T23
 '@T6G_MB_LIB.T6G(SCH_1):PAGE30_I42@PURE_QUANTA.GENOA_SP5(CHIPS)':
 'VDDCR_CPU0_T23': CDS_PINID='VDDCR_CPU0_T23';
NODE_NAME     U25 T24
 '@T6G_MB_LIB.T6G(SCH_1):PAGE30_I42@PURE_QUANTA.GENOA_SP5(CHIPS)':
 'VDDCR_CPU0_T24': CDS_PINID='VDDCR_CPU0_T24';
NODE_NAME     U25 T26
 '@T6G_MB_LIB.T6G(SCH_1):PAGE30_I42@PURE_QUANTA.GENOA_SP5(CHIPS)':
 'VDDCR_CPU0_T26': CDS_PINID='VDDCR_CPU0_T26';
NODE_NAME     U25 T27
 '@T6G_MB_LIB.T6G(SCH_1):PAGE30_I42@PURE_QUANTA.GENOA_SP5(CHIPS)':
 'VDDCR_CPU0_T27': CDS_PINID='VDDCR_CPU0_T27';
NODE_NAME     U25 T29
 '@T6G_MB_LIB.T6G(SCH_1):PAGE30_I42@PURE_QUANTA.GENOA_SP5(CHIPS)':
 'VDDCR_CPU0_T29': CDS_PINID='VDDCR_CPU0_T29';
NODE_NAME     U25 T30
 '@T6G_MB_LIB.T6G(SCH_1):PAGE30_I42@PURE_QUANTA.GENOA_SP5(CHIPS)':
 'VDDCR_CPU0_T30': CDS_PINID='VDDCR_CPU0_T30';
NODE_NAME     U25 T32
 '@T6G_MB_LIB.T6G(SCH_1):PAGE30_I42@PURE_QUANTA.GENOA_SP5(CHIPS)':
 'VDDCR_CPU0_T32': CDS_PINID='VDDCR_CPU0_T32';
NODE_NAME     U25 T33
 '@T6G_MB_LIB.T6G(SCH_1):PAGE30_I42@PURE_QUANTA.GENOA_SP5(CHIPS)':
 'VDDCR_CPU0_T33': CDS_PINID='VDDCR_CPU0_T33';
NODE_NAME     U25 T43
 '@T6G_MB_LIB.T6G(SCH_1):PAGE30_I42@PURE_QUANTA.GENOA_SP5(CHIPS)':
 'VDDCR_CPU0_T43': CDS_PINID='VDDCR_CPU0_T43';
NODE_NAME     U25 T44
 '@T6G_MB_LIB.T6G(SCH_1):PAGE30_I42@PURE_QUANTA.GENOA_SP5(CHIPS)':
 'VDDCR_CPU0_T44': CDS_PINID='VDDCR_CPU0_T44';
NODE_NAME     U25 T46
 '@T6G_MB_LIB.T6G(SCH_1):PAGE30_I42@PURE_QUANTA.GENOA_SP5(CHIPS)':
 'VDDCR_CPU0_T46': CDS_PINID='VDDCR_CPU0_T46';
NODE_NAME     U25 T47
 '@T6G_MB_LIB.T6G(SCH_1):PAGE30_I42@PURE_QUANTA.GENOA_SP5(CHIPS)':
 'VDDCR_CPU0_T47': CDS_PINID='VDDCR_CPU0_T47';
NODE_NAME     U25 T49
 '@T6G_MB_LIB.T6G(SCH_1):PAGE30_I42@PURE_QUANTA.GENOA_SP5(CHIPS)':
 'VDDCR_CPU0_T49': CDS_PINID='VDDCR_CPU0_T49';
NODE_NAME     U25 T50
 '@T6G_MB_LIB.T6G(SCH_1):PAGE30_I42@PURE_QUANTA.GENOA_SP5(CHIPS)':
 'VDDCR_CPU0_T50': CDS_PINID='VDDCR_CPU0_T50';
NODE_NAME     U25 T52
 '@T6G_MB_LIB.T6G(SCH_1):PAGE30_I42@PURE_QUANTA.GENOA_SP5(CHIPS)':
 'VDDCR_CPU0_T52': CDS_PINID='VDDCR_CPU0_T52';
NODE_NAME     U25 T53
 '@T6G_MB_LIB.T6G(SCH_1):PAGE30_I42@PURE_QUANTA.GENOA_SP5(CHIPS)':
 'VDDCR_CPU0_T53': CDS_PINID='VDDCR_CPU0_T53';
NODE_NAME     U25 U35
 '@T6G_MB_LIB.T6G(SCH_1):PAGE30_I42@PURE_QUANTA.GENOA_SP5(CHIPS)':
 'VDDCR_CPU0_U35': CDS_PINID='VDDCR_CPU0_U35';
NODE_NAME     U25 U36
 '@T6G_MB_LIB.T6G(SCH_1):PAGE30_I42@PURE_QUANTA.GENOA_SP5(CHIPS)':
 'VDDCR_CPU0_U36': CDS_PINID='VDDCR_CPU0_U36';
NODE_NAME     U25 U40
 '@T6G_MB_LIB.T6G(SCH_1):PAGE30_I42@PURE_QUANTA.GENOA_SP5(CHIPS)':
 'VDDCR_CPU0_U40': CDS_PINID='VDDCR_CPU0_U40';
NODE_NAME     U25 U41
 '@T6G_MB_LIB.T6G(SCH_1):PAGE30_I42@PURE_QUANTA.GENOA_SP5(CHIPS)':
 'VDDCR_CPU0_U41': CDS_PINID='VDDCR_CPU0_U41';
NODE_NAME     U25 W29
 '@T6G_MB_LIB.T6G(SCH_1):PAGE30_I42@PURE_QUANTA.GENOA_SP5(CHIPS)':
 'VDDCR_CPU0_W29': CDS_PINID='VDDCR_CPU0_W29';
NODE_NAME     U25 W30
 '@T6G_MB_LIB.T6G(SCH_1):PAGE30_I42@PURE_QUANTA.GENOA_SP5(CHIPS)':
 'VDDCR_CPU0_W30': CDS_PINID='VDDCR_CPU0_W30';
NODE_NAME     U25 W32
 '@T6G_MB_LIB.T6G(SCH_1):PAGE30_I42@PURE_QUANTA.GENOA_SP5(CHIPS)':
 'VDDCR_CPU0_W32': CDS_PINID='VDDCR_CPU0_W32';
NODE_NAME     U25 W33
 '@T6G_MB_LIB.T6G(SCH_1):PAGE30_I42@PURE_QUANTA.GENOA_SP5(CHIPS)':
 'VDDCR_CPU0_W33': CDS_PINID='VDDCR_CPU0_W33';
NODE_NAME     U25 W43
 '@T6G_MB_LIB.T6G(SCH_1):PAGE30_I42@PURE_QUANTA.GENOA_SP5(CHIPS)':
 'VDDCR_CPU0_W43': CDS_PINID='VDDCR_CPU0_W43';
NODE_NAME     U25 W44
 '@T6G_MB_LIB.T6G(SCH_1):PAGE30_I42@PURE_QUANTA.GENOA_SP5(CHIPS)':
 'VDDCR_CPU0_W44': CDS_PINID='VDDCR_CPU0_W44';
NODE_NAME     U25 W46
 '@T6G_MB_LIB.T6G(SCH_1):PAGE30_I42@PURE_QUANTA.GENOA_SP5(CHIPS)':
 'VDDCR_CPU0_W46': CDS_PINID='VDDCR_CPU0_W46';
NODE_NAME     U25 W47
 '@T6G_MB_LIB.T6G(SCH_1):PAGE30_I42@PURE_QUANTA.GENOA_SP5(CHIPS)':
 'VDDCR_CPU0_W47': CDS_PINID='VDDCR_CPU0_W47';
NODE_NAME     U25 Y35
 '@T6G_MB_LIB.T6G(SCH_1):PAGE30_I42@PURE_QUANTA.GENOA_SP5(CHIPS)':
 'VDDCR_CPU0_Y35': CDS_PINID='VDDCR_CPU0_Y35';
NODE_NAME     U25 Y36
 '@T6G_MB_LIB.T6G(SCH_1):PAGE30_I42@PURE_QUANTA.GENOA_SP5(CHIPS)':
 'VDDCR_CPU0_Y36': CDS_PINID='VDDCR_CPU0_Y36';
NODE_NAME     U25 Y40
 '@T6G_MB_LIB.T6G(SCH_1):PAGE30_I42@PURE_QUANTA.GENOA_SP5(CHIPS)':
 'VDDCR_CPU0_Y40': CDS_PINID='VDDCR_CPU0_Y40';
NODE_NAME     U25 Y41
 '@T6G_MB_LIB.T6G(SCH_1):PAGE30_I42@PURE_QUANTA.GENOA_SP5(CHIPS)':
 'VDDCR_CPU0_Y41': CDS_PINID='VDDCR_CPU0_Y41';
NODE_NAME     C2167 1
 '@T6G_MB_LIB.T6G(SCH_1):PAGE68_I1@PURE_QUANTA.Q_CAP(CHIPS)':
 'A': CDS_PINID='A';
NODE_NAME     C2171 1
 '@T6G_MB_LIB.T6G(SCH_1):PAGE68_I2@PURE_QUANTA.Q_CAP(CHIPS)':
 'A': CDS_PINID='A';
NODE_NAME     C2166 1
 '@T6G_MB_LIB.T6G(SCH_1):PAGE68_I4@PURE_QUANTA.Q_CAP(CHIPS)':
 'A': CDS_PINID='A';
NODE_NAME     C2170 1
 '@T6G_MB_LIB.T6G(SCH_1):PAGE68_I5@PURE_QUANTA.Q_CAP(CHIPS)':
 'A': CDS_PINID='A';
NODE_NAME     C2165 1
 '@T6G_MB_LIB.T6G(SCH_1):PAGE68_I7@PURE_QUANTA.Q_CAP(CHIPS)':
 'A': CDS_PINID='A';
NODE_NAME     C2169 1
 '@T6G_MB_LIB.T6G(SCH_1):PAGE68_I9@PURE_QUANTA.Q_CAP(CHIPS)':
 'A': CDS_PINID='A';
NODE_NAME     C246 1
 '@T6G_MB_LIB.T6G(SCH_1):PAGE68_I10@PURE_QUANTA.Q_CAP(CHIPS)':
 'A': CDS_PINID='A';
NODE_NAME     C252 1
 '@T6G_MB_LIB.T6G(SCH_1):PAGE68_I12@PURE_QUANTA.Q_CAP(CHIPS)':
 'A': CDS_PINID='A';
NODE_NAME     C245 1
 '@T6G_MB_LIB.T6G(SCH_1):PAGE68_I14@PURE_QUANTA.Q_CAP(CHIPS)':
 'A': CDS_PINID='A';
NODE_NAME     C251 1
 '@T6G_MB_LIB.T6G(SCH_1):PAGE68_I15@PURE_QUANTA.Q_CAP(CHIPS)':
 'A': CDS_PINID='A';
NODE_NAME     C2175 1
 '@T6G_MB_LIB.T6G(SCH_1):PAGE68_I16@PURE_QUANTA.Q_CAP(CHIPS)':
 'A': CDS_PINID='A';
NODE_NAME     C10179 1
 '@T6G_MB_LIB.T6G(SCH_1):PAGE68_I17@PURE_QUANTA.Q_CAP(CHIPS)':
 'A': CDS_PINID='A';
NODE_NAME     C2183 1
 '@T6G_MB_LIB.T6G(SCH_1):PAGE68_I19@PURE_QUANTA.Q_CAP(CHIPS)':
 'A': CDS_PINID='A';
NODE_NAME     C2174 1
 '@T6G_MB_LIB.T6G(SCH_1):PAGE68_I20@PURE_QUANTA.Q_CAP(CHIPS)':
 'A': CDS_PINID='A';
NODE_NAME     C2178 1
 '@T6G_MB_LIB.T6G(SCH_1):PAGE68_I21@PURE_QUANTA.Q_CAP(CHIPS)':
 'A': CDS_PINID='A';
NODE_NAME     C2173 1
 '@T6G_MB_LIB.T6G(SCH_1):PAGE68_I22@PURE_QUANTA.Q_CAP(CHIPS)':
 'A': CDS_PINID='A';
NODE_NAME     C2177 1
 '@T6G_MB_LIB.T6G(SCH_1):PAGE68_I23@PURE_QUANTA.Q_CAP(CHIPS)':
 'A': CDS_PINID='A';
NODE_NAME     C2182 1
 '@T6G_MB_LIB.T6G(SCH_1):PAGE68_I24@PURE_QUANTA.Q_CAP(CHIPS)':
 'A': CDS_PINID='A';
NODE_NAME     C2181 1
 '@T6G_MB_LIB.T6G(SCH_1):PAGE68_I25@PURE_QUANTA.Q_CAP(CHIPS)':
 'A': CDS_PINID='A';
NODE_NAME     C2186 1
 '@T6G_MB_LIB.T6G(SCH_1):PAGE68_I26@PURE_QUANTA.Q_CAP(CHIPS)':
 'A': CDS_PINID='A';
NODE_NAME     C2190 1
 '@T6G_MB_LIB.T6G(SCH_1):PAGE68_I27@PURE_QUANTA.Q_CAP(CHIPS)':
 'A': CDS_PINID='A';
NODE_NAME     C2185 1
 '@T6G_MB_LIB.T6G(SCH_1):PAGE68_I28@PURE_QUANTA.Q_CAP(CHIPS)':
 'A': CDS_PINID='A';
NODE_NAME     C2189 1
 '@T6G_MB_LIB.T6G(SCH_1):PAGE68_I29@PURE_QUANTA.Q_CAP(CHIPS)':
 'A': CDS_PINID='A';
NODE_NAME     C2193 1
 '@T6G_MB_LIB.T6G(SCH_1):PAGE68_I31@PURE_QUANTA.Q_CAP(CHIPS)':
 'A': CDS_PINID='A';
NODE_NAME     C2196 1
 '@T6G_MB_LIB.T6G(SCH_1):PAGE68_I32@PURE_QUANTA.Q_CAP(CHIPS)':
 'A': CDS_PINID='A';
NODE_NAME     C2192 1
 '@T6G_MB_LIB.T6G(SCH_1):PAGE68_I33@PURE_QUANTA.Q_CAP(CHIPS)':
 'A': CDS_PINID='A';
NODE_NAME     C2195 1
 '@T6G_MB_LIB.T6G(SCH_1):PAGE68_I34@PURE_QUANTA.Q_CAP(CHIPS)':
 'A': CDS_PINID='A';
NODE_NAME     C2199 1
 '@T6G_MB_LIB.T6G(SCH_1):PAGE68_I36@PURE_QUANTA.Q_CAP(CHIPS)':
 'A': CDS_PINID='A';
NODE_NAME     C2198 1
 '@T6G_MB_LIB.T6G(SCH_1):PAGE68_I40@PURE_QUANTA.Q_CAP(CHIPS)':
 'A': CDS_PINID='A';
NODE_NAME     C1922 1
 '@T6G_MB_LIB.T6G(SCH_1):PAGE68_I45@PURE_QUANTA.Q_CAP(CHIPS)':
 'A': CDS_PINID='A';
NODE_NAME     C263 1
 '@T6G_MB_LIB.T6G(SCH_1):PAGE68_I46@PURE_QUANTA.Q_CAP(CHIPS)':
 'A': CDS_PINID='A';
NODE_NAME     C4178 1
 '@T6G_MB_LIB.T6G(SCH_1):PAGE68_I47@PURE_QUANTA.Q_CAP(CHIPS)':
 'A': CDS_PINID='A';
NODE_NAME     C4179 1
 '@T6G_MB_LIB.T6G(SCH_1):PAGE68_I48@PURE_QUANTA.Q_CAP(CHIPS)':
 'A': CDS_PINID='A';
NODE_NAME     C268 1
 '@T6G_MB_LIB.T6G(SCH_1):PAGE68_I49@PURE_QUANTA.Q_CAP(CHIPS)':
 'A': CDS_PINID='A';
NODE_NAME     C267 1
 '@T6G_MB_LIB.T6G(SCH_1):PAGE68_I50@PURE_QUANTA.Q_CAP(CHIPS)':
 'A': CDS_PINID='A';
NODE_NAME     C271 1
 '@T6G_MB_LIB.T6G(SCH_1):PAGE68_I51@PURE_QUANTA.Q_CAP(CHIPS)':
 'A': CDS_PINID='A';
NODE_NAME     C273 1
 '@T6G_MB_LIB.T6G(SCH_1):PAGE68_I52@PURE_QUANTA.Q_CAP(CHIPS)':
 'A': CDS_PINID='A';
NODE_NAME     C270 1
 '@T6G_MB_LIB.T6G(SCH_1):PAGE68_I53@PURE_QUANTA.Q_CAP(CHIPS)':
 'A': CDS_PINID='A';
NODE_NAME     C275 1
 '@T6G_MB_LIB.T6G(SCH_1):PAGE68_I54@PURE_QUANTA.Q_CAP(CHIPS)':
 'A': CDS_PINID='A';
NODE_NAME     C277 1
 '@T6G_MB_LIB.T6G(SCH_1):PAGE68_I55@PURE_QUANTA.Q_CAP(CHIPS)':
 'A': CDS_PINID='A';
NODE_NAME     C274 1
 '@T6G_MB_LIB.T6G(SCH_1):PAGE68_I56@PURE_QUANTA.Q_CAP(CHIPS)':
 'A': CDS_PINID='A';
NODE_NAME     C276 1
 '@T6G_MB_LIB.T6G(SCH_1):PAGE68_I57@PURE_QUANTA.Q_CAP(CHIPS)':
 'A': CDS_PINID='A';
NODE_NAME     C279 1
 '@T6G_MB_LIB.T6G(SCH_1):PAGE68_I58@PURE_QUANTA.Q_CAP(CHIPS)':
 'A': CDS_PINID='A';
NODE_NAME     C278 1
 '@T6G_MB_LIB.T6G(SCH_1):PAGE68_I62@PURE_QUANTA.Q_CAP(CHIPS)':
 'A': CDS_PINID='A';
NODE_NAME     C272 1
 '@T6G_MB_LIB.T6G(SCH_1):PAGE68_I110@PURE_QUANTA.Q_CAP(CHIPS)':
 'A': CDS_PINID='A';
NODE_NAME     PL52 4
 '@T6G_MB_LIB.T6G(SCH_1):PAGE169_I62@PURE_QUANTA.Q_INDUCTOR4P_14(CHIPS)':
 '4': CDS_PINID='\4\';
NODE_NAME     PC108 1
 '@T6G_MB_LIB.T6G(SCH_1):PAGE169_I64@PURE_QUANTA.Q_CAPP(CHIPS)':
 'A': CDS_PINID='A';
NODE_NAME     PC494 1
 '@T6G_MB_LIB.T6G(SCH_1):PAGE169_I65@PURE_QUANTA.Q_CAPP(CHIPS)':
 'A': CDS_PINID='A';
NODE_NAME     PC495 1
 '@T6G_MB_LIB.T6G(SCH_1):PAGE169_I66@PURE_QUANTA.Q_CAPP(CHIPS)':
 'A': CDS_PINID='A';
NODE_NAME     PC496 1
 '@T6G_MB_LIB.T6G(SCH_1):PAGE169_I67@PURE_QUANTA.Q_CAPP(CHIPS)':
 'A': CDS_PINID='A';
NODE_NAME     PC499_2 1
 '@T6G_MB_LIB.T6G(SCH_1):PAGE169_I68@PURE_QUANTA.Q_CAP(CHIPS)':
 'A': CDS_PINID='A';
NODE_NAME     PR350 2
 '@T6G_MB_LIB.T6G(SCH_1):PAGE170_I26@PURE_QUANTA.Q_RES(CHIPS)':
 'B': CDS_PINID='B';
NODE_NAME     PR294 1
 '@T6G_MB_LIB.T6G(SCH_1):PAGE168_I72@PURE_QUANTA.Q_RES(CHIPS)':
 'A': CDS_PINID='A';
NODE_NAME     PR325 2
 '@T6G_MB_LIB.T6G(SCH_1):PAGE169_I30@PURE_QUANTA.Q_RES(CHIPS)':
 'B': CDS_PINID='B';
NODE_NAME     PR324 2
 '@T6G_MB_LIB.T6G(SCH_1):PAGE169_I43@PURE_QUANTA.Q_RES(CHIPS)':
 'B': CDS_PINID='B';
NODE_NAME     PC501_2 1
 '@T6G_MB_LIB.T6G(SCH_1):PAGE169_I70@PURE_QUANTA.Q_CAP(CHIPS)':
 'A': CDS_PINID='A';
NODE_NAME     PC498 1
 '@T6G_MB_LIB.T6G(SCH_1):PAGE169_I73@PURE_QUANTA.Q_CAPP(CHIPS)':
 'A': CDS_PINID='A';
NODE_NAME     PL51 4
 '@T6G_MB_LIB.T6G(SCH_1):PAGE169_I77@PURE_QUANTA.Q_INDUCTOR4P_14(CHIPS)':
 '4': CDS_PINID='\4\';
NODE_NAME     PC497 1
 '@T6G_MB_LIB.T6G(SCH_1):PAGE169_I87@PURE_QUANTA.Q_CAP(CHIPS)':
 'A': CDS_PINID='A';
NODE_NAME     PC500_1 1
 '@T6G_MB_LIB.T6G(SCH_1):PAGE169_I88@PURE_QUANTA.Q_CAP(CHIPS)':
 'A': CDS_PINID='A';
NODE_NAME     PC502_1 1
 '@T6G_MB_LIB.T6G(SCH_1):PAGE169_I89@PURE_QUANTA.Q_CAP(CHIPS)':
 'A': CDS_PINID='A';
NODE_NAME     PR447 1
 '@T6G_MB_LIB.T6G(SCH_1):PAGE169_I90@PURE_QUANTA.Q_RES(CHIPS)':
 'A': CDS_PINID='A';
NODE_NAME     PR351 2
 '@T6G_MB_LIB.T6G(SCH_1):PAGE170_I50@PURE_QUANTA.Q_RES(CHIPS)':
 'B': CDS_PINID='B';
NODE_NAME     PL60 4
 '@T6G_MB_LIB.T6G(SCH_1):PAGE170_I52@PURE_QUANTA.Q_INDUCTOR4P_14(CHIPS)':
 '4': CDS_PINID='\4\';
NODE_NAME     PC563_4 1
 '@T6G_MB_LIB.T6G(SCH_1):PAGE170_I58@PURE_QUANTA.Q_CAP(CHIPS)':
 'A': CDS_PINID='A';
NODE_NAME     PC565_4 1
 '@T6G_MB_LIB.T6G(SCH_1):PAGE170_I60@PURE_QUANTA.Q_CAP(CHIPS)':
 'A': CDS_PINID='A';
NODE_NAME     PL59 4
 '@T6G_MB_LIB.T6G(SCH_1):PAGE170_I64@PURE_QUANTA.Q_INDUCTOR4P_14(CHIPS)':
 '4': CDS_PINID='\4\';
NODE_NAME     PC562_3 1
 '@T6G_MB_LIB.T6G(SCH_1):PAGE170_I70@PURE_QUANTA.Q_CAP(CHIPS)':
 'A': CDS_PINID='A';
NODE_NAME     PC564_3 1
 '@T6G_MB_LIB.T6G(SCH_1):PAGE170_I71@PURE_QUANTA.Q_CAP(CHIPS)':
 'A': CDS_PINID='A';
NODE_NAME     PR433 2
 '@T6G_MB_LIB.T6G(SCH_1):PAGE171_I21@PURE_QUANTA.Q_RES(CHIPS)':
 'B': CDS_PINID='B';
NODE_NAME     PR355 2
 '@T6G_MB_LIB.T6G(SCH_1):PAGE171_I32@PURE_QUANTA.Q_RES(CHIPS)':
 'B': CDS_PINID='B';
NODE_NAME     PL70 4
 '@T6G_MB_LIB.T6G(SCH_1):PAGE171_I52@PURE_QUANTA.Q_INDUCTOR4P_14(CHIPS)':
 '4': CDS_PINID='\4\';
NODE_NAME     PC163_6 1
 '@T6G_MB_LIB.T6G(SCH_1):PAGE171_I59@PURE_QUANTA.Q_CAP(CHIPS)':
 'A': CDS_PINID='A';
NODE_NAME     PC166_6 1
 '@T6G_MB_LIB.T6G(SCH_1):PAGE171_I60@PURE_QUANTA.Q_CAP(CHIPS)':
 'A': CDS_PINID='A';
NODE_NAME     PL61 4
 '@T6G_MB_LIB.T6G(SCH_1):PAGE171_I64@PURE_QUANTA.Q_INDUCTOR4P_14(CHIPS)':
 '4': CDS_PINID='\4\';
NODE_NAME     PC575_5 1
 '@T6G_MB_LIB.T6G(SCH_1):PAGE171_I69@PURE_QUANTA.Q_CAP(CHIPS)':
 'A': CDS_PINID='A';
NODE_NAME     PC576_5 1
 '@T6G_MB_LIB.T6G(SCH_1):PAGE171_I71@PURE_QUANTA.Q_CAP(CHIPS)':
 'A': CDS_PINID='A';
NET_NAME
'PVDDCR_CPU0_P0_EN'
 '@T6G_MB_LIB.T6G(SCH_1):PVDDCR_CPU0_P0_EN':
 C_SIGNAL='@t6g_mb_lib.t6g(sch_1):pvddcr_cpu0_p0_en';
NODE_NAME     R8312 1
 '@T6G_MB_LIB.T6G(SCH_1):PAGE168_I88@PURE_QUANTA.Q_RES(CHIPS)':
 'A': CDS_PINID='A';
NODE_NAME     U18 B17
 '@T6G_MB_LIB.T6G(SCH_1):PAGE79_I94@PURE_QUANTA.LCMXO3LF9400C5BG484C(CHIPS)':
 'PT39B': CDS_PINID='PT39B';
NET_NAME
'PVDDCR_CPU0_P0_EN_R'
 '@T6G_MB_LIB.T6G(SCH_1):PVDDCR_CPU0_P0_EN_R':
 C_SIGNAL='@t6g_mb_lib.t6g(sch_1):pvddcr_cpu0_p0_en_r';
NODE_NAME     R8312 2
 '@T6G_MB_LIB.T6G(SCH_1):PAGE168_I88@PURE_QUANTA.Q_RES(CHIPS)':
 'B': CDS_PINID='B';
NODE_NAME     C468 1
 '@T6G_MB_LIB.T6G(SCH_1):PAGE168_I90@PURE_QUANTA.Q_CAP(CHIPS)':
 'A': CDS_PINID='A';
NODE_NAME     PU42 17
 '@T6G_MB_LIB.T6G(SCH_1):PAGE168_I135@PURE_QUANTA.RAA229620GNPHA0(CHIPS)':
 'EN0': CDS_PINID='EN0';
NET_NAME
'PVDDCR_CPU0_P0_IMON1'
 '@T6G_MB_LIB.T6G(SCH_1):PVDDCR_CPU0_P0_IMON1':
 C_SIGNAL='@t6g_mb_lib.t6g(sch_1):pvddcr_cpu0_p0_imon1';
NODE_NAME     PU6 38
 '@T6G_MB_LIB.T6G(SCH_1):PAGE169_I26@PURE_QUANTA.ISL99390FRZTR5935(CHIPS)':
 'IOUT': CDS_PINID='IOUT';
NODE_NAME     PU42 27
 '@T6G_MB_LIB.T6G(SCH_1):PAGE168_I135@PURE_QUANTA.RAA229620GNPHA0(CHIPS)':
 'CS11': CDS_PINID='CS11';
NET_NAME
'PVDDCR_CPU0_P0_IMON2'
 '@T6G_MB_LIB.T6G(SCH_1):PVDDCR_CPU0_P0_IMON2':
 C_SIGNAL='@t6g_mb_lib.t6g(sch_1):pvddcr_cpu0_p0_imon2';
NODE_NAME     PU43 38
 '@T6G_MB_LIB.T6G(SCH_1):PAGE169_I16@PURE_QUANTA.ISL99390FRZTR5935(CHIPS)':
 'IOUT': CDS_PINID='IOUT';
NODE_NAME     PU42 28
 '@T6G_MB_LIB.T6G(SCH_1):PAGE168_I135@PURE_QUANTA.RAA229620GNPHA0(CHIPS)':
 'CS10': CDS_PINID='CS10';
NET_NAME
'PVDDCR_CPU0_P0_IMON3'
 '@T6G_MB_LIB.T6G(SCH_1):PVDDCR_CPU0_P0_IMON3':
 C_SIGNAL='@t6g_mb_lib.t6g(sch_1):pvddcr_cpu0_p0_imon3';
NODE_NAME     PU42 29
 '@T6G_MB_LIB.T6G(SCH_1):PAGE168_I135@PURE_QUANTA.RAA229620GNPHA0(CHIPS)':
 'CS9': CDS_PINID='CS9';
NODE_NAME     PU46 38
 '@T6G_MB_LIB.T6G(SCH_1):PAGE170_I38@PURE_QUANTA.ISL99390FRZTR5935(CHIPS)':
 'IOUT': CDS_PINID='IOUT';
NET_NAME
'PVDDCR_CPU0_P0_IMON4'
 '@T6G_MB_LIB.T6G(SCH_1):PVDDCR_CPU0_P0_IMON4':
 C_SIGNAL='@t6g_mb_lib.t6g(sch_1):pvddcr_cpu0_p0_imon4';
NODE_NAME     PU42 30
 '@T6G_MB_LIB.T6G(SCH_1):PAGE168_I135@PURE_QUANTA.RAA229620GNPHA0(CHIPS)':
 'CS8': CDS_PINID='CS8';
NODE_NAME     PU47 38
 '@T6G_MB_LIB.T6G(SCH_1):PAGE170_I9@PURE_QUANTA.ISL99390FRZTR5935(CHIPS)':
 'IOUT': CDS_PINID='IOUT';
NET_NAME
'PVDDCR_CPU0_P0_IMON5'
 '@T6G_MB_LIB.T6G(SCH_1):PVDDCR_CPU0_P0_IMON5':
 C_SIGNAL='@t6g_mb_lib.t6g(sch_1):pvddcr_cpu0_p0_imon5';
NODE_NAME     PU42 31
 '@T6G_MB_LIB.T6G(SCH_1):PAGE168_I135@PURE_QUANTA.RAA229620GNPHA0(CHIPS)':
 'CS7': CDS_PINID='CS7';
NODE_NAME     PU48 38
 '@T6G_MB_LIB.T6G(SCH_1):PAGE171_I18@PURE_QUANTA.ISL99390FRZTR5935(CHIPS)':
 'IOUT': CDS_PINID='IOUT';
NET_NAME
'PVDDCR_CPU0_P0_IMON6'
 '@T6G_MB_LIB.T6G(SCH_1):PVDDCR_CPU0_P0_IMON6':
 C_SIGNAL='@t6g_mb_lib.t6g(sch_1):pvddcr_cpu0_p0_imon6';
NODE_NAME     PU42 32
 '@T6G_MB_LIB.T6G(SCH_1):PAGE168_I135@PURE_QUANTA.RAA229620GNPHA0(CHIPS)':
 'CS6': CDS_PINID='CS6';
NODE_NAME     PU10 38
 '@T6G_MB_LIB.T6G(SCH_1):PAGE171_I73@PURE_QUANTA.ISL99390FRZTR5935(CHIPS)':
 'IOUT': CDS_PINID='IOUT';
NET_NAME
'PVDDCR_CPU0_P0_LSET1'
 '@T6G_MB_LIB.T6G(SCH_1):PVDDCR_CPU0_P0_LSET1':
 C_SIGNAL='@t6g_mb_lib.t6g(sch_1):pvddcr_cpu0_p0_lset1';
NODE_NAME     PU6 37
 '@T6G_MB_LIB.T6G(SCH_1):PAGE169_I26@PURE_QUANTA.ISL99390FRZTR5935(CHIPS)':
 'LSET': CDS_PINID='LSET';
NODE_NAME     PR320 2
 '@T6G_MB_LIB.T6G(SCH_1):PAGE169_I46@PURE_QUANTA.Q_RES(CHIPS)':
 'B': CDS_PINID='B';
NET_NAME
'PVDDCR_CPU0_P0_LSET2'
 '@T6G_MB_LIB.T6G(SCH_1):PVDDCR_CPU0_P0_LSET2':
 C_SIGNAL='@t6g_mb_lib.t6g(sch_1):pvddcr_cpu0_p0_lset2';
NODE_NAME     PU43 37
 '@T6G_MB_LIB.T6G(SCH_1):PAGE169_I16@PURE_QUANTA.ISL99390FRZTR5935(CHIPS)':
 'LSET': CDS_PINID='LSET';
NODE_NAME     PR321 2
 '@T6G_MB_LIB.T6G(SCH_1):PAGE169_I10@PURE_QUANTA.Q_RES(CHIPS)':
 'B': CDS_PINID='B';
NET_NAME
'PVDDCR_CPU0_P0_LSET3'
 '@T6G_MB_LIB.T6G(SCH_1):PVDDCR_CPU0_P0_LSET3':
 C_SIGNAL='@t6g_mb_lib.t6g(sch_1):pvddcr_cpu0_p0_lset3';
NODE_NAME     PR346 2
 '@T6G_MB_LIB.T6G(SCH_1):PAGE170_I33@PURE_QUANTA.Q_RES(CHIPS)':
 'B': CDS_PINID='B';
NODE_NAME     PU46 37
 '@T6G_MB_LIB.T6G(SCH_1):PAGE170_I38@PURE_QUANTA.ISL99390FRZTR5935(CHIPS)':
 'LSET': CDS_PINID='LSET';
NET_NAME
'PVDDCR_CPU0_P0_LSET4'
 '@T6G_MB_LIB.T6G(SCH_1):PVDDCR_CPU0_P0_LSET4':
 C_SIGNAL='@t6g_mb_lib.t6g(sch_1):pvddcr_cpu0_p0_lset4';
NODE_NAME     PU47 37
 '@T6G_MB_LIB.T6G(SCH_1):PAGE170_I9@PURE_QUANTA.ISL99390FRZTR5935(CHIPS)':
 'LSET': CDS_PINID='LSET';
NODE_NAME     PR347 2
 '@T6G_MB_LIB.T6G(SCH_1):PAGE170_I11@PURE_QUANTA.Q_RES(CHIPS)':
 'B': CDS_PINID='B';
NET_NAME
'PVDDCR_CPU0_P0_LSET5'
 '@T6G_MB_LIB.T6G(SCH_1):PVDDCR_CPU0_P0_LSET5':
 C_SIGNAL='@t6g_mb_lib.t6g(sch_1):pvddcr_cpu0_p0_lset5';
NODE_NAME     PU48 37
 '@T6G_MB_LIB.T6G(SCH_1):PAGE171_I18@PURE_QUANTA.ISL99390FRZTR5935(CHIPS)':
 'LSET': CDS_PINID='LSET';
NODE_NAME     PR353 2
 '@T6G_MB_LIB.T6G(SCH_1):PAGE171_I36@PURE_QUANTA.Q_RES(CHIPS)':
 'B': CDS_PINID='B';
NET_NAME
'PVDDCR_CPU0_P0_LSET6'
 '@T6G_MB_LIB.T6G(SCH_1):PVDDCR_CPU0_P0_LSET6':
 C_SIGNAL='@t6g_mb_lib.t6g(sch_1):pvddcr_cpu0_p0_lset6';
NODE_NAME     PR431 2
 '@T6G_MB_LIB.T6G(SCH_1):PAGE171_I8@PURE_QUANTA.Q_RES(CHIPS)':
 'B': CDS_PINID='B';
NODE_NAME     PU10 37
 '@T6G_MB_LIB.T6G(SCH_1):PAGE171_I73@PURE_QUANTA.ISL99390FRZTR5935(CHIPS)':
 'LSET': CDS_PINID='LSET';
NET_NAME
'PVDDCR_CPU0_P0_OCP_N'
 '@T6G_MB_LIB.T6G(SCH_1):PVDDCR_CPU0_P0_OCP_N':
 C_SIGNAL='@t6g_mb_lib.t6g(sch_1):pvddcr_cpu0_p0_ocp_n';
NODE_NAME     R8301 1
 '@T6G_MB_LIB.T6G(SCH_1):PAGE168_I58@PURE_QUANTA.Q_RES(CHIPS)':
 'A': CDS_PINID='A';
NODE_NAME     R231 1
 '@T6G_MB_LIB.T6G(SCH_1):PAGE81_I60@PURE_QUANTA.Q_RES(CHIPS)':
 'A': CDS_PINID='A';
NET_NAME
'PVDDCR_CPU0_P0_OCP_N_R'
 '@T6G_MB_LIB.T6G(SCH_1):PVDDCR_CPU0_P0_OCP_N_R':
 C_SIGNAL='@t6g_mb_lib.t6g(sch_1):pvddcr_cpu0_p0_ocp_n_r';
NODE_NAME     R8301 2
 '@T6G_MB_LIB.T6G(SCH_1):PAGE168_I58@PURE_QUANTA.Q_RES(CHIPS)':
 'B': CDS_PINID='B';
NODE_NAME     R8313 2
 '@T6G_MB_LIB.T6G(SCH_1):PAGE168_I54@PURE_QUANTA.Q_RES(CHIPS)':
 'B': CDS_PINID='B';
NODE_NAME     PU42 41
 '@T6G_MB_LIB.T6G(SCH_1):PAGE168_I135@PURE_QUANTA.RAA229620GNPHA0(CHIPS)':
 'OCP_L': CDS_PINID='OCP_L';
NET_NAME
'PVDDCR_CPU0_P0_PMALERT'
 '@T6G_MB_LIB.T6G(SCH_1):PVDDCR_CPU0_P0_PMALERT':
 C_SIGNAL='@t6g_mb_lib.t6g(sch_1):pvddcr_cpu0_p0_pmalert';
NODE_NAME     R1185 1
 '@T6G_MB_LIB.T6G(SCH_1):PAGE82_I62@PURE_QUANTA.Q_RES(CHIPS)':
 'A': CDS_PINID='A';
NODE_NAME     R8310 1
 '@T6G_MB_LIB.T6G(SCH_1):PAGE168_I83@PURE_QUANTA.Q_RES(CHIPS)':
 'A': CDS_PINID='A';
NODE_NAME     U18 AB3
 '@T6G_MB_LIB.T6G(SCH_1):PAGE80_I216@PURE_QUANTA.LCMXO3LF9400C5BG484C(CHIPS)':
 'PB7B': CDS_PINID='PB7B';
NODE_NAME     C5011 1
 '@T6G_MB_LIB.T6G(SCH_1):PAGE168_I142@PURE_QUANTA.Q_CAP(CHIPS)':
 'A': CDS_PINID='A';
NET_NAME
'PVDDCR_CPU0_P0_PMALERT_R'
 '@T6G_MB_LIB.T6G(SCH_1):PVDDCR_CPU0_P0_PMALERT_R':
 C_SIGNAL='@t6g_mb_lib.t6g(sch_1):pvddcr_cpu0_p0_pmalert_r';
NODE_NAME     R8310 2
 '@T6G_MB_LIB.T6G(SCH_1):PAGE168_I83@PURE_QUANTA.Q_RES(CHIPS)':
 'B': CDS_PINID='B';
NODE_NAME     PU42 15
 '@T6G_MB_LIB.T6G(SCH_1):PAGE168_I135@PURE_QUANTA.RAA229620GNPHA0(CHIPS)':
 'NPMALERT': CDS_PINID='NPMALERT';
NET_NAME
'PVDDCR_CPU0_P0_PMSCL_R'
 '@T6G_MB_LIB.T6G(SCH_1):PVDDCR_CPU0_P0_PMSCL_R':
 C_SIGNAL='@t6g_mb_lib.t6g(sch_1):pvddcr_cpu0_p0_pmscl_r';
NODE_NAME     R8308 2
 '@T6G_MB_LIB.T6G(SCH_1):PAGE168_I85@PURE_QUANTA.Q_RES(CHIPS)':
 'B': CDS_PINID='B';
NODE_NAME     PU42 14
 '@T6G_MB_LIB.T6G(SCH_1):PAGE168_I135@PURE_QUANTA.RAA229620GNPHA0(CHIPS)':
 'PMSCL': CDS_PINID='PMSCL';
NET_NAME
'PVDDCR_CPU0_P0_PMSDA_R'
 '@T6G_MB_LIB.T6G(SCH_1):PVDDCR_CPU0_P0_PMSDA_R':
 C_SIGNAL='@t6g_mb_lib.t6g(sch_1):pvddcr_cpu0_p0_pmsda_r';
NODE_NAME     R8309 2
 '@T6G_MB_LIB.T6G(SCH_1):PAGE168_I84@PURE_QUANTA.Q_RES(CHIPS)':
 'B': CDS_PINID='B';
NODE_NAME     PU42 13
 '@T6G_MB_LIB.T6G(SCH_1):PAGE168_I135@PURE_QUANTA.RAA229620GNPHA0(CHIPS)':
 'PMSDA': CDS_PINID='PMSDA';
NET_NAME
'PVDDCR_CPU0_P0_PVCC'
 '@T6G_MB_LIB.T6G(SCH_1):PVDDCR_CPU0_P0_PVCC':
 C_SIGNAL='@t6g_mb_lib.t6g(sch_1):pvddcr_cpu0_p0_pvcc',
 CDS_GLOBAL_NET='TRUE';
NODE_NAME     PR445 1
 '@T6G_MB_LIB.T6G(SCH_1):PAGE169_I3@PURE_QUANTA.Q_RES(CHIPS)':
 'A': CDS_PINID='A';
NODE_NAME     PR446 1
 '@T6G_MB_LIB.T6G(SCH_1):PAGE169_I4@PURE_QUANTA.Q_RES(CHIPS)':
 'A': CDS_PINID='A';
NODE_NAME     PU43 4
 '@T6G_MB_LIB.T6G(SCH_1):PAGE169_I16@PURE_QUANTA.ISL99390FRZTR5935(CHIPS)':
 'PVCC': CDS_PINID='PVCC';
NODE_NAME     PR319 1
 '@T6G_MB_LIB.T6G(SCH_1):PAGE169_I17@PURE_QUANTA.Q_RES(CHIPS)':
 'A': CDS_PINID='A';
NODE_NAME     PC478_C0P0_2 1
 '@T6G_MB_LIB.T6G(SCH_1):PAGE169_I19@PURE_QUANTA.Q_CAP(CHIPS)':
 'A': CDS_PINID='A';
NODE_NAME     PU6 4
 '@T6G_MB_LIB.T6G(SCH_1):PAGE169_I26@PURE_QUANTA.ISL99390FRZTR5935(CHIPS)':
 'PVCC': CDS_PINID='PVCC';
NODE_NAME     PU51 4
 '@T6G_MB_LIB.T6G(SCH_1):PAGE174_I38@PURE_QUANTA.ISL99390FRZTR5935(CHIPS)':
 'PVCC': CDS_PINID='PVCC';
NODE_NAME     PR318 1
 '@T6G_MB_LIB.T6G(SCH_1):PAGE169_I49@PURE_QUANTA.Q_RES(CHIPS)':
 'A': CDS_PINID='A';
NODE_NAME     PC477_C0P0_1 1
 '@T6G_MB_LIB.T6G(SCH_1):PAGE169_I51@PURE_QUANTA.Q_CAP(CHIPS)':
 'A': CDS_PINID='A';
NODE_NAME     PU47 4
 '@T6G_MB_LIB.T6G(SCH_1):PAGE170_I9@PURE_QUANTA.ISL99390FRZTR5935(CHIPS)':
 'PVCC': CDS_PINID='PVCC';
NODE_NAME     PR345 1
 '@T6G_MB_LIB.T6G(SCH_1):PAGE170_I12@PURE_QUANTA.Q_RES(CHIPS)':
 'A': CDS_PINID='A';
NODE_NAME     PC549_C0P0_4 1
 '@T6G_MB_LIB.T6G(SCH_1):PAGE170_I15@PURE_QUANTA.Q_CAP(CHIPS)':
 'A': CDS_PINID='A';
NODE_NAME     PR344 1
 '@T6G_MB_LIB.T6G(SCH_1):PAGE170_I37@PURE_QUANTA.Q_RES(CHIPS)':
 'A': CDS_PINID='A';
NODE_NAME     PU46 4
 '@T6G_MB_LIB.T6G(SCH_1):PAGE170_I38@PURE_QUANTA.ISL99390FRZTR5935(CHIPS)':
 'PVCC': CDS_PINID='PVCC';
NODE_NAME     PC548_C0P0_3 1
 '@T6G_MB_LIB.T6G(SCH_1):PAGE170_I40@PURE_QUANTA.Q_CAP(CHIPS)':
 'A': CDS_PINID='A';
NODE_NAME     PR430 1
 '@T6G_MB_LIB.T6G(SCH_1):PAGE171_I13@PURE_QUANTA.Q_RES(CHIPS)':
 'A': CDS_PINID='A';
NODE_NAME     PC152_C0P0_6 1
 '@T6G_MB_LIB.T6G(SCH_1):PAGE171_I14@PURE_QUANTA.Q_CAP(CHIPS)':
 'A': CDS_PINID='A';
NODE_NAME     PU48 4
 '@T6G_MB_LIB.T6G(SCH_1):PAGE171_I18@PURE_QUANTA.ISL99390FRZTR5935(CHIPS)':
 'PVCC': CDS_PINID='PVCC';
NODE_NAME     PR352 1
 '@T6G_MB_LIB.T6G(SCH_1):PAGE171_I40@PURE_QUANTA.Q_RES(CHIPS)':
 'A': CDS_PINID='A';
NODE_NAME     PC568_C0P0_5 1
 '@T6G_MB_LIB.T6G(SCH_1):PAGE171_I42@PURE_QUANTA.Q_CAP(CHIPS)':
 'A': CDS_PINID='A';
NODE_NAME     PU10 4
 '@T6G_MB_LIB.T6G(SCH_1):PAGE171_I73@PURE_QUANTA.ISL99390FRZTR5935(CHIPS)':
 'PVCC': CDS_PINID='PVCC';
NODE_NAME     PR357 1
 '@T6G_MB_LIB.T6G(SCH_1):PAGE173_I12@PURE_QUANTA.Q_RES(CHIPS)':
 'A': CDS_PINID='A';
NODE_NAME     PC582_SOP0_2 1
 '@T6G_MB_LIB.T6G(SCH_1):PAGE173_I14@PURE_QUANTA.Q_CAP(CHIPS)':
 'A': CDS_PINID='A';
NODE_NAME     PR356 1
 '@T6G_MB_LIB.T6G(SCH_1):PAGE173_I38@PURE_QUANTA.Q_RES(CHIPS)':
 'A': CDS_PINID='A';
NODE_NAME     PC581_SOP0_1 1
 '@T6G_MB_LIB.T6G(SCH_1):PAGE173_I40@PURE_QUANTA.Q_CAP(CHIPS)':
 'A': CDS_PINID='A';
NODE_NAME     PU49 4
 '@T6G_MB_LIB.T6G(SCH_1):PAGE173_I41@PURE_QUANTA.ISL99390FRZTR5935(CHIPS)':
 'PVCC': CDS_PINID='PVCC';
NODE_NAME     PU50 4
 '@T6G_MB_LIB.T6G(SCH_1):PAGE173_I86@PURE_QUANTA.ISL99390FRZTR5935(CHIPS)':
 'PVCC': CDS_PINID='PVCC';
NODE_NAME     PR364 1
 '@T6G_MB_LIB.T6G(SCH_1):PAGE174_I15@PURE_QUANTA.Q_RES(CHIPS)':
 'A': CDS_PINID='A';
NODE_NAME     PC607_SOP0_3 1
 '@T6G_MB_LIB.T6G(SCH_1):PAGE174_I19@PURE_QUANTA.Q_CAP(CHIPS)':
 'A': CDS_PINID='A';
NET_NAME
'PVDDCR_CPU0_P0_PWM1'
 '@T6G_MB_LIB.T6G(SCH_1):PVDDCR_CPU0_P0_PWM1':
 C_SIGNAL='@t6g_mb_lib.t6g(sch_1):pvddcr_cpu0_p0_pwm1';
NODE_NAME     PU6 34
 '@T6G_MB_LIB.T6G(SCH_1):PAGE169_I26@PURE_QUANTA.ISL99390FRZTR5935(CHIPS)':
 'PWM': CDS_PINID='PWM';
NODE_NAME     PU42 12
 '@T6G_MB_LIB.T6G(SCH_1):PAGE168_I135@PURE_QUANTA.RAA229620GNPHA0(CHIPS)':
 'PWM11': CDS_PINID='PWM11';
NET_NAME
'PVDDCR_CPU0_P0_PWM2'
 '@T6G_MB_LIB.T6G(SCH_1):PVDDCR_CPU0_P0_PWM2':
 C_SIGNAL='@t6g_mb_lib.t6g(sch_1):pvddcr_cpu0_p0_pwm2';
NODE_NAME     PU43 34
 '@T6G_MB_LIB.T6G(SCH_1):PAGE169_I16@PURE_QUANTA.ISL99390FRZTR5935(CHIPS)':
 'PWM': CDS_PINID='PWM';
NODE_NAME     PU42 11
 '@T6G_MB_LIB.T6G(SCH_1):PAGE168_I135@PURE_QUANTA.RAA229620GNPHA0(CHIPS)':
 'PWM10': CDS_PINID='PWM10';
NET_NAME
'PVDDCR_CPU0_P0_PWM3'
 '@T6G_MB_LIB.T6G(SCH_1):PVDDCR_CPU0_P0_PWM3':
 C_SIGNAL='@t6g_mb_lib.t6g(sch_1):pvddcr_cpu0_p0_pwm3';
NODE_NAME     PU42 10
 '@T6G_MB_LIB.T6G(SCH_1):PAGE168_I135@PURE_QUANTA.RAA229620GNPHA0(CHIPS)':
 'PWM9': CDS_PINID='PWM9';
NODE_NAME     PU46 34
 '@T6G_MB_LIB.T6G(SCH_1):PAGE170_I38@PURE_QUANTA.ISL99390FRZTR5935(CHIPS)':
 'PWM': CDS_PINID='PWM';
NET_NAME
'PVDDCR_CPU0_P0_PWM4'
 '@T6G_MB_LIB.T6G(SCH_1):PVDDCR_CPU0_P0_PWM4':
 C_SIGNAL='@t6g_mb_lib.t6g(sch_1):pvddcr_cpu0_p0_pwm4';
NODE_NAME     PU42 9
 '@T6G_MB_LIB.T6G(SCH_1):PAGE168_I135@PURE_QUANTA.RAA229620GNPHA0(CHIPS)':
 'PWM8': CDS_PINID='PWM8';
NODE_NAME     PU47 34
 '@T6G_MB_LIB.T6G(SCH_1):PAGE170_I9@PURE_QUANTA.ISL99390FRZTR5935(CHIPS)':
 'PWM': CDS_PINID='PWM';
NET_NAME
'PVDDCR_CPU0_P0_PWM5'
 '@T6G_MB_LIB.T6G(SCH_1):PVDDCR_CPU0_P0_PWM5':
 C_SIGNAL='@t6g_mb_lib.t6g(sch_1):pvddcr_cpu0_p0_pwm5';
NODE_NAME     PU42 8
 '@T6G_MB_LIB.T6G(SCH_1):PAGE168_I135@PURE_QUANTA.RAA229620GNPHA0(CHIPS)':
 'PWM7': CDS_PINID='PWM7';
NODE_NAME     PU48 34
 '@T6G_MB_LIB.T6G(SCH_1):PAGE171_I18@PURE_QUANTA.ISL99390FRZTR5935(CHIPS)':
 'PWM': CDS_PINID='PWM';
NET_NAME
'PVDDCR_CPU0_P0_PWM6'
 '@T6G_MB_LIB.T6G(SCH_1):PVDDCR_CPU0_P0_PWM6':
 C_SIGNAL='@t6g_mb_lib.t6g(sch_1):pvddcr_cpu0_p0_pwm6';
NODE_NAME     PU42 7
 '@T6G_MB_LIB.T6G(SCH_1):PAGE168_I135@PURE_QUANTA.RAA229620GNPHA0(CHIPS)':
 'PWM6': CDS_PINID='PWM6';
NODE_NAME     PU10 34
 '@T6G_MB_LIB.T6G(SCH_1):PAGE171_I73@PURE_QUANTA.ISL99390FRZTR5935(CHIPS)':
 'PWM': CDS_PINID='PWM';
NET_NAME
'PVDDCR_CPU0_P0_RESET_N'
 '@T6G_MB_LIB.T6G(SCH_1):PVDDCR_CPU0_P0_RESET_N':
 C_SIGNAL='@t6g_mb_lib.t6g(sch_1):pvddcr_cpu0_p0_reset_n';
NODE_NAME     U29 6
 '@T6G_MB_LIB.T6G(SCH_1):PAGE77_I15@PURE_QUANTA.SN74LVC2G07DCKR(CHIPS)':
 '1Y': CDS_PINID='\1y\';
NODE_NAME     R315 1
 '@T6G_MB_LIB.T6G(SCH_1):PAGE168_I57@PURE_QUANTA.Q_RES(CHIPS)':
 'A': CDS_PINID='A';
NET_NAME
'PVDDCR_CPU0_P0_RESET_N_R'
 '@T6G_MB_LIB.T6G(SCH_1):PVDDCR_CPU0_P0_RESET_N_R':
 C_SIGNAL='@t6g_mb_lib.t6g(sch_1):pvddcr_cpu0_p0_reset_n_r';
NODE_NAME     R8317 2
 '@T6G_MB_LIB.T6G(SCH_1):PAGE168_I42@PURE_QUANTA.Q_RES(CHIPS)':
 'B': CDS_PINID='B';
NODE_NAME     R315 2
 '@T6G_MB_LIB.T6G(SCH_1):PAGE168_I57@PURE_QUANTA.Q_RES(CHIPS)':
 'B': CDS_PINID='B';
NODE_NAME     PU42 18
 '@T6G_MB_LIB.T6G(SCH_1):PAGE168_I135@PURE_QUANTA.RAA229620GNPHA0(CHIPS)':
 'RESET_L': CDS_PINID='RESET_L';
NET_NAME
'PVDDCR_CPU0_P0_TEMP0'
 '@T6G_MB_LIB.T6G(SCH_1):PVDDCR_CPU0_P0_TEMP0':
 C_SIGNAL='@t6g_mb_lib.t6g(sch_1):pvddcr_cpu0_p0_temp0';
NODE_NAME     PU43 36
 '@T6G_MB_LIB.T6G(SCH_1):PAGE169_I16@PURE_QUANTA.ISL99390FRZTR5935(CHIPS)':
 'TOUT_FLT': CDS_PINID='TOUT_FLT';
NODE_NAME     PU6 36
 '@T6G_MB_LIB.T6G(SCH_1):PAGE169_I26@PURE_QUANTA.ISL99390FRZTR5935(CHIPS)':
 'TOUT_FLT': CDS_PINID='TOUT_FLT';
NODE_NAME     PC469 1
 '@T6G_MB_LIB.T6G(SCH_1):PAGE168_I95@PURE_QUANTA.Q_CAP(CHIPS)':
 'A': CDS_PINID='A';
NODE_NAME     PU42 44
 '@T6G_MB_LIB.T6G(SCH_1):PAGE168_I135@PURE_QUANTA.RAA229620GNPHA0(CHIPS)':
 'TEMP0': CDS_PINID='TEMP0';
NODE_NAME     PU47 36
 '@T6G_MB_LIB.T6G(SCH_1):PAGE170_I9@PURE_QUANTA.ISL99390FRZTR5935(CHIPS)':
 'TOUT_FLT': CDS_PINID='TOUT_FLT';
NODE_NAME     PU46 36
 '@T6G_MB_LIB.T6G(SCH_1):PAGE170_I38@PURE_QUANTA.ISL99390FRZTR5935(CHIPS)':
 'TOUT_FLT': CDS_PINID='TOUT_FLT';
NODE_NAME     PU48 36
 '@T6G_MB_LIB.T6G(SCH_1):PAGE171_I18@PURE_QUANTA.ISL99390FRZTR5935(CHIPS)':
 'TOUT_FLT': CDS_PINID='TOUT_FLT';
NODE_NAME     PU10 36
 '@T6G_MB_LIB.T6G(SCH_1):PAGE171_I73@PURE_QUANTA.ISL99390FRZTR5935(CHIPS)':
 'TOUT_FLT': CDS_PINID='TOUT_FLT';
NET_NAME
'PVDDCR_CPU0_P0_VCC'
 '@T6G_MB_LIB.T6G(SCH_1):PVDDCR_CPU0_P0_VCC':
 C_SIGNAL='@t6g_mb_lib.t6g(sch_1):pvddcr_cpu0_p0_vcc';
NODE_NAME     PC12 1
 '@T6G_MB_LIB.T6G(SCH_1):PAGE168_I120@PURE_QUANTA.Q_CAP(CHIPS)':
 'A': CDS_PINID='A';
NODE_NAME     PC471 1
 '@T6G_MB_LIB.T6G(SCH_1):PAGE168_I131@PURE_QUANTA.Q_CAP(CHIPS)':
 'A': CDS_PINID='A';
NODE_NAME     PR316 1
 '@T6G_MB_LIB.T6G(SCH_1):PAGE168_I133@PURE_QUANTA.Q_RES(CHIPS)':
 'A': CDS_PINID='A';
NODE_NAME     PU42 47
 '@T6G_MB_LIB.T6G(SCH_1):PAGE168_I135@PURE_QUANTA.RAA229620GNPHA0(CHIPS)':
 'VCC': CDS_PINID='VCC';
NET_NAME
'PVDDCR_CPU0_P0_VCC1'
 '@T6G_MB_LIB.T6G(SCH_1):PVDDCR_CPU0_P0_VCC1':
 C_SIGNAL='@t6g_mb_lib.t6g(sch_1):pvddcr_cpu0_p0_vcc1';
NODE_NAME     PU6 35
 '@T6G_MB_LIB.T6G(SCH_1):PAGE169_I26@PURE_QUANTA.ISL99390FRZTR5935(CHIPS)':
 'EN': CDS_PINID='EN';
NODE_NAME     PU6 3
 '@T6G_MB_LIB.T6G(SCH_1):PAGE169_I26@PURE_QUANTA.ISL99390FRZTR5935(CHIPS)':
 'VCC': CDS_PINID='VCC';
NODE_NAME     PC475 1
 '@T6G_MB_LIB.T6G(SCH_1):PAGE169_I45@PURE_QUANTA.Q_CAP(CHIPS)':
 'A': CDS_PINID='A';
NODE_NAME     PR318 2
 '@T6G_MB_LIB.T6G(SCH_1):PAGE169_I49@PURE_QUANTA.Q_RES(CHIPS)':
 'B': CDS_PINID='B';
NET_NAME
'PVDDCR_CPU0_P0_VCC2'
 '@T6G_MB_LIB.T6G(SCH_1):PVDDCR_CPU0_P0_VCC2':
 C_SIGNAL='@t6g_mb_lib.t6g(sch_1):pvddcr_cpu0_p0_vcc2';
NODE_NAME     PU43 35
 '@T6G_MB_LIB.T6G(SCH_1):PAGE169_I16@PURE_QUANTA.ISL99390FRZTR5935(CHIPS)':
 'EN': CDS_PINID='EN';
NODE_NAME     PU43 3
 '@T6G_MB_LIB.T6G(SCH_1):PAGE169_I16@PURE_QUANTA.ISL99390FRZTR5935(CHIPS)':
 'VCC': CDS_PINID='VCC';
NODE_NAME     PR319 2
 '@T6G_MB_LIB.T6G(SCH_1):PAGE169_I17@PURE_QUANTA.Q_RES(CHIPS)':
 'B': CDS_PINID='B';
NODE_NAME     PC476 1
 '@T6G_MB_LIB.T6G(SCH_1):PAGE169_I14@PURE_QUANTA.Q_CAP(CHIPS)':
 'A': CDS_PINID='A';
NET_NAME
'PVDDCR_CPU0_P0_VCC3'
 '@T6G_MB_LIB.T6G(SCH_1):PVDDCR_CPU0_P0_VCC3':
 C_SIGNAL='@t6g_mb_lib.t6g(sch_1):pvddcr_cpu0_p0_vcc3';
NODE_NAME     PC546 1
 '@T6G_MB_LIB.T6G(SCH_1):PAGE170_I36@PURE_QUANTA.Q_CAP(CHIPS)':
 'A': CDS_PINID='A';
NODE_NAME     PR344 2
 '@T6G_MB_LIB.T6G(SCH_1):PAGE170_I37@PURE_QUANTA.Q_RES(CHIPS)':
 'B': CDS_PINID='B';
NODE_NAME     PU46 35
 '@T6G_MB_LIB.T6G(SCH_1):PAGE170_I38@PURE_QUANTA.ISL99390FRZTR5935(CHIPS)':
 'EN': CDS_PINID='EN';
NODE_NAME     PU46 3
 '@T6G_MB_LIB.T6G(SCH_1):PAGE170_I38@PURE_QUANTA.ISL99390FRZTR5935(CHIPS)':
 'VCC': CDS_PINID='VCC';
NET_NAME
'PVDDCR_CPU0_P0_VCC4'
 '@T6G_MB_LIB.T6G(SCH_1):PVDDCR_CPU0_P0_VCC4':
 C_SIGNAL='@t6g_mb_lib.t6g(sch_1):pvddcr_cpu0_p0_vcc4';
NODE_NAME     PC547 1
 '@T6G_MB_LIB.T6G(SCH_1):PAGE170_I6@PURE_QUANTA.Q_CAP(CHIPS)':
 'A': CDS_PINID='A';
NODE_NAME     PU47 35
 '@T6G_MB_LIB.T6G(SCH_1):PAGE170_I9@PURE_QUANTA.ISL99390FRZTR5935(CHIPS)':
 'EN': CDS_PINID='EN';
NODE_NAME     PU47 3
 '@T6G_MB_LIB.T6G(SCH_1):PAGE170_I9@PURE_QUANTA.ISL99390FRZTR5935(CHIPS)':
 'VCC': CDS_PINID='VCC';
NODE_NAME     PR345 2
 '@T6G_MB_LIB.T6G(SCH_1):PAGE170_I12@PURE_QUANTA.Q_RES(CHIPS)':
 'B': CDS_PINID='B';
NET_NAME
'PVDDCR_CPU0_P0_VCC5'
 '@T6G_MB_LIB.T6G(SCH_1):PVDDCR_CPU0_P0_VCC5':
 C_SIGNAL='@t6g_mb_lib.t6g(sch_1):pvddcr_cpu0_p0_vcc5';
NODE_NAME     PU48 35
 '@T6G_MB_LIB.T6G(SCH_1):PAGE171_I18@PURE_QUANTA.ISL99390FRZTR5935(CHIPS)':
 'EN': CDS_PINID='EN';
NODE_NAME     PU48 3
 '@T6G_MB_LIB.T6G(SCH_1):PAGE171_I18@PURE_QUANTA.ISL99390FRZTR5935(CHIPS)':
 'VCC': CDS_PINID='VCC';
NODE_NAME     PC567 1
 '@T6G_MB_LIB.T6G(SCH_1):PAGE171_I38@PURE_QUANTA.Q_CAP(CHIPS)':
 'A': CDS_PINID='A';
NODE_NAME     PR352 2
 '@T6G_MB_LIB.T6G(SCH_1):PAGE171_I40@PURE_QUANTA.Q_RES(CHIPS)':
 'B': CDS_PINID='B';
NET_NAME
'PVDDCR_CPU0_P0_VCC6'
 '@T6G_MB_LIB.T6G(SCH_1):PVDDCR_CPU0_P0_VCC6':
 C_SIGNAL='@t6g_mb_lib.t6g(sch_1):pvddcr_cpu0_p0_vcc6';
NODE_NAME     PC151 1
 '@T6G_MB_LIB.T6G(SCH_1):PAGE171_I11@PURE_QUANTA.Q_CAP(CHIPS)':
 'A': CDS_PINID='A';
NODE_NAME     PR430 2
 '@T6G_MB_LIB.T6G(SCH_1):PAGE171_I13@PURE_QUANTA.Q_RES(CHIPS)':
 'B': CDS_PINID='B';
NODE_NAME     PU10 35
 '@T6G_MB_LIB.T6G(SCH_1):PAGE171_I73@PURE_QUANTA.ISL99390FRZTR5935(CHIPS)':
 'EN': CDS_PINID='EN';
NODE_NAME     PU10 3
 '@T6G_MB_LIB.T6G(SCH_1):PAGE171_I73@PURE_QUANTA.ISL99390FRZTR5935(CHIPS)':
 'VCC': CDS_PINID='VCC';
NET_NAME
'PVDDCR_CPU0_P0_VCCS'
 '@T6G_MB_LIB.T6G(SCH_1):PVDDCR_CPU0_P0_VCCS':
 C_SIGNAL='@t6g_mb_lib.t6g(sch_1):pvddcr_cpu0_p0_vccs';
NODE_NAME     PC13 1
 '@T6G_MB_LIB.T6G(SCH_1):PAGE168_I118@PURE_QUANTA.Q_CAP(CHIPS)':
 'A': CDS_PINID='A';
NODE_NAME     PU43 39
 '@T6G_MB_LIB.T6G(SCH_1):PAGE169_I16@PURE_QUANTA.ISL99390FRZTR5935(CHIPS)':
 'REFIN': CDS_PINID='REFIN';
NODE_NAME     PU6 39
 '@T6G_MB_LIB.T6G(SCH_1):PAGE169_I26@PURE_QUANTA.ISL99390FRZTR5935(CHIPS)':
 'REFIN': CDS_PINID='REFIN';
NODE_NAME     PC578_8 1
 '@T6G_MB_LIB.T6G(SCH_1):PAGE173_I4@PURE_QUANTA.Q_CAP(CHIPS)':
 'A': CDS_PINID='A';
NODE_NAME     PC577_7 1
 '@T6G_MB_LIB.T6G(SCH_1):PAGE173_I29@PURE_QUANTA.Q_CAP(CHIPS)':
 'A': CDS_PINID='A';
NODE_NAME     PU51 39
 '@T6G_MB_LIB.T6G(SCH_1):PAGE174_I38@PURE_QUANTA.ISL99390FRZTR5935(CHIPS)':
 'REFIN': CDS_PINID='REFIN';
NODE_NAME     PC470 1
 '@T6G_MB_LIB.T6G(SCH_1):PAGE168_I129@PURE_QUANTA.Q_CAP(CHIPS)':
 'A': CDS_PINID='A';
NODE_NAME     PU42 48
 '@T6G_MB_LIB.T6G(SCH_1):PAGE168_I135@PURE_QUANTA.RAA229620GNPHA0(CHIPS)':
 'VCCS': CDS_PINID='VCCS';
NODE_NAME     PC474_2 1
 '@T6G_MB_LIB.T6G(SCH_1):PAGE169_I8@PURE_QUANTA.Q_CAP(CHIPS)':
 'A': CDS_PINID='A';
NODE_NAME     PC473_1 1
 '@T6G_MB_LIB.T6G(SCH_1):PAGE169_I22@PURE_QUANTA.Q_CAP(CHIPS)':
 'A': CDS_PINID='A';
NODE_NAME     PC545_4 1
 '@T6G_MB_LIB.T6G(SCH_1):PAGE170_I2@PURE_QUANTA.Q_CAP(CHIPS)':
 'A': CDS_PINID='A';
NODE_NAME     PU47 39
 '@T6G_MB_LIB.T6G(SCH_1):PAGE170_I9@PURE_QUANTA.ISL99390FRZTR5935(CHIPS)':
 'REFIN': CDS_PINID='REFIN';
NODE_NAME     PC544_3 1
 '@T6G_MB_LIB.T6G(SCH_1):PAGE170_I27@PURE_QUANTA.Q_CAP(CHIPS)':
 'A': CDS_PINID='A';
NODE_NAME     PU46 39
 '@T6G_MB_LIB.T6G(SCH_1):PAGE170_I38@PURE_QUANTA.ISL99390FRZTR5935(CHIPS)':
 'REFIN': CDS_PINID='REFIN';
NODE_NAME     PC150_6 1
 '@T6G_MB_LIB.T6G(SCH_1):PAGE171_I4@PURE_QUANTA.Q_CAP(CHIPS)':
 'A': CDS_PINID='A';
NODE_NAME     PU48 39
 '@T6G_MB_LIB.T6G(SCH_1):PAGE171_I18@PURE_QUANTA.ISL99390FRZTR5935(CHIPS)':
 'REFIN': CDS_PINID='REFIN';
NODE_NAME     PC566_5 1
 '@T6G_MB_LIB.T6G(SCH_1):PAGE171_I33@PURE_QUANTA.Q_CAP(CHIPS)':
 'A': CDS_PINID='A';
NODE_NAME     PU10 39
 '@T6G_MB_LIB.T6G(SCH_1):PAGE171_I73@PURE_QUANTA.ISL99390FRZTR5935(CHIPS)':
 'REFIN': CDS_PINID='REFIN';
NODE_NAME     PU49 39
 '@T6G_MB_LIB.T6G(SCH_1):PAGE173_I41@PURE_QUANTA.ISL99390FRZTR5935(CHIPS)':
 'REFIN': CDS_PINID='REFIN';
NODE_NAME     PU50 39
 '@T6G_MB_LIB.T6G(SCH_1):PAGE173_I86@PURE_QUANTA.ISL99390FRZTR5935(CHIPS)':
 'REFIN': CDS_PINID='REFIN';
NODE_NAME     PC605_9 1
 '@T6G_MB_LIB.T6G(SCH_1):PAGE174_I2@PURE_QUANTA.Q_CAP(CHIPS)':
 'A': CDS_PINID='A';
NET_NAME
'PVDDCR_CPU0_P0_VINSEN'
 '@T6G_MB_LIB.T6G(SCH_1):PVDDCR_CPU0_P0_VINSEN':
 C_SIGNAL='@t6g_mb_lib.t6g(sch_1):pvddcr_cpu0_p0_vinsen';
NODE_NAME     PR599 1
 '@T6G_MB_LIB.T6G(SCH_1):PAGE168_I47@PURE_QUANTA.Q_RES(CHIPS)':
 'A': CDS_PINID='A';
NODE_NAME     PR314 2
 '@T6G_MB_LIB.T6G(SCH_1):PAGE168_I48@PURE_QUANTA.Q_RES(CHIPS)':
 'B': CDS_PINID='B';
NODE_NAME     PC7 1
 '@T6G_MB_LIB.T6G(SCH_1):PAGE168_I50@PURE_QUANTA.Q_CAP(CHIPS)':
 'A': CDS_PINID='A';
NODE_NAME     PU42 46
 '@T6G_MB_LIB.T6G(SCH_1):PAGE168_I135@PURE_QUANTA.RAA229620GNPHA0(CHIPS)':
 'VINSEN': CDS_PINID='VINSEN';
NET_NAME
'PVDDCR_CPU0_P0_VMON'
 '@T6G_MB_LIB.T6G(SCH_1):PVDDCR_CPU0_P0_VMON':
 C_SIGNAL='@t6g_mb_lib.t6g(sch_1):pvddcr_cpu0_p0_vmon';
NODE_NAME     PR290 2
 '@T6G_MB_LIB.T6G(SCH_1):PAGE168_I15@PURE_QUANTA.Q_RES(CHIPS)':
 'B': CDS_PINID='B';
NODE_NAME     PR5 1
 '@T6G_MB_LIB.T6G(SCH_1):PAGE168_I21@PURE_QUANTA.Q_RES(CHIPS)':
 'A': CDS_PINID='A';
NODE_NAME     PC462 1
 '@T6G_MB_LIB.T6G(SCH_1):PAGE168_I23@PURE_QUANTA.Q_CAP(CHIPS)':
 'A': CDS_PINID='A';
NODE_NAME     PU42 45
 '@T6G_MB_LIB.T6G(SCH_1):PAGE168_I135@PURE_QUANTA.RAA229620GNPHA0(CHIPS)':
 'VMON||IINSEN': CDS_PINID='\vmon||iinsen\';
NET_NAME
'PVDDCR_CPU0_P0_VOS1'
 '@T6G_MB_LIB.T6G(SCH_1):PVDDCR_CPU0_P0_VOS1':
 C_SIGNAL='@t6g_mb_lib.t6g(sch_1):pvddcr_cpu0_p0_vos1';
NODE_NAME     PU6 1
 '@T6G_MB_LIB.T6G(SCH_1):PAGE169_I26@PURE_QUANTA.ISL99390FRZTR5935(CHIPS)':
 'VOS': CDS_PINID='VOS';
NODE_NAME     PR324 1
 '@T6G_MB_LIB.T6G(SCH_1):PAGE169_I43@PURE_QUANTA.Q_RES(CHIPS)':
 'A': CDS_PINID='A';
NET_NAME
'PVDDCR_CPU0_P0_VOS2'
 '@T6G_MB_LIB.T6G(SCH_1):PVDDCR_CPU0_P0_VOS2':
 C_SIGNAL='@t6g_mb_lib.t6g(sch_1):pvddcr_cpu0_p0_vos2';
NODE_NAME     PU43 1
 '@T6G_MB_LIB.T6G(SCH_1):PAGE169_I16@PURE_QUANTA.ISL99390FRZTR5935(CHIPS)':
 'VOS': CDS_PINID='VOS';
NODE_NAME     PR325 1
 '@T6G_MB_LIB.T6G(SCH_1):PAGE169_I30@PURE_QUANTA.Q_RES(CHIPS)':
 'A': CDS_PINID='A';
NET_NAME
'PVDDCR_CPU0_P0_VOS3'
 '@T6G_MB_LIB.T6G(SCH_1):PVDDCR_CPU0_P0_VOS3':
 C_SIGNAL='@t6g_mb_lib.t6g(sch_1):pvddcr_cpu0_p0_vos3';
NODE_NAME     PR350 1
 '@T6G_MB_LIB.T6G(SCH_1):PAGE170_I26@PURE_QUANTA.Q_RES(CHIPS)':
 'A': CDS_PINID='A';
NODE_NAME     PU46 1
 '@T6G_MB_LIB.T6G(SCH_1):PAGE170_I38@PURE_QUANTA.ISL99390FRZTR5935(CHIPS)':
 'VOS': CDS_PINID='VOS';
NET_NAME
'PVDDCR_CPU0_P0_VOS4'
 '@T6G_MB_LIB.T6G(SCH_1):PVDDCR_CPU0_P0_VOS4':
 C_SIGNAL='@t6g_mb_lib.t6g(sch_1):pvddcr_cpu0_p0_vos4';
NODE_NAME     PU47 1
 '@T6G_MB_LIB.T6G(SCH_1):PAGE170_I9@PURE_QUANTA.ISL99390FRZTR5935(CHIPS)':
 'VOS': CDS_PINID='VOS';
NODE_NAME     PR351 1
 '@T6G_MB_LIB.T6G(SCH_1):PAGE170_I50@PURE_QUANTA.Q_RES(CHIPS)':
 'A': CDS_PINID='A';
NET_NAME
'PVDDCR_CPU0_P0_VOS5'
 '@T6G_MB_LIB.T6G(SCH_1):PVDDCR_CPU0_P0_VOS5':
 C_SIGNAL='@t6g_mb_lib.t6g(sch_1):pvddcr_cpu0_p0_vos5';
NODE_NAME     PU48 1
 '@T6G_MB_LIB.T6G(SCH_1):PAGE171_I18@PURE_QUANTA.ISL99390FRZTR5935(CHIPS)':
 'VOS': CDS_PINID='VOS';
NODE_NAME     PR355 1
 '@T6G_MB_LIB.T6G(SCH_1):PAGE171_I32@PURE_QUANTA.Q_RES(CHIPS)':
 'A': CDS_PINID='A';
NET_NAME
'PVDDCR_CPU0_P0_VOS6'
 '@T6G_MB_LIB.T6G(SCH_1):PVDDCR_CPU0_P0_VOS6':
 C_SIGNAL='@t6g_mb_lib.t6g(sch_1):pvddcr_cpu0_p0_vos6';
NODE_NAME     PR433 1
 '@T6G_MB_LIB.T6G(SCH_1):PAGE171_I21@PURE_QUANTA.Q_RES(CHIPS)':
 'A': CDS_PINID='A';
NODE_NAME     PU10 1
 '@T6G_MB_LIB.T6G(SCH_1):PAGE171_I73@PURE_QUANTA.ISL99390FRZTR5935(CHIPS)':
 'VOS': CDS_PINID='VOS';
NET_NAME
'PVDDCR_CPU0_P1'
 '@T6G_MB_LIB.T6G(SCH_1):PVDDCR_CPU0_P1':
 C_SIGNAL='@t6g_mb_lib.t6g(sch_1):pvddcr_cpu0_p1',
 CDS_GLOBAL_NET='TRUE';
NODE_NAME     U26 AB23
 '@T6G_MB_LIB.T6G(SCH_1):PAGE57_I29@PURE_QUANTA.GENOA_SP5(CHIPS)':
 'VDDCR_CPU0_AB23': CDS_PINID='VDDCR_CPU0_AB23';
NODE_NAME     U26 AB24
 '@T6G_MB_LIB.T6G(SCH_1):PAGE57_I29@PURE_QUANTA.GENOA_SP5(CHIPS)':
 'VDDCR_CPU0_AB24': CDS_PINID='VDDCR_CPU0_AB24';
NODE_NAME     U26 AB26
 '@T6G_MB_LIB.T6G(SCH_1):PAGE57_I29@PURE_QUANTA.GENOA_SP5(CHIPS)':
 'VDDCR_CPU0_AB26': CDS_PINID='VDDCR_CPU0_AB26';
NODE_NAME     U26 AB27
 '@T6G_MB_LIB.T6G(SCH_1):PAGE57_I29@PURE_QUANTA.GENOA_SP5(CHIPS)':
 'VDDCR_CPU0_AB27': CDS_PINID='VDDCR_CPU0_AB27';
NODE_NAME     U26 AB29
 '@T6G_MB_LIB.T6G(SCH_1):PAGE57_I29@PURE_QUANTA.GENOA_SP5(CHIPS)':
 'VDDCR_CPU0_AB29': CDS_PINID='VDDCR_CPU0_AB29';
NODE_NAME     U26 AB30
 '@T6G_MB_LIB.T6G(SCH_1):PAGE57_I29@PURE_QUANTA.GENOA_SP5(CHIPS)':
 'VDDCR_CPU0_AB30': CDS_PINID='VDDCR_CPU0_AB30';
NODE_NAME     U26 AB32
 '@T6G_MB_LIB.T6G(SCH_1):PAGE57_I29@PURE_QUANTA.GENOA_SP5(CHIPS)':
 'VDDCR_CPU0_AB32': CDS_PINID='VDDCR_CPU0_AB32';
NODE_NAME     U26 AB33
 '@T6G_MB_LIB.T6G(SCH_1):PAGE57_I29@PURE_QUANTA.GENOA_SP5(CHIPS)':
 'VDDCR_CPU0_AB33': CDS_PINID='VDDCR_CPU0_AB33';
NODE_NAME     U26 AB43
 '@T6G_MB_LIB.T6G(SCH_1):PAGE57_I29@PURE_QUANTA.GENOA_SP5(CHIPS)':
 'VDDCR_CPU0_AB43': CDS_PINID='VDDCR_CPU0_AB43';
NODE_NAME     U26 AB44
 '@T6G_MB_LIB.T6G(SCH_1):PAGE57_I29@PURE_QUANTA.GENOA_SP5(CHIPS)':
 'VDDCR_CPU0_AB44': CDS_PINID='VDDCR_CPU0_AB44';
NODE_NAME     U26 AB46
 '@T6G_MB_LIB.T6G(SCH_1):PAGE57_I29@PURE_QUANTA.GENOA_SP5(CHIPS)':
 'VDDCR_CPU0_AB46': CDS_PINID='VDDCR_CPU0_AB46';
NODE_NAME     U26 AB47
 '@T6G_MB_LIB.T6G(SCH_1):PAGE57_I29@PURE_QUANTA.GENOA_SP5(CHIPS)':
 'VDDCR_CPU0_AB47': CDS_PINID='VDDCR_CPU0_AB47';
NODE_NAME     U26 AB49
 '@T6G_MB_LIB.T6G(SCH_1):PAGE57_I29@PURE_QUANTA.GENOA_SP5(CHIPS)':
 'VDDCR_CPU0_AB49': CDS_PINID='VDDCR_CPU0_AB49';
NODE_NAME     U26 AB50
 '@T6G_MB_LIB.T6G(SCH_1):PAGE57_I29@PURE_QUANTA.GENOA_SP5(CHIPS)':
 'VDDCR_CPU0_AB50': CDS_PINID='VDDCR_CPU0_AB50';
NODE_NAME     U26 AB52
 '@T6G_MB_LIB.T6G(SCH_1):PAGE57_I29@PURE_QUANTA.GENOA_SP5(CHIPS)':
 'VDDCR_CPU0_AB52': CDS_PINID='VDDCR_CPU0_AB52';
NODE_NAME     U26 AB53
 '@T6G_MB_LIB.T6G(SCH_1):PAGE57_I29@PURE_QUANTA.GENOA_SP5(CHIPS)':
 'VDDCR_CPU0_AB53': CDS_PINID='VDDCR_CPU0_AB53';
NODE_NAME     U26 AC35
 '@T6G_MB_LIB.T6G(SCH_1):PAGE57_I29@PURE_QUANTA.GENOA_SP5(CHIPS)':
 'VDDCR_CPU0_AC35': CDS_PINID='VDDCR_CPU0_AC35';
NODE_NAME     U26 AC36
 '@T6G_MB_LIB.T6G(SCH_1):PAGE57_I29@PURE_QUANTA.GENOA_SP5(CHIPS)':
 'VDDCR_CPU0_AC36': CDS_PINID='VDDCR_CPU0_AC36';
NODE_NAME     U26 AC40
 '@T6G_MB_LIB.T6G(SCH_1):PAGE57_I29@PURE_QUANTA.GENOA_SP5(CHIPS)':
 'VDDCR_CPU0_AC40': CDS_PINID='VDDCR_CPU0_AC40';
NODE_NAME     U26 AC41
 '@T6G_MB_LIB.T6G(SCH_1):PAGE57_I29@PURE_QUANTA.GENOA_SP5(CHIPS)':
 'VDDCR_CPU0_AC41': CDS_PINID='VDDCR_CPU0_AC41';
NODE_NAME     U26 AF23
 '@T6G_MB_LIB.T6G(SCH_1):PAGE57_I29@PURE_QUANTA.GENOA_SP5(CHIPS)':
 'VDDCR_CPU0_AF23': CDS_PINID='VDDCR_CPU0_AF23';
NODE_NAME     U26 AF24
 '@T6G_MB_LIB.T6G(SCH_1):PAGE57_I29@PURE_QUANTA.GENOA_SP5(CHIPS)':
 'VDDCR_CPU0_AF24': CDS_PINID='VDDCR_CPU0_AF24';
NODE_NAME     U26 AF26
 '@T6G_MB_LIB.T6G(SCH_1):PAGE57_I29@PURE_QUANTA.GENOA_SP5(CHIPS)':
 'VDDCR_CPU0_AF26': CDS_PINID='VDDCR_CPU0_AF26';
NODE_NAME     U26 AF27
 '@T6G_MB_LIB.T6G(SCH_1):PAGE57_I29@PURE_QUANTA.GENOA_SP5(CHIPS)':
 'VDDCR_CPU0_AF27': CDS_PINID='VDDCR_CPU0_AF27';
NODE_NAME     U26 AF29
 '@T6G_MB_LIB.T6G(SCH_1):PAGE57_I29@PURE_QUANTA.GENOA_SP5(CHIPS)':
 'VDDCR_CPU0_AF29': CDS_PINID='VDDCR_CPU0_AF29';
NODE_NAME     U26 AF30
 '@T6G_MB_LIB.T6G(SCH_1):PAGE57_I29@PURE_QUANTA.GENOA_SP5(CHIPS)':
 'VDDCR_CPU0_AF30': CDS_PINID='VDDCR_CPU0_AF30';
NODE_NAME     U26 AF32
 '@T6G_MB_LIB.T6G(SCH_1):PAGE57_I29@PURE_QUANTA.GENOA_SP5(CHIPS)':
 'VDDCR_CPU0_AF32': CDS_PINID='VDDCR_CPU0_AF32';
NODE_NAME     U26 AF33
 '@T6G_MB_LIB.T6G(SCH_1):PAGE57_I29@PURE_QUANTA.GENOA_SP5(CHIPS)':
 'VDDCR_CPU0_AF33': CDS_PINID='VDDCR_CPU0_AF33';
NODE_NAME     U26 AF43
 '@T6G_MB_LIB.T6G(SCH_1):PAGE57_I29@PURE_QUANTA.GENOA_SP5(CHIPS)':
 'VDDCR_CPU0_AF43': CDS_PINID='VDDCR_CPU0_AF43';
NODE_NAME     U26 AF44
 '@T6G_MB_LIB.T6G(SCH_1):PAGE57_I29@PURE_QUANTA.GENOA_SP5(CHIPS)':
 'VDDCR_CPU0_AF44': CDS_PINID='VDDCR_CPU0_AF44';
NODE_NAME     U26 AF46
 '@T6G_MB_LIB.T6G(SCH_1):PAGE57_I29@PURE_QUANTA.GENOA_SP5(CHIPS)':
 'VDDCR_CPU0_AF46': CDS_PINID='VDDCR_CPU0_AF46';
NODE_NAME     U26 AF47
 '@T6G_MB_LIB.T6G(SCH_1):PAGE57_I29@PURE_QUANTA.GENOA_SP5(CHIPS)':
 'VDDCR_CPU0_AF47': CDS_PINID='VDDCR_CPU0_AF47';
NODE_NAME     U26 AF49
 '@T6G_MB_LIB.T6G(SCH_1):PAGE57_I29@PURE_QUANTA.GENOA_SP5(CHIPS)':
 'VDDCR_CPU0_AF49': CDS_PINID='VDDCR_CPU0_AF49';
NODE_NAME     U26 AF50
 '@T6G_MB_LIB.T6G(SCH_1):PAGE57_I29@PURE_QUANTA.GENOA_SP5(CHIPS)':
 'VDDCR_CPU0_AF50': CDS_PINID='VDDCR_CPU0_AF50';
NODE_NAME     U26 AF52
 '@T6G_MB_LIB.T6G(SCH_1):PAGE57_I29@PURE_QUANTA.GENOA_SP5(CHIPS)':
 'VDDCR_CPU0_AF52': CDS_PINID='VDDCR_CPU0_AF52';
NODE_NAME     U26 AF53
 '@T6G_MB_LIB.T6G(SCH_1):PAGE57_I29@PURE_QUANTA.GENOA_SP5(CHIPS)':
 'VDDCR_CPU0_AF53': CDS_PINID='VDDCR_CPU0_AF53';
NODE_NAME     U26 AG35
 '@T6G_MB_LIB.T6G(SCH_1):PAGE57_I29@PURE_QUANTA.GENOA_SP5(CHIPS)':
 'VDDCR_CPU0_AG35': CDS_PINID='VDDCR_CPU0_AG35';
NODE_NAME     U26 AG36
 '@T6G_MB_LIB.T6G(SCH_1):PAGE57_I29@PURE_QUANTA.GENOA_SP5(CHIPS)':
 'VDDCR_CPU0_AG36': CDS_PINID='VDDCR_CPU0_AG36';
NODE_NAME     U26 AG40
 '@T6G_MB_LIB.T6G(SCH_1):PAGE57_I29@PURE_QUANTA.GENOA_SP5(CHIPS)':
 'VDDCR_CPU0_AG40': CDS_PINID='VDDCR_CPU0_AG40';
NODE_NAME     U26 AG41
 '@T6G_MB_LIB.T6G(SCH_1):PAGE57_I29@PURE_QUANTA.GENOA_SP5(CHIPS)':
 'VDDCR_CPU0_AG41': CDS_PINID='VDDCR_CPU0_AG41';
NODE_NAME     U26 AK23
 '@T6G_MB_LIB.T6G(SCH_1):PAGE57_I29@PURE_QUANTA.GENOA_SP5(CHIPS)':
 'VDDCR_CPU0_AK23': CDS_PINID='VDDCR_CPU0_AK23';
NODE_NAME     U26 AK24
 '@T6G_MB_LIB.T6G(SCH_1):PAGE57_I29@PURE_QUANTA.GENOA_SP5(CHIPS)':
 'VDDCR_CPU0_AK24': CDS_PINID='VDDCR_CPU0_AK24';
NODE_NAME     U26 AK26
 '@T6G_MB_LIB.T6G(SCH_1):PAGE57_I29@PURE_QUANTA.GENOA_SP5(CHIPS)':
 'VDDCR_CPU0_AK26': CDS_PINID='VDDCR_CPU0_AK26';
NODE_NAME     U26 AK27
 '@T6G_MB_LIB.T6G(SCH_1):PAGE57_I29@PURE_QUANTA.GENOA_SP5(CHIPS)':
 'VDDCR_CPU0_AK27': CDS_PINID='VDDCR_CPU0_AK27';
NODE_NAME     U26 AK29
 '@T6G_MB_LIB.T6G(SCH_1):PAGE57_I29@PURE_QUANTA.GENOA_SP5(CHIPS)':
 'VDDCR_CPU0_AK29': CDS_PINID='VDDCR_CPU0_AK29';
NODE_NAME     U26 AK30
 '@T6G_MB_LIB.T6G(SCH_1):PAGE57_I29@PURE_QUANTA.GENOA_SP5(CHIPS)':
 'VDDCR_CPU0_AK30': CDS_PINID='VDDCR_CPU0_AK30';
NODE_NAME     U26 AK32
 '@T6G_MB_LIB.T6G(SCH_1):PAGE57_I29@PURE_QUANTA.GENOA_SP5(CHIPS)':
 'VDDCR_CPU0_AK32': CDS_PINID='VDDCR_CPU0_AK32';
NODE_NAME     U26 AK33
 '@T6G_MB_LIB.T6G(SCH_1):PAGE57_I29@PURE_QUANTA.GENOA_SP5(CHIPS)':
 'VDDCR_CPU0_AK33': CDS_PINID='VDDCR_CPU0_AK33';
NODE_NAME     U26 AK43
 '@T6G_MB_LIB.T6G(SCH_1):PAGE57_I29@PURE_QUANTA.GENOA_SP5(CHIPS)':
 'VDDCR_CPU0_AK43': CDS_PINID='VDDCR_CPU0_AK43';
NODE_NAME     U26 AK44
 '@T6G_MB_LIB.T6G(SCH_1):PAGE57_I29@PURE_QUANTA.GENOA_SP5(CHIPS)':
 'VDDCR_CPU0_AK44': CDS_PINID='VDDCR_CPU0_AK44';
NODE_NAME     U26 AK46
 '@T6G_MB_LIB.T6G(SCH_1):PAGE57_I29@PURE_QUANTA.GENOA_SP5(CHIPS)':
 'VDDCR_CPU0_AK46': CDS_PINID='VDDCR_CPU0_AK46';
NODE_NAME     U26 AK47
 '@T6G_MB_LIB.T6G(SCH_1):PAGE57_I29@PURE_QUANTA.GENOA_SP5(CHIPS)':
 'VDDCR_CPU0_AK47': CDS_PINID='VDDCR_CPU0_AK47';
NODE_NAME     U26 AK49
 '@T6G_MB_LIB.T6G(SCH_1):PAGE57_I29@PURE_QUANTA.GENOA_SP5(CHIPS)':
 'VDDCR_CPU0_AK49': CDS_PINID='VDDCR_CPU0_AK49';
NODE_NAME     U26 AK50
 '@T6G_MB_LIB.T6G(SCH_1):PAGE57_I29@PURE_QUANTA.GENOA_SP5(CHIPS)':
 'VDDCR_CPU0_AK50': CDS_PINID='VDDCR_CPU0_AK50';
NODE_NAME     U26 AK52
 '@T6G_MB_LIB.T6G(SCH_1):PAGE57_I29@PURE_QUANTA.GENOA_SP5(CHIPS)':
 'VDDCR_CPU0_AK52': CDS_PINID='VDDCR_CPU0_AK52';
NODE_NAME     U26 AK53
 '@T6G_MB_LIB.T6G(SCH_1):PAGE57_I29@PURE_QUANTA.GENOA_SP5(CHIPS)':
 'VDDCR_CPU0_AK53': CDS_PINID='VDDCR_CPU0_AK53';
NODE_NAME     U26 AL35
 '@T6G_MB_LIB.T6G(SCH_1):PAGE57_I29@PURE_QUANTA.GENOA_SP5(CHIPS)':
 'VDDCR_CPU0_AL35': CDS_PINID='VDDCR_CPU0_AL35';
NODE_NAME     U26 AL36
 '@T6G_MB_LIB.T6G(SCH_1):PAGE57_I29@PURE_QUANTA.GENOA_SP5(CHIPS)':
 'VDDCR_CPU0_AL36': CDS_PINID='VDDCR_CPU0_AL36';
NODE_NAME     U26 AL40
 '@T6G_MB_LIB.T6G(SCH_1):PAGE57_I29@PURE_QUANTA.GENOA_SP5(CHIPS)':
 'VDDCR_CPU0_AL40': CDS_PINID='VDDCR_CPU0_AL40';
NODE_NAME     U26 AL41
 '@T6G_MB_LIB.T6G(SCH_1):PAGE57_I29@PURE_QUANTA.GENOA_SP5(CHIPS)':
 'VDDCR_CPU0_AL41': CDS_PINID='VDDCR_CPU0_AL41';
NODE_NAME     U26 AP23
 '@T6G_MB_LIB.T6G(SCH_1):PAGE57_I29@PURE_QUANTA.GENOA_SP5(CHIPS)':
 'VDDCR_CPU0_AP23': CDS_PINID='VDDCR_CPU0_AP23';
NODE_NAME     U26 AP24
 '@T6G_MB_LIB.T6G(SCH_1):PAGE57_I29@PURE_QUANTA.GENOA_SP5(CHIPS)':
 'VDDCR_CPU0_AP24': CDS_PINID='VDDCR_CPU0_AP24';
NODE_NAME     U26 AP26
 '@T6G_MB_LIB.T6G(SCH_1):PAGE57_I29@PURE_QUANTA.GENOA_SP5(CHIPS)':
 'VDDCR_CPU0_AP26': CDS_PINID='VDDCR_CPU0_AP26';
NODE_NAME     U26 AP27
 '@T6G_MB_LIB.T6G(SCH_1):PAGE57_I29@PURE_QUANTA.GENOA_SP5(CHIPS)':
 'VDDCR_CPU0_AP27': CDS_PINID='VDDCR_CPU0_AP27';
NODE_NAME     U26 AP29
 '@T6G_MB_LIB.T6G(SCH_1):PAGE57_I29@PURE_QUANTA.GENOA_SP5(CHIPS)':
 'VDDCR_CPU0_AP29': CDS_PINID='VDDCR_CPU0_AP29';
NODE_NAME     U26 AP30
 '@T6G_MB_LIB.T6G(SCH_1):PAGE57_I29@PURE_QUANTA.GENOA_SP5(CHIPS)':
 'VDDCR_CPU0_AP30': CDS_PINID='VDDCR_CPU0_AP30';
NODE_NAME     U26 AP32
 '@T6G_MB_LIB.T6G(SCH_1):PAGE57_I29@PURE_QUANTA.GENOA_SP5(CHIPS)':
 'VDDCR_CPU0_AP32': CDS_PINID='VDDCR_CPU0_AP32';
NODE_NAME     U26 AP33
 '@T6G_MB_LIB.T6G(SCH_1):PAGE57_I29@PURE_QUANTA.GENOA_SP5(CHIPS)':
 'VDDCR_CPU0_AP33': CDS_PINID='VDDCR_CPU0_AP33';
NODE_NAME     U26 AP43
 '@T6G_MB_LIB.T6G(SCH_1):PAGE57_I29@PURE_QUANTA.GENOA_SP5(CHIPS)':
 'VDDCR_CPU0_AP43': CDS_PINID='VDDCR_CPU0_AP43';
NODE_NAME     U26 AP44
 '@T6G_MB_LIB.T6G(SCH_1):PAGE57_I29@PURE_QUANTA.GENOA_SP5(CHIPS)':
 'VDDCR_CPU0_AP44': CDS_PINID='VDDCR_CPU0_AP44';
NODE_NAME     U26 AP46
 '@T6G_MB_LIB.T6G(SCH_1):PAGE57_I29@PURE_QUANTA.GENOA_SP5(CHIPS)':
 'VDDCR_CPU0_AP46': CDS_PINID='VDDCR_CPU0_AP46';
NODE_NAME     U26 AP47
 '@T6G_MB_LIB.T6G(SCH_1):PAGE57_I29@PURE_QUANTA.GENOA_SP5(CHIPS)':
 'VDDCR_CPU0_AP47': CDS_PINID='VDDCR_CPU0_AP47';
NODE_NAME     U26 AP49
 '@T6G_MB_LIB.T6G(SCH_1):PAGE57_I29@PURE_QUANTA.GENOA_SP5(CHIPS)':
 'VDDCR_CPU0_AP49': CDS_PINID='VDDCR_CPU0_AP49';
NODE_NAME     U26 AP50
 '@T6G_MB_LIB.T6G(SCH_1):PAGE57_I29@PURE_QUANTA.GENOA_SP5(CHIPS)':
 'VDDCR_CPU0_AP50': CDS_PINID='VDDCR_CPU0_AP50';
NODE_NAME     U26 AP52
 '@T6G_MB_LIB.T6G(SCH_1):PAGE57_I29@PURE_QUANTA.GENOA_SP5(CHIPS)':
 'VDDCR_CPU0_AP52': CDS_PINID='VDDCR_CPU0_AP52';
NODE_NAME     U26 AP53
 '@T6G_MB_LIB.T6G(SCH_1):PAGE57_I29@PURE_QUANTA.GENOA_SP5(CHIPS)':
 'VDDCR_CPU0_AP53': CDS_PINID='VDDCR_CPU0_AP53';
NODE_NAME     U26 AR23
 '@T6G_MB_LIB.T6G(SCH_1):PAGE57_I29@PURE_QUANTA.GENOA_SP5(CHIPS)':
 'VDDCR_CPU0_AR23': CDS_PINID='VDDCR_CPU0_AR23';
NODE_NAME     U26 AR25
 '@T6G_MB_LIB.T6G(SCH_1):PAGE57_I29@PURE_QUANTA.GENOA_SP5(CHIPS)':
 'VDDCR_CPU0_AR25': CDS_PINID='VDDCR_CPU0_AR25';
NODE_NAME     U26 AR27
 '@T6G_MB_LIB.T6G(SCH_1):PAGE57_I29@PURE_QUANTA.GENOA_SP5(CHIPS)':
 'VDDCR_CPU0_AR27': CDS_PINID='VDDCR_CPU0_AR27';
NODE_NAME     U26 AR29
 '@T6G_MB_LIB.T6G(SCH_1):PAGE57_I29@PURE_QUANTA.GENOA_SP5(CHIPS)':
 'VDDCR_CPU0_AR29': CDS_PINID='VDDCR_CPU0_AR29';
NODE_NAME     U26 AR31
 '@T6G_MB_LIB.T6G(SCH_1):PAGE57_I29@PURE_QUANTA.GENOA_SP5(CHIPS)':
 'VDDCR_CPU0_AR31': CDS_PINID='VDDCR_CPU0_AR31';
NODE_NAME     U26 AR33
 '@T6G_MB_LIB.T6G(SCH_1):PAGE57_I29@PURE_QUANTA.GENOA_SP5(CHIPS)':
 'VDDCR_CPU0_AR33': CDS_PINID='VDDCR_CPU0_AR33';
NODE_NAME     U26 AR35
 '@T6G_MB_LIB.T6G(SCH_1):PAGE57_I29@PURE_QUANTA.GENOA_SP5(CHIPS)':
 'VDDCR_CPU0_AR35': CDS_PINID='VDDCR_CPU0_AR35';
NODE_NAME     U26 AR40
 '@T6G_MB_LIB.T6G(SCH_1):PAGE57_I29@PURE_QUANTA.GENOA_SP5(CHIPS)':
 'VDDCR_CPU0_AR40': CDS_PINID='VDDCR_CPU0_AR40';
NODE_NAME     U26 AR42
 '@T6G_MB_LIB.T6G(SCH_1):PAGE57_I29@PURE_QUANTA.GENOA_SP5(CHIPS)':
 'VDDCR_CPU0_AR42': CDS_PINID='VDDCR_CPU0_AR42';
NODE_NAME     U26 AR44
 '@T6G_MB_LIB.T6G(SCH_1):PAGE57_I29@PURE_QUANTA.GENOA_SP5(CHIPS)':
 'VDDCR_CPU0_AR44': CDS_PINID='VDDCR_CPU0_AR44';
NODE_NAME     U26 AR46
 '@T6G_MB_LIB.T6G(SCH_1):PAGE57_I29@PURE_QUANTA.GENOA_SP5(CHIPS)':
 'VDDCR_CPU0_AR46': CDS_PINID='VDDCR_CPU0_AR46';
NODE_NAME     U26 AR48
 '@T6G_MB_LIB.T6G(SCH_1):PAGE57_I29@PURE_QUANTA.GENOA_SP5(CHIPS)':
 'VDDCR_CPU0_AR48': CDS_PINID='VDDCR_CPU0_AR48';
NODE_NAME     U26 AR50
 '@T6G_MB_LIB.T6G(SCH_1):PAGE57_I29@PURE_QUANTA.GENOA_SP5(CHIPS)':
 'VDDCR_CPU0_AR50': CDS_PINID='VDDCR_CPU0_AR50';
NODE_NAME     U26 AT24
 '@T6G_MB_LIB.T6G(SCH_1):PAGE57_I29@PURE_QUANTA.GENOA_SP5(CHIPS)':
 'VDDCR_CPU0_AT24': CDS_PINID='VDDCR_CPU0_AT24';
NODE_NAME     U26 AT26
 '@T6G_MB_LIB.T6G(SCH_1):PAGE57_I29@PURE_QUANTA.GENOA_SP5(CHIPS)':
 'VDDCR_CPU0_AT26': CDS_PINID='VDDCR_CPU0_AT26';
NODE_NAME     U26 AT28
 '@T6G_MB_LIB.T6G(SCH_1):PAGE57_I29@PURE_QUANTA.GENOA_SP5(CHIPS)':
 'VDDCR_CPU0_AT28': CDS_PINID='VDDCR_CPU0_AT28';
NODE_NAME     U26 AT30
 '@T6G_MB_LIB.T6G(SCH_1):PAGE57_I29@PURE_QUANTA.GENOA_SP5(CHIPS)':
 'VDDCR_CPU0_AT30': CDS_PINID='VDDCR_CPU0_AT30';
NODE_NAME     U26 AT32
 '@T6G_MB_LIB.T6G(SCH_1):PAGE57_I29@PURE_QUANTA.GENOA_SP5(CHIPS)':
 'VDDCR_CPU0_AT32': CDS_PINID='VDDCR_CPU0_AT32';
NODE_NAME     U26 AT34
 '@T6G_MB_LIB.T6G(SCH_1):PAGE57_I29@PURE_QUANTA.GENOA_SP5(CHIPS)':
 'VDDCR_CPU0_AT34': CDS_PINID='VDDCR_CPU0_AT34';
NODE_NAME     U26 AT36
 '@T6G_MB_LIB.T6G(SCH_1):PAGE57_I29@PURE_QUANTA.GENOA_SP5(CHIPS)':
 'VDDCR_CPU0_AT36': CDS_PINID='VDDCR_CPU0_AT36';
NODE_NAME     U26 AT39
 '@T6G_MB_LIB.T6G(SCH_1):PAGE57_I29@PURE_QUANTA.GENOA_SP5(CHIPS)':
 'VDDCR_CPU0_AT39': CDS_PINID='VDDCR_CPU0_AT39';
NODE_NAME     U26 AT41
 '@T6G_MB_LIB.T6G(SCH_1):PAGE57_I29@PURE_QUANTA.GENOA_SP5(CHIPS)':
 'VDDCR_CPU0_AT41': CDS_PINID='VDDCR_CPU0_AT41';
NODE_NAME     U26 AT43
 '@T6G_MB_LIB.T6G(SCH_1):PAGE57_I29@PURE_QUANTA.GENOA_SP5(CHIPS)':
 'VDDCR_CPU0_AT43': CDS_PINID='VDDCR_CPU0_AT43';
NODE_NAME     U26 AT45
 '@T6G_MB_LIB.T6G(SCH_1):PAGE57_I29@PURE_QUANTA.GENOA_SP5(CHIPS)':
 'VDDCR_CPU0_AT45': CDS_PINID='VDDCR_CPU0_AT45';
NODE_NAME     U26 AT47
 '@T6G_MB_LIB.T6G(SCH_1):PAGE57_I29@PURE_QUANTA.GENOA_SP5(CHIPS)':
 'VDDCR_CPU0_AT47': CDS_PINID='VDDCR_CPU0_AT47';
NODE_NAME     U26 AT49
 '@T6G_MB_LIB.T6G(SCH_1):PAGE57_I29@PURE_QUANTA.GENOA_SP5(CHIPS)':
 'VDDCR_CPU0_AT49': CDS_PINID='VDDCR_CPU0_AT49';
NODE_NAME     U26 AU25
 '@T6G_MB_LIB.T6G(SCH_1):PAGE57_I29@PURE_QUANTA.GENOA_SP5(CHIPS)':
 'VDDCR_CPU0_AU25': CDS_PINID='VDDCR_CPU0_AU25';
NODE_NAME     U26 AU29
 '@T6G_MB_LIB.T6G(SCH_1):PAGE57_I29@PURE_QUANTA.GENOA_SP5(CHIPS)':
 'VDDCR_CPU0_AU29': CDS_PINID='VDDCR_CPU0_AU29';
NODE_NAME     U26 AU33
 '@T6G_MB_LIB.T6G(SCH_1):PAGE57_I29@PURE_QUANTA.GENOA_SP5(CHIPS)':
 'VDDCR_CPU0_AU33': CDS_PINID='VDDCR_CPU0_AU33';
NODE_NAME     U26 AU42
 '@T6G_MB_LIB.T6G(SCH_1):PAGE57_I29@PURE_QUANTA.GENOA_SP5(CHIPS)':
 'VDDCR_CPU0_AU42': CDS_PINID='VDDCR_CPU0_AU42';
NODE_NAME     U26 AU44
 '@T6G_MB_LIB.T6G(SCH_1):PAGE57_I29@PURE_QUANTA.GENOA_SP5(CHIPS)':
 'VDDCR_CPU0_AU44': CDS_PINID='VDDCR_CPU0_AU44';
NODE_NAME     U26 AU46
 '@T6G_MB_LIB.T6G(SCH_1):PAGE57_I29@PURE_QUANTA.GENOA_SP5(CHIPS)':
 'VDDCR_CPU0_AU46': CDS_PINID='VDDCR_CPU0_AU46';
NODE_NAME     U26 AU48
 '@T6G_MB_LIB.T6G(SCH_1):PAGE57_I29@PURE_QUANTA.GENOA_SP5(CHIPS)':
 'VDDCR_CPU0_AU48': CDS_PINID='VDDCR_CPU0_AU48';
NODE_NAME     U26 B19
 '@T6G_MB_LIB.T6G(SCH_1):PAGE57_I29@PURE_QUANTA.GENOA_SP5(CHIPS)':
 'VDDCR_CPU0_B19': CDS_PINID='VDDCR_CPU0_B19';
NODE_NAME     U26 B20
 '@T6G_MB_LIB.T6G(SCH_1):PAGE57_I29@PURE_QUANTA.GENOA_SP5(CHIPS)':
 'VDDCR_CPU0_B20': CDS_PINID='VDDCR_CPU0_B20';
NODE_NAME     U26 B22
 '@T6G_MB_LIB.T6G(SCH_1):PAGE57_I29@PURE_QUANTA.GENOA_SP5(CHIPS)':
 'VDDCR_CPU0_B22': CDS_PINID='VDDCR_CPU0_B22';
NODE_NAME     U26 B23
 '@T6G_MB_LIB.T6G(SCH_1):PAGE57_I29@PURE_QUANTA.GENOA_SP5(CHIPS)':
 'VDDCR_CPU0_B23': CDS_PINID='VDDCR_CPU0_B23';
NODE_NAME     U26 B25
 '@T6G_MB_LIB.T6G(SCH_1):PAGE57_I29@PURE_QUANTA.GENOA_SP5(CHIPS)':
 'VDDCR_CPU0_B25': CDS_PINID='VDDCR_CPU0_B25';
NODE_NAME     U26 B26
 '@T6G_MB_LIB.T6G(SCH_1):PAGE57_I29@PURE_QUANTA.GENOA_SP5(CHIPS)':
 'VDDCR_CPU0_B26': CDS_PINID='VDDCR_CPU0_B26';
NODE_NAME     U26 B28
 '@T6G_MB_LIB.T6G(SCH_1):PAGE57_I29@PURE_QUANTA.GENOA_SP5(CHIPS)':
 'VDDCR_CPU0_B28': CDS_PINID='VDDCR_CPU0_B28';
NODE_NAME     U26 B29
 '@T6G_MB_LIB.T6G(SCH_1):PAGE57_I29@PURE_QUANTA.GENOA_SP5(CHIPS)':
 'VDDCR_CPU0_B29': CDS_PINID='VDDCR_CPU0_B29';
NODE_NAME     U26 B31
 '@T6G_MB_LIB.T6G(SCH_1):PAGE57_I29@PURE_QUANTA.GENOA_SP5(CHIPS)':
 'VDDCR_CPU0_B31': CDS_PINID='VDDCR_CPU0_B31';
NODE_NAME     U26 B32
 '@T6G_MB_LIB.T6G(SCH_1):PAGE57_I29@PURE_QUANTA.GENOA_SP5(CHIPS)':
 'VDDCR_CPU0_B32': CDS_PINID='VDDCR_CPU0_B32';
NODE_NAME     U26 B34
 '@T6G_MB_LIB.T6G(SCH_1):PAGE57_I29@PURE_QUANTA.GENOA_SP5(CHIPS)':
 'VDDCR_CPU0_B34': CDS_PINID='VDDCR_CPU0_B34';
NODE_NAME     U26 B35
 '@T6G_MB_LIB.T6G(SCH_1):PAGE57_I29@PURE_QUANTA.GENOA_SP5(CHIPS)':
 'VDDCR_CPU0_B35': CDS_PINID='VDDCR_CPU0_B35';
NODE_NAME     U26 B41
 '@T6G_MB_LIB.T6G(SCH_1):PAGE57_I29@PURE_QUANTA.GENOA_SP5(CHIPS)':
 'VDDCR_CPU0_B41': CDS_PINID='VDDCR_CPU0_B41';
NODE_NAME     U26 B42
 '@T6G_MB_LIB.T6G(SCH_1):PAGE57_I29@PURE_QUANTA.GENOA_SP5(CHIPS)':
 'VDDCR_CPU0_B42': CDS_PINID='VDDCR_CPU0_B42';
NODE_NAME     U26 B44
 '@T6G_MB_LIB.T6G(SCH_1):PAGE57_I29@PURE_QUANTA.GENOA_SP5(CHIPS)':
 'VDDCR_CPU0_B44': CDS_PINID='VDDCR_CPU0_B44';
NODE_NAME     U26 B45
 '@T6G_MB_LIB.T6G(SCH_1):PAGE57_I29@PURE_QUANTA.GENOA_SP5(CHIPS)':
 'VDDCR_CPU0_B45': CDS_PINID='VDDCR_CPU0_B45';
NODE_NAME     U26 B47
 '@T6G_MB_LIB.T6G(SCH_1):PAGE57_I29@PURE_QUANTA.GENOA_SP5(CHIPS)':
 'VDDCR_CPU0_B47': CDS_PINID='VDDCR_CPU0_B47';
NODE_NAME     U26 B48
 '@T6G_MB_LIB.T6G(SCH_1):PAGE57_I29@PURE_QUANTA.GENOA_SP5(CHIPS)':
 'VDDCR_CPU0_B48': CDS_PINID='VDDCR_CPU0_B48';
NODE_NAME     U26 B50
 '@T6G_MB_LIB.T6G(SCH_1):PAGE57_I29@PURE_QUANTA.GENOA_SP5(CHIPS)':
 'VDDCR_CPU0_B50': CDS_PINID='VDDCR_CPU0_B50';
NODE_NAME     U26 B51
 '@T6G_MB_LIB.T6G(SCH_1):PAGE57_I29@PURE_QUANTA.GENOA_SP5(CHIPS)':
 'VDDCR_CPU0_B51': CDS_PINID='VDDCR_CPU0_B51';
NODE_NAME     U26 B53
 '@T6G_MB_LIB.T6G(SCH_1):PAGE57_I29@PURE_QUANTA.GENOA_SP5(CHIPS)':
 'VDDCR_CPU0_B53': CDS_PINID='VDDCR_CPU0_B53';
NODE_NAME     U26 B54
 '@T6G_MB_LIB.T6G(SCH_1):PAGE57_I29@PURE_QUANTA.GENOA_SP5(CHIPS)':
 'VDDCR_CPU0_B54': CDS_PINID='VDDCR_CPU0_B54';
NODE_NAME     U26 B56
 '@T6G_MB_LIB.T6G(SCH_1):PAGE57_I29@PURE_QUANTA.GENOA_SP5(CHIPS)':
 'VDDCR_CPU0_B56': CDS_PINID='VDDCR_CPU0_B56';
NODE_NAME     U26 B57
 '@T6G_MB_LIB.T6G(SCH_1):PAGE57_I29@PURE_QUANTA.GENOA_SP5(CHIPS)':
 'VDDCR_CPU0_B57': CDS_PINID='VDDCR_CPU0_B57';
NODE_NAME     U26 C20
 '@T6G_MB_LIB.T6G(SCH_1):PAGE57_I29@PURE_QUANTA.GENOA_SP5(CHIPS)':
 'VDDCR_CPU0_C20': CDS_PINID='VDDCR_CPU0_C20';
NODE_NAME     U26 D55
 '@T6G_MB_LIB.T6G(SCH_1):PAGE57_I29@PURE_QUANTA.GENOA_SP5(CHIPS)':
 'VDDCR_CPU0_D55': CDS_PINID='VDDCR_CPU0_D55';
NODE_NAME     U26 D56
 '@T6G_MB_LIB.T6G(SCH_1):PAGE57_I29@PURE_QUANTA.GENOA_SP5(CHIPS)':
 'VDDCR_CPU0_D56': CDS_PINID='VDDCR_CPU0_D56';
NODE_NAME     U26 E22
 '@T6G_MB_LIB.T6G(SCH_1):PAGE57_I29@PURE_QUANTA.GENOA_SP5(CHIPS)':
 'VDDCR_CPU0_E22': CDS_PINID='VDDCR_CPU0_E22';
NODE_NAME     U26 E25
 '@T6G_MB_LIB.T6G(SCH_1):PAGE57_I29@PURE_QUANTA.GENOA_SP5(CHIPS)':
 'VDDCR_CPU0_E25': CDS_PINID='VDDCR_CPU0_E25';
NODE_NAME     U26 E28
 '@T6G_MB_LIB.T6G(SCH_1):PAGE57_I29@PURE_QUANTA.GENOA_SP5(CHIPS)':
 'VDDCR_CPU0_E28': CDS_PINID='VDDCR_CPU0_E28';
NODE_NAME     U26 E31
 '@T6G_MB_LIB.T6G(SCH_1):PAGE57_I29@PURE_QUANTA.GENOA_SP5(CHIPS)':
 'VDDCR_CPU0_E31': CDS_PINID='VDDCR_CPU0_E31';
NODE_NAME     U26 E34
 '@T6G_MB_LIB.T6G(SCH_1):PAGE57_I29@PURE_QUANTA.GENOA_SP5(CHIPS)':
 'VDDCR_CPU0_E34': CDS_PINID='VDDCR_CPU0_E34';
NODE_NAME     U26 E35
 '@T6G_MB_LIB.T6G(SCH_1):PAGE57_I29@PURE_QUANTA.GENOA_SP5(CHIPS)':
 'VDDCR_CPU0_E35': CDS_PINID='VDDCR_CPU0_E35';
NODE_NAME     U26 E42
 '@T6G_MB_LIB.T6G(SCH_1):PAGE57_I29@PURE_QUANTA.GENOA_SP5(CHIPS)':
 'VDDCR_CPU0_E42': CDS_PINID='VDDCR_CPU0_E42';
NODE_NAME     U26 E45
 '@T6G_MB_LIB.T6G(SCH_1):PAGE57_I29@PURE_QUANTA.GENOA_SP5(CHIPS)':
 'VDDCR_CPU0_E45': CDS_PINID='VDDCR_CPU0_E45';
NODE_NAME     U26 E48
 '@T6G_MB_LIB.T6G(SCH_1):PAGE57_I29@PURE_QUANTA.GENOA_SP5(CHIPS)':
 'VDDCR_CPU0_E48': CDS_PINID='VDDCR_CPU0_E48';
NODE_NAME     U26 E51
 '@T6G_MB_LIB.T6G(SCH_1):PAGE57_I29@PURE_QUANTA.GENOA_SP5(CHIPS)':
 'VDDCR_CPU0_E51': CDS_PINID='VDDCR_CPU0_E51';
NODE_NAME     U26 E54
 '@T6G_MB_LIB.T6G(SCH_1):PAGE57_I29@PURE_QUANTA.GENOA_SP5(CHIPS)':
 'VDDCR_CPU0_E54': CDS_PINID='VDDCR_CPU0_E54';
NODE_NAME     U26 F22
 '@T6G_MB_LIB.T6G(SCH_1):PAGE57_I29@PURE_QUANTA.GENOA_SP5(CHIPS)':
 'VDDCR_CPU0_F22': CDS_PINID='VDDCR_CPU0_F22';
NODE_NAME     U26 F25
 '@T6G_MB_LIB.T6G(SCH_1):PAGE57_I29@PURE_QUANTA.GENOA_SP5(CHIPS)':
 'VDDCR_CPU0_F25': CDS_PINID='VDDCR_CPU0_F25';
NODE_NAME     U26 F28
 '@T6G_MB_LIB.T6G(SCH_1):PAGE57_I29@PURE_QUANTA.GENOA_SP5(CHIPS)':
 'VDDCR_CPU0_F28': CDS_PINID='VDDCR_CPU0_F28';
NODE_NAME     U26 F31
 '@T6G_MB_LIB.T6G(SCH_1):PAGE57_I29@PURE_QUANTA.GENOA_SP5(CHIPS)':
 'VDDCR_CPU0_F31': CDS_PINID='VDDCR_CPU0_F31';
NODE_NAME     U26 F34
 '@T6G_MB_LIB.T6G(SCH_1):PAGE57_I29@PURE_QUANTA.GENOA_SP5(CHIPS)':
 'VDDCR_CPU0_F34': CDS_PINID='VDDCR_CPU0_F34';
NODE_NAME     U26 F42
 '@T6G_MB_LIB.T6G(SCH_1):PAGE57_I29@PURE_QUANTA.GENOA_SP5(CHIPS)':
 'VDDCR_CPU0_F42': CDS_PINID='VDDCR_CPU0_F42';
NODE_NAME     U26 F45
 '@T6G_MB_LIB.T6G(SCH_1):PAGE57_I29@PURE_QUANTA.GENOA_SP5(CHIPS)':
 'VDDCR_CPU0_F45': CDS_PINID='VDDCR_CPU0_F45';
NODE_NAME     U26 F48
 '@T6G_MB_LIB.T6G(SCH_1):PAGE57_I29@PURE_QUANTA.GENOA_SP5(CHIPS)':
 'VDDCR_CPU0_F48': CDS_PINID='VDDCR_CPU0_F48';
NODE_NAME     U26 F51
 '@T6G_MB_LIB.T6G(SCH_1):PAGE57_I29@PURE_QUANTA.GENOA_SP5(CHIPS)':
 'VDDCR_CPU0_F51': CDS_PINID='VDDCR_CPU0_F51';
NODE_NAME     U26 F54
 '@T6G_MB_LIB.T6G(SCH_1):PAGE57_I29@PURE_QUANTA.GENOA_SP5(CHIPS)':
 'VDDCR_CPU0_F54': CDS_PINID='VDDCR_CPU0_F54';
NODE_NAME     U26 G35
 '@T6G_MB_LIB.T6G(SCH_1):PAGE57_I29@PURE_QUANTA.GENOA_SP5(CHIPS)':
 'VDDCR_CPU0_G35': CDS_PINID='VDDCR_CPU0_G35';
NODE_NAME     U26 G36
 '@T6G_MB_LIB.T6G(SCH_1):PAGE57_I29@PURE_QUANTA.GENOA_SP5(CHIPS)':
 'VDDCR_CPU0_G36': CDS_PINID='VDDCR_CPU0_G36';
NODE_NAME     U26 G40
 '@T6G_MB_LIB.T6G(SCH_1):PAGE57_I29@PURE_QUANTA.GENOA_SP5(CHIPS)':
 'VDDCR_CPU0_G40': CDS_PINID='VDDCR_CPU0_G40';
NODE_NAME     U26 G41
 '@T6G_MB_LIB.T6G(SCH_1):PAGE57_I29@PURE_QUANTA.GENOA_SP5(CHIPS)':
 'VDDCR_CPU0_G41': CDS_PINID='VDDCR_CPU0_G41';
NODE_NAME     U26 H23
 '@T6G_MB_LIB.T6G(SCH_1):PAGE57_I29@PURE_QUANTA.GENOA_SP5(CHIPS)':
 'VDDCR_CPU0_H23': CDS_PINID='VDDCR_CPU0_H23';
NODE_NAME     U26 H24
 '@T6G_MB_LIB.T6G(SCH_1):PAGE57_I29@PURE_QUANTA.GENOA_SP5(CHIPS)':
 'VDDCR_CPU0_H24': CDS_PINID='VDDCR_CPU0_H24';
NODE_NAME     U26 H26
 '@T6G_MB_LIB.T6G(SCH_1):PAGE57_I29@PURE_QUANTA.GENOA_SP5(CHIPS)':
 'VDDCR_CPU0_H26': CDS_PINID='VDDCR_CPU0_H26';
NODE_NAME     U26 H27
 '@T6G_MB_LIB.T6G(SCH_1):PAGE57_I29@PURE_QUANTA.GENOA_SP5(CHIPS)':
 'VDDCR_CPU0_H27': CDS_PINID='VDDCR_CPU0_H27';
NODE_NAME     U26 H29
 '@T6G_MB_LIB.T6G(SCH_1):PAGE57_I29@PURE_QUANTA.GENOA_SP5(CHIPS)':
 'VDDCR_CPU0_H29': CDS_PINID='VDDCR_CPU0_H29';
NODE_NAME     U26 H30
 '@T6G_MB_LIB.T6G(SCH_1):PAGE57_I29@PURE_QUANTA.GENOA_SP5(CHIPS)':
 'VDDCR_CPU0_H30': CDS_PINID='VDDCR_CPU0_H30';
NODE_NAME     U26 H32
 '@T6G_MB_LIB.T6G(SCH_1):PAGE57_I29@PURE_QUANTA.GENOA_SP5(CHIPS)':
 'VDDCR_CPU0_H32': CDS_PINID='VDDCR_CPU0_H32';
NODE_NAME     U26 H33
 '@T6G_MB_LIB.T6G(SCH_1):PAGE57_I29@PURE_QUANTA.GENOA_SP5(CHIPS)':
 'VDDCR_CPU0_H33': CDS_PINID='VDDCR_CPU0_H33';
NODE_NAME     U26 H43
 '@T6G_MB_LIB.T6G(SCH_1):PAGE57_I29@PURE_QUANTA.GENOA_SP5(CHIPS)':
 'VDDCR_CPU0_H43': CDS_PINID='VDDCR_CPU0_H43';
NODE_NAME     U26 H44
 '@T6G_MB_LIB.T6G(SCH_1):PAGE57_I29@PURE_QUANTA.GENOA_SP5(CHIPS)':
 'VDDCR_CPU0_H44': CDS_PINID='VDDCR_CPU0_H44';
NODE_NAME     U26 H46
 '@T6G_MB_LIB.T6G(SCH_1):PAGE57_I29@PURE_QUANTA.GENOA_SP5(CHIPS)':
 'VDDCR_CPU0_H46': CDS_PINID='VDDCR_CPU0_H46';
NODE_NAME     U26 H47
 '@T6G_MB_LIB.T6G(SCH_1):PAGE57_I29@PURE_QUANTA.GENOA_SP5(CHIPS)':
 'VDDCR_CPU0_H47': CDS_PINID='VDDCR_CPU0_H47';
NODE_NAME     U26 H49
 '@T6G_MB_LIB.T6G(SCH_1):PAGE57_I29@PURE_QUANTA.GENOA_SP5(CHIPS)':
 'VDDCR_CPU0_H49': CDS_PINID='VDDCR_CPU0_H49';
NODE_NAME     U26 H50
 '@T6G_MB_LIB.T6G(SCH_1):PAGE57_I29@PURE_QUANTA.GENOA_SP5(CHIPS)':
 'VDDCR_CPU0_H50': CDS_PINID='VDDCR_CPU0_H50';
NODE_NAME     U26 H52
 '@T6G_MB_LIB.T6G(SCH_1):PAGE57_I29@PURE_QUANTA.GENOA_SP5(CHIPS)':
 'VDDCR_CPU0_H52': CDS_PINID='VDDCR_CPU0_H52';
NODE_NAME     U26 H53
 '@T6G_MB_LIB.T6G(SCH_1):PAGE57_I29@PURE_QUANTA.GENOA_SP5(CHIPS)':
 'VDDCR_CPU0_H53': CDS_PINID='VDDCR_CPU0_H53';
NODE_NAME     U26 J35
 '@T6G_MB_LIB.T6G(SCH_1):PAGE57_I29@PURE_QUANTA.GENOA_SP5(CHIPS)':
 'VDDCR_CPU0_J35': CDS_PINID='VDDCR_CPU0_J35';
NODE_NAME     U26 J36
 '@T6G_MB_LIB.T6G(SCH_1):PAGE57_I29@PURE_QUANTA.GENOA_SP5(CHIPS)':
 'VDDCR_CPU0_J36': CDS_PINID='VDDCR_CPU0_J36';
NODE_NAME     U26 J40
 '@T6G_MB_LIB.T6G(SCH_1):PAGE57_I29@PURE_QUANTA.GENOA_SP5(CHIPS)':
 'VDDCR_CPU0_J40': CDS_PINID='VDDCR_CPU0_J40';
NODE_NAME     U26 J41
 '@T6G_MB_LIB.T6G(SCH_1):PAGE57_I29@PURE_QUANTA.GENOA_SP5(CHIPS)':
 'VDDCR_CPU0_J41': CDS_PINID='VDDCR_CPU0_J41';
NODE_NAME     U26 M23
 '@T6G_MB_LIB.T6G(SCH_1):PAGE57_I29@PURE_QUANTA.GENOA_SP5(CHIPS)':
 'VDDCR_CPU0_M23': CDS_PINID='VDDCR_CPU0_M23';
NODE_NAME     U26 M24
 '@T6G_MB_LIB.T6G(SCH_1):PAGE57_I29@PURE_QUANTA.GENOA_SP5(CHIPS)':
 'VDDCR_CPU0_M24': CDS_PINID='VDDCR_CPU0_M24';
NODE_NAME     U26 M26
 '@T6G_MB_LIB.T6G(SCH_1):PAGE57_I29@PURE_QUANTA.GENOA_SP5(CHIPS)':
 'VDDCR_CPU0_M26': CDS_PINID='VDDCR_CPU0_M26';
NODE_NAME     U26 M27
 '@T6G_MB_LIB.T6G(SCH_1):PAGE57_I29@PURE_QUANTA.GENOA_SP5(CHIPS)':
 'VDDCR_CPU0_M27': CDS_PINID='VDDCR_CPU0_M27';
NODE_NAME     U26 M29
 '@T6G_MB_LIB.T6G(SCH_1):PAGE57_I29@PURE_QUANTA.GENOA_SP5(CHIPS)':
 'VDDCR_CPU0_M29': CDS_PINID='VDDCR_CPU0_M29';
NODE_NAME     U26 M30
 '@T6G_MB_LIB.T6G(SCH_1):PAGE57_I29@PURE_QUANTA.GENOA_SP5(CHIPS)':
 'VDDCR_CPU0_M30': CDS_PINID='VDDCR_CPU0_M30';
NODE_NAME     U26 M32
 '@T6G_MB_LIB.T6G(SCH_1):PAGE57_I29@PURE_QUANTA.GENOA_SP5(CHIPS)':
 'VDDCR_CPU0_M32': CDS_PINID='VDDCR_CPU0_M32';
NODE_NAME     U26 M33
 '@T6G_MB_LIB.T6G(SCH_1):PAGE57_I29@PURE_QUANTA.GENOA_SP5(CHIPS)':
 'VDDCR_CPU0_M33': CDS_PINID='VDDCR_CPU0_M33';
NODE_NAME     U26 M43
 '@T6G_MB_LIB.T6G(SCH_1):PAGE57_I29@PURE_QUANTA.GENOA_SP5(CHIPS)':
 'VDDCR_CPU0_M43': CDS_PINID='VDDCR_CPU0_M43';
NODE_NAME     U26 M44
 '@T6G_MB_LIB.T6G(SCH_1):PAGE57_I29@PURE_QUANTA.GENOA_SP5(CHIPS)':
 'VDDCR_CPU0_M44': CDS_PINID='VDDCR_CPU0_M44';
NODE_NAME     U26 M46
 '@T6G_MB_LIB.T6G(SCH_1):PAGE57_I29@PURE_QUANTA.GENOA_SP5(CHIPS)':
 'VDDCR_CPU0_M46': CDS_PINID='VDDCR_CPU0_M46';
NODE_NAME     U26 M47
 '@T6G_MB_LIB.T6G(SCH_1):PAGE57_I29@PURE_QUANTA.GENOA_SP5(CHIPS)':
 'VDDCR_CPU0_M47': CDS_PINID='VDDCR_CPU0_M47';
NODE_NAME     U26 M49
 '@T6G_MB_LIB.T6G(SCH_1):PAGE57_I29@PURE_QUANTA.GENOA_SP5(CHIPS)':
 'VDDCR_CPU0_M49': CDS_PINID='VDDCR_CPU0_M49';
NODE_NAME     U26 M50
 '@T6G_MB_LIB.T6G(SCH_1):PAGE57_I29@PURE_QUANTA.GENOA_SP5(CHIPS)':
 'VDDCR_CPU0_M50': CDS_PINID='VDDCR_CPU0_M50';
NODE_NAME     U26 M52
 '@T6G_MB_LIB.T6G(SCH_1):PAGE57_I29@PURE_QUANTA.GENOA_SP5(CHIPS)':
 'VDDCR_CPU0_M52': CDS_PINID='VDDCR_CPU0_M52';
NODE_NAME     U26 M53
 '@T6G_MB_LIB.T6G(SCH_1):PAGE57_I29@PURE_QUANTA.GENOA_SP5(CHIPS)':
 'VDDCR_CPU0_M53': CDS_PINID='VDDCR_CPU0_M53';
NODE_NAME     U26 N35
 '@T6G_MB_LIB.T6G(SCH_1):PAGE57_I29@PURE_QUANTA.GENOA_SP5(CHIPS)':
 'VDDCR_CPU0_N35': CDS_PINID='VDDCR_CPU0_N35';
NODE_NAME     U26 N36
 '@T6G_MB_LIB.T6G(SCH_1):PAGE57_I29@PURE_QUANTA.GENOA_SP5(CHIPS)':
 'VDDCR_CPU0_N36': CDS_PINID='VDDCR_CPU0_N36';
NODE_NAME     U26 N40
 '@T6G_MB_LIB.T6G(SCH_1):PAGE57_I29@PURE_QUANTA.GENOA_SP5(CHIPS)':
 'VDDCR_CPU0_N40': CDS_PINID='VDDCR_CPU0_N40';
NODE_NAME     U26 N41
 '@T6G_MB_LIB.T6G(SCH_1):PAGE57_I29@PURE_QUANTA.GENOA_SP5(CHIPS)':
 'VDDCR_CPU0_N41': CDS_PINID='VDDCR_CPU0_N41';
NODE_NAME     U26 T23
 '@T6G_MB_LIB.T6G(SCH_1):PAGE57_I29@PURE_QUANTA.GENOA_SP5(CHIPS)':
 'VDDCR_CPU0_T23': CDS_PINID='VDDCR_CPU0_T23';
NODE_NAME     U26 T24
 '@T6G_MB_LIB.T6G(SCH_1):PAGE57_I29@PURE_QUANTA.GENOA_SP5(CHIPS)':
 'VDDCR_CPU0_T24': CDS_PINID='VDDCR_CPU0_T24';
NODE_NAME     U26 T26
 '@T6G_MB_LIB.T6G(SCH_1):PAGE57_I29@PURE_QUANTA.GENOA_SP5(CHIPS)':
 'VDDCR_CPU0_T26': CDS_PINID='VDDCR_CPU0_T26';
NODE_NAME     U26 T27
 '@T6G_MB_LIB.T6G(SCH_1):PAGE57_I29@PURE_QUANTA.GENOA_SP5(CHIPS)':
 'VDDCR_CPU0_T27': CDS_PINID='VDDCR_CPU0_T27';
NODE_NAME     U26 T29
 '@T6G_MB_LIB.T6G(SCH_1):PAGE57_I29@PURE_QUANTA.GENOA_SP5(CHIPS)':
 'VDDCR_CPU0_T29': CDS_PINID='VDDCR_CPU0_T29';
NODE_NAME     U26 T30
 '@T6G_MB_LIB.T6G(SCH_1):PAGE57_I29@PURE_QUANTA.GENOA_SP5(CHIPS)':
 'VDDCR_CPU0_T30': CDS_PINID='VDDCR_CPU0_T30';
NODE_NAME     U26 T32
 '@T6G_MB_LIB.T6G(SCH_1):PAGE57_I29@PURE_QUANTA.GENOA_SP5(CHIPS)':
 'VDDCR_CPU0_T32': CDS_PINID='VDDCR_CPU0_T32';
NODE_NAME     U26 T33
 '@T6G_MB_LIB.T6G(SCH_1):PAGE57_I29@PURE_QUANTA.GENOA_SP5(CHIPS)':
 'VDDCR_CPU0_T33': CDS_PINID='VDDCR_CPU0_T33';
NODE_NAME     U26 T43
 '@T6G_MB_LIB.T6G(SCH_1):PAGE57_I29@PURE_QUANTA.GENOA_SP5(CHIPS)':
 'VDDCR_CPU0_T43': CDS_PINID='VDDCR_CPU0_T43';
NODE_NAME     U26 T44
 '@T6G_MB_LIB.T6G(SCH_1):PAGE57_I29@PURE_QUANTA.GENOA_SP5(CHIPS)':
 'VDDCR_CPU0_T44': CDS_PINID='VDDCR_CPU0_T44';
NODE_NAME     U26 T46
 '@T6G_MB_LIB.T6G(SCH_1):PAGE57_I29@PURE_QUANTA.GENOA_SP5(CHIPS)':
 'VDDCR_CPU0_T46': CDS_PINID='VDDCR_CPU0_T46';
NODE_NAME     U26 T47
 '@T6G_MB_LIB.T6G(SCH_1):PAGE57_I29@PURE_QUANTA.GENOA_SP5(CHIPS)':
 'VDDCR_CPU0_T47': CDS_PINID='VDDCR_CPU0_T47';
NODE_NAME     U26 T49
 '@T6G_MB_LIB.T6G(SCH_1):PAGE57_I29@PURE_QUANTA.GENOA_SP5(CHIPS)':
 'VDDCR_CPU0_T49': CDS_PINID='VDDCR_CPU0_T49';
NODE_NAME     U26 T50
 '@T6G_MB_LIB.T6G(SCH_1):PAGE57_I29@PURE_QUANTA.GENOA_SP5(CHIPS)':
 'VDDCR_CPU0_T50': CDS_PINID='VDDCR_CPU0_T50';
NODE_NAME     U26 T52
 '@T6G_MB_LIB.T6G(SCH_1):PAGE57_I29@PURE_QUANTA.GENOA_SP5(CHIPS)':
 'VDDCR_CPU0_T52': CDS_PINID='VDDCR_CPU0_T52';
NODE_NAME     U26 T53
 '@T6G_MB_LIB.T6G(SCH_1):PAGE57_I29@PURE_QUANTA.GENOA_SP5(CHIPS)':
 'VDDCR_CPU0_T53': CDS_PINID='VDDCR_CPU0_T53';
NODE_NAME     U26 U35
 '@T6G_MB_LIB.T6G(SCH_1):PAGE57_I29@PURE_QUANTA.GENOA_SP5(CHIPS)':
 'VDDCR_CPU0_U35': CDS_PINID='VDDCR_CPU0_U35';
NODE_NAME     U26 U36
 '@T6G_MB_LIB.T6G(SCH_1):PAGE57_I29@PURE_QUANTA.GENOA_SP5(CHIPS)':
 'VDDCR_CPU0_U36': CDS_PINID='VDDCR_CPU0_U36';
NODE_NAME     U26 U40
 '@T6G_MB_LIB.T6G(SCH_1):PAGE57_I29@PURE_QUANTA.GENOA_SP5(CHIPS)':
 'VDDCR_CPU0_U40': CDS_PINID='VDDCR_CPU0_U40';
NODE_NAME     U26 U41
 '@T6G_MB_LIB.T6G(SCH_1):PAGE57_I29@PURE_QUANTA.GENOA_SP5(CHIPS)':
 'VDDCR_CPU0_U41': CDS_PINID='VDDCR_CPU0_U41';
NODE_NAME     U26 W29
 '@T6G_MB_LIB.T6G(SCH_1):PAGE57_I29@PURE_QUANTA.GENOA_SP5(CHIPS)':
 'VDDCR_CPU0_W29': CDS_PINID='VDDCR_CPU0_W29';
NODE_NAME     U26 W30
 '@T6G_MB_LIB.T6G(SCH_1):PAGE57_I29@PURE_QUANTA.GENOA_SP5(CHIPS)':
 'VDDCR_CPU0_W30': CDS_PINID='VDDCR_CPU0_W30';
NODE_NAME     U26 W32
 '@T6G_MB_LIB.T6G(SCH_1):PAGE57_I29@PURE_QUANTA.GENOA_SP5(CHIPS)':
 'VDDCR_CPU0_W32': CDS_PINID='VDDCR_CPU0_W32';
NODE_NAME     U26 W33
 '@T6G_MB_LIB.T6G(SCH_1):PAGE57_I29@PURE_QUANTA.GENOA_SP5(CHIPS)':
 'VDDCR_CPU0_W33': CDS_PINID='VDDCR_CPU0_W33';
NODE_NAME     U26 W43
 '@T6G_MB_LIB.T6G(SCH_1):PAGE57_I29@PURE_QUANTA.GENOA_SP5(CHIPS)':
 'VDDCR_CPU0_W43': CDS_PINID='VDDCR_CPU0_W43';
NODE_NAME     U26 W44
 '@T6G_MB_LIB.T6G(SCH_1):PAGE57_I29@PURE_QUANTA.GENOA_SP5(CHIPS)':
 'VDDCR_CPU0_W44': CDS_PINID='VDDCR_CPU0_W44';
NODE_NAME     U26 W46
 '@T6G_MB_LIB.T6G(SCH_1):PAGE57_I29@PURE_QUANTA.GENOA_SP5(CHIPS)':
 'VDDCR_CPU0_W46': CDS_PINID='VDDCR_CPU0_W46';
NODE_NAME     U26 W47
 '@T6G_MB_LIB.T6G(SCH_1):PAGE57_I29@PURE_QUANTA.GENOA_SP5(CHIPS)':
 'VDDCR_CPU0_W47': CDS_PINID='VDDCR_CPU0_W47';
NODE_NAME     U26 Y35
 '@T6G_MB_LIB.T6G(SCH_1):PAGE57_I29@PURE_QUANTA.GENOA_SP5(CHIPS)':
 'VDDCR_CPU0_Y35': CDS_PINID='VDDCR_CPU0_Y35';
NODE_NAME     U26 Y36
 '@T6G_MB_LIB.T6G(SCH_1):PAGE57_I29@PURE_QUANTA.GENOA_SP5(CHIPS)':
 'VDDCR_CPU0_Y36': CDS_PINID='VDDCR_CPU0_Y36';
NODE_NAME     U26 Y40
 '@T6G_MB_LIB.T6G(SCH_1):PAGE57_I29@PURE_QUANTA.GENOA_SP5(CHIPS)':
 'VDDCR_CPU0_Y40': CDS_PINID='VDDCR_CPU0_Y40';
NODE_NAME     U26 Y41
 '@T6G_MB_LIB.T6G(SCH_1):PAGE57_I29@PURE_QUANTA.GENOA_SP5(CHIPS)':
 'VDDCR_CPU0_Y41': CDS_PINID='VDDCR_CPU0_Y41';
NODE_NAME     C2298 1
 '@T6G_MB_LIB.T6G(SCH_1):PAGE72_I1@PURE_QUANTA.Q_CAP(CHIPS)':
 'A': CDS_PINID='A';
NODE_NAME     C2304 1
 '@T6G_MB_LIB.T6G(SCH_1):PAGE72_I3@PURE_QUANTA.Q_CAP(CHIPS)':
 'A': CDS_PINID='A';
NODE_NAME     C2310 1
 '@T6G_MB_LIB.T6G(SCH_1):PAGE72_I4@PURE_QUANTA.Q_CAP(CHIPS)':
 'A': CDS_PINID='A';
NODE_NAME     C2297 1
 '@T6G_MB_LIB.T6G(SCH_1):PAGE72_I5@PURE_QUANTA.Q_CAP(CHIPS)':
 'A': CDS_PINID='A';
NODE_NAME     C2296 1
 '@T6G_MB_LIB.T6G(SCH_1):PAGE72_I7@PURE_QUANTA.Q_CAP(CHIPS)':
 'A': CDS_PINID='A';
NODE_NAME     C2295 1
 '@T6G_MB_LIB.T6G(SCH_1):PAGE72_I9@PURE_QUANTA.Q_CAP(CHIPS)':
 'A': CDS_PINID='A';
NODE_NAME     C2303 1
 '@T6G_MB_LIB.T6G(SCH_1):PAGE72_I10@PURE_QUANTA.Q_CAP(CHIPS)':
 'A': CDS_PINID='A';
NODE_NAME     C2309 1
 '@T6G_MB_LIB.T6G(SCH_1):PAGE72_I11@PURE_QUANTA.Q_CAP(CHIPS)':
 'A': CDS_PINID='A';
NODE_NAME     C2302 1
 '@T6G_MB_LIB.T6G(SCH_1):PAGE72_I12@PURE_QUANTA.Q_CAP(CHIPS)':
 'A': CDS_PINID='A';
NODE_NAME     C2301 1
 '@T6G_MB_LIB.T6G(SCH_1):PAGE72_I13@PURE_QUANTA.Q_CAP(CHIPS)':
 'A': CDS_PINID='A';
NODE_NAME     C2308 1
 '@T6G_MB_LIB.T6G(SCH_1):PAGE72_I14@PURE_QUANTA.Q_CAP(CHIPS)':
 'A': CDS_PINID='A';
NODE_NAME     C2307 1
 '@T6G_MB_LIB.T6G(SCH_1):PAGE72_I15@PURE_QUANTA.Q_CAP(CHIPS)':
 'A': CDS_PINID='A';
NODE_NAME     C2294 1
 '@T6G_MB_LIB.T6G(SCH_1):PAGE72_I17@PURE_QUANTA.Q_CAP(CHIPS)':
 'A': CDS_PINID='A';
NODE_NAME     C2300 1
 '@T6G_MB_LIB.T6G(SCH_1):PAGE72_I19@PURE_QUANTA.Q_CAP(CHIPS)':
 'A': CDS_PINID='A';
NODE_NAME     C2306 1
 '@T6G_MB_LIB.T6G(SCH_1):PAGE72_I20@PURE_QUANTA.Q_CAP(CHIPS)':
 'A': CDS_PINID='A';
NODE_NAME     C2316 1
 '@T6G_MB_LIB.T6G(SCH_1):PAGE72_I21@PURE_QUANTA.Q_CAP(CHIPS)':
 'A': CDS_PINID='A';
NODE_NAME     C2322 1
 '@T6G_MB_LIB.T6G(SCH_1):PAGE72_I23@PURE_QUANTA.Q_CAP(CHIPS)':
 'A': CDS_PINID='A';
NODE_NAME     C2315 1
 '@T6G_MB_LIB.T6G(SCH_1):PAGE72_I24@PURE_QUANTA.Q_CAP(CHIPS)':
 'A': CDS_PINID='A';
NODE_NAME     C2321 1
 '@T6G_MB_LIB.T6G(SCH_1):PAGE72_I25@PURE_QUANTA.Q_CAP(CHIPS)':
 'A': CDS_PINID='A';
NODE_NAME     C2327 1
 '@T6G_MB_LIB.T6G(SCH_1):PAGE72_I26@PURE_QUANTA.Q_CAP(CHIPS)':
 'A': CDS_PINID='A';
NODE_NAME     C2314 1
 '@T6G_MB_LIB.T6G(SCH_1):PAGE72_I27@PURE_QUANTA.Q_CAP(CHIPS)':
 'A': CDS_PINID='A';
NODE_NAME     C2313 1
 '@T6G_MB_LIB.T6G(SCH_1):PAGE72_I28@PURE_QUANTA.Q_CAP(CHIPS)':
 'A': CDS_PINID='A';
NODE_NAME     C2320 1
 '@T6G_MB_LIB.T6G(SCH_1):PAGE72_I29@PURE_QUANTA.Q_CAP(CHIPS)':
 'A': CDS_PINID='A';
NODE_NAME     C2326 1
 '@T6G_MB_LIB.T6G(SCH_1):PAGE72_I30@PURE_QUANTA.Q_CAP(CHIPS)':
 'A': CDS_PINID='A';
NODE_NAME     C2319 1
 '@T6G_MB_LIB.T6G(SCH_1):PAGE72_I31@PURE_QUANTA.Q_CAP(CHIPS)':
 'A': CDS_PINID='A';
NODE_NAME     C2325 1
 '@T6G_MB_LIB.T6G(SCH_1):PAGE72_I32@PURE_QUANTA.Q_CAP(CHIPS)':
 'A': CDS_PINID='A';
NODE_NAME     C2333 1
 '@T6G_MB_LIB.T6G(SCH_1):PAGE72_I33@PURE_QUANTA.Q_CAP(CHIPS)':
 'A': CDS_PINID='A';
NODE_NAME     C2338 1
 '@T6G_MB_LIB.T6G(SCH_1):PAGE72_I34@PURE_QUANTA.Q_CAP(CHIPS)':
 'A': CDS_PINID='A';
NODE_NAME     C2332 1
 '@T6G_MB_LIB.T6G(SCH_1):PAGE72_I35@PURE_QUANTA.Q_CAP(CHIPS)':
 'A': CDS_PINID='A';
NODE_NAME     C2331 1
 '@T6G_MB_LIB.T6G(SCH_1):PAGE72_I36@PURE_QUANTA.Q_CAP(CHIPS)':
 'A': CDS_PINID='A';
NODE_NAME     C2337 1
 '@T6G_MB_LIB.T6G(SCH_1):PAGE72_I37@PURE_QUANTA.Q_CAP(CHIPS)':
 'A': CDS_PINID='A';
NODE_NAME     C2336 1
 '@T6G_MB_LIB.T6G(SCH_1):PAGE72_I38@PURE_QUANTA.Q_CAP(CHIPS)':
 'A': CDS_PINID='A';
NODE_NAME     C2343 1
 '@T6G_MB_LIB.T6G(SCH_1):PAGE72_I42@PURE_QUANTA.Q_CAP(CHIPS)':
 'A': CDS_PINID='A';
NODE_NAME     C2348 1
 '@T6G_MB_LIB.T6G(SCH_1):PAGE72_I44@PURE_QUANTA.Q_CAP(CHIPS)':
 'A': CDS_PINID='A';
NODE_NAME     C2342 1
 '@T6G_MB_LIB.T6G(SCH_1):PAGE72_I46@PURE_QUANTA.Q_CAP(CHIPS)':
 'A': CDS_PINID='A';
NODE_NAME     C2341 1
 '@T6G_MB_LIB.T6G(SCH_1):PAGE72_I47@PURE_QUANTA.Q_CAP(CHIPS)':
 'A': CDS_PINID='A';
NODE_NAME     C2347 1
 '@T6G_MB_LIB.T6G(SCH_1):PAGE72_I48@PURE_QUANTA.Q_CAP(CHIPS)':
 'A': CDS_PINID='A';
NODE_NAME     C2346 1
 '@T6G_MB_LIB.T6G(SCH_1):PAGE72_I50@PURE_QUANTA.Q_CAP(CHIPS)':
 'A': CDS_PINID='A';
NODE_NAME     C2312 1
 '@T6G_MB_LIB.T6G(SCH_1):PAGE72_I59@PURE_QUANTA.Q_CAP(CHIPS)':
 'A': CDS_PINID='A';
NODE_NAME     C2318 1
 '@T6G_MB_LIB.T6G(SCH_1):PAGE72_I60@PURE_QUANTA.Q_CAP(CHIPS)':
 'A': CDS_PINID='A';
NODE_NAME     C2324 1
 '@T6G_MB_LIB.T6G(SCH_1):PAGE72_I61@PURE_QUANTA.Q_CAP(CHIPS)':
 'A': CDS_PINID='A';
NODE_NAME     C2330 1
 '@T6G_MB_LIB.T6G(SCH_1):PAGE72_I62@PURE_QUANTA.Q_CAP(CHIPS)':
 'A': CDS_PINID='A';
NODE_NAME     C2335 1
 '@T6G_MB_LIB.T6G(SCH_1):PAGE72_I63@PURE_QUANTA.Q_CAP(CHIPS)':
 'A': CDS_PINID='A';
NODE_NAME     C2340 1
 '@T6G_MB_LIB.T6G(SCH_1):PAGE72_I64@PURE_QUANTA.Q_CAP(CHIPS)':
 'A': CDS_PINID='A';
NODE_NAME     C2345 1
 '@T6G_MB_LIB.T6G(SCH_1):PAGE72_I66@PURE_QUANTA.Q_CAP(CHIPS)':
 'A': CDS_PINID='A';
NODE_NAME     PR191 2
 '@T6G_MB_LIB.T6G(SCH_1):PAGE186_I35@PURE_QUANTA.Q_RES(CHIPS)':
 'B': CDS_PINID='B';
NODE_NAME     PC282_2 1
 '@T6G_MB_LIB.T6G(SCH_1):PAGE186_I63@PURE_QUANTA.Q_CAP(CHIPS)':
 'A': CDS_PINID='A';
NODE_NAME     PC279 1
 '@T6G_MB_LIB.T6G(SCH_1):PAGE186_I66@PURE_QUANTA.Q_CAPP(CHIPS)':
 'A': CDS_PINID='A';
NODE_NAME     PR161 1
 '@T6G_MB_LIB.T6G(SCH_1):PAGE185_I70@PURE_QUANTA.Q_RES(CHIPS)':
 'A': CDS_PINID='A';
NODE_NAME     PR192 2
 '@T6G_MB_LIB.T6G(SCH_1):PAGE186_I23@PURE_QUANTA.Q_RES(CHIPS)':
 'B': CDS_PINID='B';
NODE_NAME     PL29 4
 '@T6G_MB_LIB.T6G(SCH_1):PAGE186_I56@PURE_QUANTA.Q_INDUCTOR4P_14(CHIPS)':
 '4': CDS_PINID='\4\';
NODE_NAME     PC275 1
 '@T6G_MB_LIB.T6G(SCH_1):PAGE186_I58@PURE_QUANTA.Q_CAPP(CHIPS)':
 'A': CDS_PINID='A';
NODE_NAME     PC276 1
 '@T6G_MB_LIB.T6G(SCH_1):PAGE186_I59@PURE_QUANTA.Q_CAPP(CHIPS)':
 'A': CDS_PINID='A';
NODE_NAME     PC277 1
 '@T6G_MB_LIB.T6G(SCH_1):PAGE186_I60@PURE_QUANTA.Q_CAPP(CHIPS)':
 'A': CDS_PINID='A';
NODE_NAME     PC280_2 1
 '@T6G_MB_LIB.T6G(SCH_1):PAGE186_I61@PURE_QUANTA.Q_CAP(CHIPS)':
 'A': CDS_PINID='A';
NODE_NAME     PC281_1 1
 '@T6G_MB_LIB.T6G(SCH_1):PAGE186_I76@PURE_QUANTA.Q_CAP(CHIPS)':
 'A': CDS_PINID='A';
NODE_NAME     PC283_1 1
 '@T6G_MB_LIB.T6G(SCH_1):PAGE186_I77@PURE_QUANTA.Q_CAP(CHIPS)':
 'A': CDS_PINID='A';
NODE_NAME     PR337 1
 '@T6G_MB_LIB.T6G(SCH_1):PAGE186_I78@PURE_QUANTA.Q_RES(CHIPS)':
 'A': CDS_PINID='A';
NODE_NAME     PC105 1
 '@T6G_MB_LIB.T6G(SCH_1):PAGE186_I84@PURE_QUANTA.Q_CAPP(CHIPS)':
 'A': CDS_PINID='A';
NODE_NAME     PC278 1
 '@T6G_MB_LIB.T6G(SCH_1):PAGE186_I85@PURE_QUANTA.Q_CAP(CHIPS)':
 'A': CDS_PINID='A';
NODE_NAME     PL28 4
 '@T6G_MB_LIB.T6G(SCH_1):PAGE186_I90@PURE_QUANTA.Q_INDUCTOR4P_14(CHIPS)':
 '4': CDS_PINID='\4\';
NODE_NAME     PR200 2
 '@T6G_MB_LIB.T6G(SCH_1):PAGE187_I17@PURE_QUANTA.Q_RES(CHIPS)':
 'B': CDS_PINID='B';
NODE_NAME     PR199 2
 '@T6G_MB_LIB.T6G(SCH_1):PAGE187_I27@PURE_QUANTA.Q_RES(CHIPS)':
 'B': CDS_PINID='B';
NODE_NAME     PL32 4
 '@T6G_MB_LIB.T6G(SCH_1):PAGE187_I53@PURE_QUANTA.Q_INDUCTOR4P_14(CHIPS)':
 '4': CDS_PINID='\4\';
NODE_NAME     PC303_4 1
 '@T6G_MB_LIB.T6G(SCH_1):PAGE187_I58@PURE_QUANTA.Q_CAP(CHIPS)':
 'A': CDS_PINID='A';
NODE_NAME     PC305_4 1
 '@T6G_MB_LIB.T6G(SCH_1):PAGE187_I60@PURE_QUANTA.Q_CAP(CHIPS)':
 'A': CDS_PINID='A';
NODE_NAME     PL31 4
 '@T6G_MB_LIB.T6G(SCH_1):PAGE187_I67@PURE_QUANTA.Q_INDUCTOR4P_14(CHIPS)':
 '4': CDS_PINID='\4\';
NODE_NAME     PC302_3 1
 '@T6G_MB_LIB.T6G(SCH_1):PAGE187_I69@PURE_QUANTA.Q_CAP(CHIPS)':
 'A': CDS_PINID='A';
NODE_NAME     PC304_3 1
 '@T6G_MB_LIB.T6G(SCH_1):PAGE187_I71@PURE_QUANTA.Q_CAP(CHIPS)':
 'A': CDS_PINID='A';
NODE_NAME     PR425 2
 '@T6G_MB_LIB.T6G(SCH_1):PAGE188_I22@PURE_QUANTA.Q_RES(CHIPS)':
 'B': CDS_PINID='B';
NODE_NAME     PR204 2
 '@T6G_MB_LIB.T6G(SCH_1):PAGE188_I33@PURE_QUANTA.Q_RES(CHIPS)':
 'B': CDS_PINID='B';
NODE_NAME     PL8 4
 '@T6G_MB_LIB.T6G(SCH_1):PAGE188_I53@PURE_QUANTA.Q_INDUCTOR4P_14(CHIPS)':
 '4': CDS_PINID='\4\';
NODE_NAME     PC134_6 1
 '@T6G_MB_LIB.T6G(SCH_1):PAGE188_I58@PURE_QUANTA.Q_CAP(CHIPS)':
 'A': CDS_PINID='A';
NODE_NAME     PC135_6 1
 '@T6G_MB_LIB.T6G(SCH_1):PAGE188_I60@PURE_QUANTA.Q_CAP(CHIPS)':
 'A': CDS_PINID='A';
NODE_NAME     PL33 4
 '@T6G_MB_LIB.T6G(SCH_1):PAGE188_I64@PURE_QUANTA.Q_INDUCTOR4P_14(CHIPS)':
 '4': CDS_PINID='\4\';
NODE_NAME     PC315_5 1
 '@T6G_MB_LIB.T6G(SCH_1):PAGE188_I69@PURE_QUANTA.Q_CAP(CHIPS)':
 'A': CDS_PINID='A';
NODE_NAME     PC316_5 1
 '@T6G_MB_LIB.T6G(SCH_1):PAGE188_I71@PURE_QUANTA.Q_CAP(CHIPS)':
 'A': CDS_PINID='A';
NET_NAME
'PVDDCR_CPU0_P1_EN'
 '@T6G_MB_LIB.T6G(SCH_1):PVDDCR_CPU0_P1_EN':
 C_SIGNAL='@t6g_mb_lib.t6g(sch_1):pvddcr_cpu0_p1_en';
NODE_NAME     R208 1
 '@T6G_MB_LIB.T6G(SCH_1):PAGE80_I65@PURE_QUANTA.Q_RES(CHIPS)':
 'A': CDS_PINID='A';
NODE_NAME     R8179 1
 '@T6G_MB_LIB.T6G(SCH_1):PAGE185_I84@PURE_QUANTA.Q_RES(CHIPS)':
 'A': CDS_PINID='A';
NET_NAME
'PVDDCR_CPU0_P1_EN_R'
 '@T6G_MB_LIB.T6G(SCH_1):PVDDCR_CPU0_P1_EN_R':
 C_SIGNAL='@t6g_mb_lib.t6g(sch_1):pvddcr_cpu0_p1_en_r';
NODE_NAME     C249 1
 '@T6G_MB_LIB.T6G(SCH_1):PAGE185_I86@PURE_QUANTA.Q_CAP(CHIPS)':
 'A': CDS_PINID='A';
NODE_NAME     R8179 2
 '@T6G_MB_LIB.T6G(SCH_1):PAGE185_I84@PURE_QUANTA.Q_RES(CHIPS)':
 'B': CDS_PINID='B';
NODE_NAME     PU25 17
 '@T6G_MB_LIB.T6G(SCH_1):PAGE185_I133@PURE_QUANTA.RAA229620GNPHA0(CHIPS)':
 'EN0': CDS_PINID='EN0';
NET_NAME
'PVDDCR_CPU0_P1_IMON1'
 '@T6G_MB_LIB.T6G(SCH_1):PVDDCR_CPU0_P1_IMON1':
 C_SIGNAL='@t6g_mb_lib.t6g(sch_1):pvddcr_cpu0_p1_imon1';
NODE_NAME     PU25 27
 '@T6G_MB_LIB.T6G(SCH_1):PAGE185_I133@PURE_QUANTA.RAA229620GNPHA0(CHIPS)':
 'CS11': CDS_PINID='CS11';
NODE_NAME     PU4 38
 '@T6G_MB_LIB.T6G(SCH_1):PAGE186_I88@PURE_QUANTA.ISL99390FRZTR5935(CHIPS)':
 'IOUT': CDS_PINID='IOUT';
NET_NAME
'PVDDCR_CPU0_P1_IMON2'
 '@T6G_MB_LIB.T6G(SCH_1):PVDDCR_CPU0_P1_IMON2':
 C_SIGNAL='@t6g_mb_lib.t6g(sch_1):pvddcr_cpu0_p1_imon2';
NODE_NAME     PU25 28
 '@T6G_MB_LIB.T6G(SCH_1):PAGE185_I133@PURE_QUANTA.RAA229620GNPHA0(CHIPS)':
 'CS10': CDS_PINID='CS10';
NODE_NAME     PU26 38
 '@T6G_MB_LIB.T6G(SCH_1):PAGE186_I91@PURE_QUANTA.ISL99390FRZTR5935(CHIPS)':
 'IOUT': CDS_PINID='IOUT';
NET_NAME
'PVDDCR_CPU0_P1_IMON3'
 '@T6G_MB_LIB.T6G(SCH_1):PVDDCR_CPU0_P1_IMON3':
 C_SIGNAL='@t6g_mb_lib.t6g(sch_1):pvddcr_cpu0_p1_imon3';
NODE_NAME     PU25 29
 '@T6G_MB_LIB.T6G(SCH_1):PAGE185_I133@PURE_QUANTA.RAA229620GNPHA0(CHIPS)':
 'CS9': CDS_PINID='CS9';
NODE_NAME     PU27 38
 '@T6G_MB_LIB.T6G(SCH_1):PAGE187_I39@PURE_QUANTA.ISL99390FRZTR5935(CHIPS)':
 'IOUT': CDS_PINID='IOUT';
NET_NAME
'PVDDCR_CPU0_P1_IMON4'
 '@T6G_MB_LIB.T6G(SCH_1):PVDDCR_CPU0_P1_IMON4':
 C_SIGNAL='@t6g_mb_lib.t6g(sch_1):pvddcr_cpu0_p1_imon4';
NODE_NAME     PU25 30
 '@T6G_MB_LIB.T6G(SCH_1):PAGE185_I133@PURE_QUANTA.RAA229620GNPHA0(CHIPS)':
 'CS8': CDS_PINID='CS8';
NODE_NAME     PU28 38
 '@T6G_MB_LIB.T6G(SCH_1):PAGE187_I9@PURE_QUANTA.ISL99390FRZTR5935(CHIPS)':
 'IOUT': CDS_PINID='IOUT';
NET_NAME
'PVDDCR_CPU0_P1_IMON5'
 '@T6G_MB_LIB.T6G(SCH_1):PVDDCR_CPU0_P1_IMON5':
 C_SIGNAL='@t6g_mb_lib.t6g(sch_1):pvddcr_cpu0_p1_imon5';
NODE_NAME     PU25 31
 '@T6G_MB_LIB.T6G(SCH_1):PAGE185_I133@PURE_QUANTA.RAA229620GNPHA0(CHIPS)':
 'CS7': CDS_PINID='CS7';
NODE_NAME     PU29 38
 '@T6G_MB_LIB.T6G(SCH_1):PAGE188_I18@PURE_QUANTA.ISL99390FRZTR5935(CHIPS)':
 'IOUT': CDS_PINID='IOUT';
NET_NAME
'PVDDCR_CPU0_P1_IMON6'
 '@T6G_MB_LIB.T6G(SCH_1):PVDDCR_CPU0_P1_IMON6':
 C_SIGNAL='@t6g_mb_lib.t6g(sch_1):pvddcr_cpu0_p1_imon6';
NODE_NAME     PU25 32
 '@T6G_MB_LIB.T6G(SCH_1):PAGE185_I133@PURE_QUANTA.RAA229620GNPHA0(CHIPS)':
 'CS6': CDS_PINID='CS6';
NODE_NAME     PU24 38
 '@T6G_MB_LIB.T6G(SCH_1):PAGE188_I73@PURE_QUANTA.ISL99390FRZTR5935(CHIPS)':
 'IOUT': CDS_PINID='IOUT';
NET_NAME
'PVDDCR_CPU0_P1_LSET1'
 '@T6G_MB_LIB.T6G(SCH_1):PVDDCR_CPU0_P1_LSET1':
 C_SIGNAL='@t6g_mb_lib.t6g(sch_1):pvddcr_cpu0_p1_lset1';
NODE_NAME     PR187 2
 '@T6G_MB_LIB.T6G(SCH_1):PAGE186_I37@PURE_QUANTA.Q_RES(CHIPS)':
 'B': CDS_PINID='B';
NODE_NAME     PU4 37
 '@T6G_MB_LIB.T6G(SCH_1):PAGE186_I88@PURE_QUANTA.ISL99390FRZTR5935(CHIPS)':
 'LSET': CDS_PINID='LSET';
NET_NAME
'PVDDCR_CPU0_P1_LSET2'
 '@T6G_MB_LIB.T6G(SCH_1):PVDDCR_CPU0_P1_LSET2':
 C_SIGNAL='@t6g_mb_lib.t6g(sch_1):pvddcr_cpu0_p1_lset2';
NODE_NAME     PR188 2
 '@T6G_MB_LIB.T6G(SCH_1):PAGE186_I80@PURE_QUANTA.Q_RES(CHIPS)':
 'B': CDS_PINID='B';
NODE_NAME     PU26 37
 '@T6G_MB_LIB.T6G(SCH_1):PAGE186_I91@PURE_QUANTA.ISL99390FRZTR5935(CHIPS)':
 'LSET': CDS_PINID='LSET';
NET_NAME
'PVDDCR_CPU0_P1_LSET3'
 '@T6G_MB_LIB.T6G(SCH_1):PVDDCR_CPU0_P1_LSET3':
 C_SIGNAL='@t6g_mb_lib.t6g(sch_1):pvddcr_cpu0_p1_lset3';
NODE_NAME     PR195 2
 '@T6G_MB_LIB.T6G(SCH_1):PAGE187_I34@PURE_QUANTA.Q_RES(CHIPS)':
 'B': CDS_PINID='B';
NODE_NAME     PU27 37
 '@T6G_MB_LIB.T6G(SCH_1):PAGE187_I39@PURE_QUANTA.ISL99390FRZTR5935(CHIPS)':
 'LSET': CDS_PINID='LSET';
NET_NAME
'PVDDCR_CPU0_P1_LSET4'
 '@T6G_MB_LIB.T6G(SCH_1):PVDDCR_CPU0_P1_LSET4':
 C_SIGNAL='@t6g_mb_lib.t6g(sch_1):pvddcr_cpu0_p1_lset4';
NODE_NAME     PU28 37
 '@T6G_MB_LIB.T6G(SCH_1):PAGE187_I9@PURE_QUANTA.ISL99390FRZTR5935(CHIPS)':
 'LSET': CDS_PINID='LSET';
NODE_NAME     PR196 2
 '@T6G_MB_LIB.T6G(SCH_1):PAGE187_I11@PURE_QUANTA.Q_RES(CHIPS)':
 'B': CDS_PINID='B';
NET_NAME
'PVDDCR_CPU0_P1_LSET5'
 '@T6G_MB_LIB.T6G(SCH_1):PVDDCR_CPU0_P1_LSET5':
 C_SIGNAL='@t6g_mb_lib.t6g(sch_1):pvddcr_cpu0_p1_lset5';
NODE_NAME     PU29 37
 '@T6G_MB_LIB.T6G(SCH_1):PAGE188_I18@PURE_QUANTA.ISL99390FRZTR5935(CHIPS)':
 'LSET': CDS_PINID='LSET';
NODE_NAME     PR202 2
 '@T6G_MB_LIB.T6G(SCH_1):PAGE188_I37@PURE_QUANTA.Q_RES(CHIPS)':
 'B': CDS_PINID='B';
NET_NAME
'PVDDCR_CPU0_P1_LSET6'
 '@T6G_MB_LIB.T6G(SCH_1):PVDDCR_CPU0_P1_LSET6':
 C_SIGNAL='@t6g_mb_lib.t6g(sch_1):pvddcr_cpu0_p1_lset6';
NODE_NAME     PR423 2
 '@T6G_MB_LIB.T6G(SCH_1):PAGE188_I8@PURE_QUANTA.Q_RES(CHIPS)':
 'B': CDS_PINID='B';
NODE_NAME     PU24 37
 '@T6G_MB_LIB.T6G(SCH_1):PAGE188_I73@PURE_QUANTA.ISL99390FRZTR5935(CHIPS)':
 'LSET': CDS_PINID='LSET';
NET_NAME
'PVDDCR_CPU0_P1_OCP_N'
 '@T6G_MB_LIB.T6G(SCH_1):PVDDCR_CPU0_P1_OCP_N':
 C_SIGNAL='@t6g_mb_lib.t6g(sch_1):pvddcr_cpu0_p1_ocp_n';
NODE_NAME     R8168 1
 '@T6G_MB_LIB.T6G(SCH_1):PAGE185_I43@PURE_QUANTA.Q_RES(CHIPS)':
 'A': CDS_PINID='A';
NODE_NAME     R284 2
 '@T6G_MB_LIB.T6G(SCH_1):PAGE81_I140@PURE_QUANTA.Q_RES(CHIPS)':
 'B': CDS_PINID='B';
NET_NAME
'PVDDCR_CPU0_P1_OCP_N_R'
 '@T6G_MB_LIB.T6G(SCH_1):PVDDCR_CPU0_P1_OCP_N_R':
 C_SIGNAL='@t6g_mb_lib.t6g(sch_1):pvddcr_cpu0_p1_ocp_n_r';
NODE_NAME     R8168 2
 '@T6G_MB_LIB.T6G(SCH_1):PAGE185_I43@PURE_QUANTA.Q_RES(CHIPS)':
 'B': CDS_PINID='B';
NODE_NAME     R8180 2
 '@T6G_MB_LIB.T6G(SCH_1):PAGE185_I54@PURE_QUANTA.Q_RES(CHIPS)':
 'B': CDS_PINID='B';
NODE_NAME     PU25 41
 '@T6G_MB_LIB.T6G(SCH_1):PAGE185_I133@PURE_QUANTA.RAA229620GNPHA0(CHIPS)':
 'OCP_L': CDS_PINID='OCP_L';
NET_NAME
'PVDDCR_CPU0_P1_PMALERT'
 '@T6G_MB_LIB.T6G(SCH_1):PVDDCR_CPU0_P1_PMALERT':
 C_SIGNAL='@t6g_mb_lib.t6g(sch_1):pvddcr_cpu0_p1_pmalert';
NODE_NAME     R1187 1
 '@T6G_MB_LIB.T6G(SCH_1):PAGE82_I59@PURE_QUANTA.Q_RES(CHIPS)':
 'A': CDS_PINID='A';
NODE_NAME     U18 M5
 '@T6G_MB_LIB.T6G(SCH_1):PAGE81_I143@PURE_QUANTA.LCMXO3LF9400C5BG484C(CHIPS)':
 'PL17D': CDS_PINID='PL17D';
NODE_NAME     R8177 1
 '@T6G_MB_LIB.T6G(SCH_1):PAGE185_I79@PURE_QUANTA.Q_RES(CHIPS)':
 'A': CDS_PINID='A';
NODE_NAME     C5012 1
 '@T6G_MB_LIB.T6G(SCH_1):PAGE185_I139@PURE_QUANTA.Q_CAP(CHIPS)':
 'A': CDS_PINID='A';
NET_NAME
'PVDDCR_CPU0_P1_PMALERT_R'
 '@T6G_MB_LIB.T6G(SCH_1):PVDDCR_CPU0_P1_PMALERT_R':
 C_SIGNAL='@t6g_mb_lib.t6g(sch_1):pvddcr_cpu0_p1_pmalert_r';
NODE_NAME     R8177 2
 '@T6G_MB_LIB.T6G(SCH_1):PAGE185_I79@PURE_QUANTA.Q_RES(CHIPS)':
 'B': CDS_PINID='B';
NODE_NAME     PU25 15
 '@T6G_MB_LIB.T6G(SCH_1):PAGE185_I133@PURE_QUANTA.RAA229620GNPHA0(CHIPS)':
 'NPMALERT': CDS_PINID='NPMALERT';
NET_NAME
'PVDDCR_CPU0_P1_PMSCL_R'
 '@T6G_MB_LIB.T6G(SCH_1):PVDDCR_CPU0_P1_PMSCL_R':
 C_SIGNAL='@t6g_mb_lib.t6g(sch_1):pvddcr_cpu0_p1_pmscl_r';
NODE_NAME     R175 2
 '@T6G_MB_LIB.T6G(SCH_1):PAGE185_I81@PURE_QUANTA.Q_RES(CHIPS)':
 'B': CDS_PINID='B';
NODE_NAME     PU25 14
 '@T6G_MB_LIB.T6G(SCH_1):PAGE185_I133@PURE_QUANTA.RAA229620GNPHA0(CHIPS)':
 'PMSCL': CDS_PINID='PMSCL';
NET_NAME
'PVDDCR_CPU0_P1_PMSDA_R'
 '@T6G_MB_LIB.T6G(SCH_1):PVDDCR_CPU0_P1_PMSDA_R':
 C_SIGNAL='@t6g_mb_lib.t6g(sch_1):pvddcr_cpu0_p1_pmsda_r';
NODE_NAME     R8176 2
 '@T6G_MB_LIB.T6G(SCH_1):PAGE185_I80@PURE_QUANTA.Q_RES(CHIPS)':
 'B': CDS_PINID='B';
NODE_NAME     PU25 13
 '@T6G_MB_LIB.T6G(SCH_1):PAGE185_I133@PURE_QUANTA.RAA229620GNPHA0(CHIPS)':
 'PMSDA': CDS_PINID='PMSDA';
NET_NAME
'PVDDCR_CPU0_P1_PVCC'
 '@T6G_MB_LIB.T6G(SCH_1):PVDDCR_CPU0_P1_PVCC':
 C_SIGNAL='@t6g_mb_lib.t6g(sch_1):pvddcr_cpu0_p1_pvcc',
 CDS_GLOBAL_NET='TRUE';
NODE_NAME     PR335 1
 '@T6G_MB_LIB.T6G(SCH_1):PAGE186_I3@PURE_QUANTA.Q_RES(CHIPS)':
 'A': CDS_PINID='A';
NODE_NAME     PR186 1
 '@T6G_MB_LIB.T6G(SCH_1):PAGE186_I11@PURE_QUANTA.Q_RES(CHIPS)':
 'A': CDS_PINID='A';
NODE_NAME     PC259_C0P1_2 1
 '@T6G_MB_LIB.T6G(SCH_1):PAGE186_I13@PURE_QUANTA.Q_CAP(CHIPS)':
 'A': CDS_PINID='A';
NODE_NAME     PR205 1
 '@T6G_MB_LIB.T6G(SCH_1):PAGE190_I39@PURE_QUANTA.Q_RES(CHIPS)':
 'A': CDS_PINID='A';
NODE_NAME     PC347_SOP1_3 1
 '@T6G_MB_LIB.T6G(SCH_1):PAGE191_I18@PURE_QUANTA.Q_CAP(CHIPS)':
 'A': CDS_PINID='A';
NODE_NAME     PU32 4
 '@T6G_MB_LIB.T6G(SCH_1):PAGE191_I38@PURE_QUANTA.ISL99390FRZTR5935(CHIPS)':
 'PVCC': CDS_PINID='PVCC';
NODE_NAME     PR336 1
 '@T6G_MB_LIB.T6G(SCH_1):PAGE186_I41@PURE_QUANTA.Q_RES(CHIPS)':
 'A': CDS_PINID='A';
NODE_NAME     PR185 1
 '@T6G_MB_LIB.T6G(SCH_1):PAGE186_I43@PURE_QUANTA.Q_RES(CHIPS)':
 'A': CDS_PINID='A';
NODE_NAME     PC258_C0P1_1 1
 '@T6G_MB_LIB.T6G(SCH_1):PAGE186_I44@PURE_QUANTA.Q_CAP(CHIPS)':
 'A': CDS_PINID='A';
NODE_NAME     PU4 4
 '@T6G_MB_LIB.T6G(SCH_1):PAGE186_I88@PURE_QUANTA.ISL99390FRZTR5935(CHIPS)':
 'PVCC': CDS_PINID='PVCC';
NODE_NAME     PU26 4
 '@T6G_MB_LIB.T6G(SCH_1):PAGE186_I91@PURE_QUANTA.ISL99390FRZTR5935(CHIPS)':
 'PVCC': CDS_PINID='PVCC';
NODE_NAME     PU28 4
 '@T6G_MB_LIB.T6G(SCH_1):PAGE187_I9@PURE_QUANTA.ISL99390FRZTR5935(CHIPS)':
 'PVCC': CDS_PINID='PVCC';
NODE_NAME     PR194 1
 '@T6G_MB_LIB.T6G(SCH_1):PAGE187_I12@PURE_QUANTA.Q_RES(CHIPS)':
 'A': CDS_PINID='A';
NODE_NAME     PC289_C0P1_4 1
 '@T6G_MB_LIB.T6G(SCH_1):PAGE187_I15@PURE_QUANTA.Q_CAP(CHIPS)':
 'A': CDS_PINID='A';
NODE_NAME     PR193 1
 '@T6G_MB_LIB.T6G(SCH_1):PAGE187_I38@PURE_QUANTA.Q_RES(CHIPS)':
 'A': CDS_PINID='A';
NODE_NAME     PU27 4
 '@T6G_MB_LIB.T6G(SCH_1):PAGE187_I39@PURE_QUANTA.ISL99390FRZTR5935(CHIPS)':
 'PVCC': CDS_PINID='PVCC';
NODE_NAME     PC288_C0P1_3 1
 '@T6G_MB_LIB.T6G(SCH_1):PAGE187_I41@PURE_QUANTA.Q_CAP(CHIPS)':
 'A': CDS_PINID='A';
NODE_NAME     PR422 1
 '@T6G_MB_LIB.T6G(SCH_1):PAGE188_I12@PURE_QUANTA.Q_RES(CHIPS)':
 'A': CDS_PINID='A';
NODE_NAME     PC126_C0P1_6 1
 '@T6G_MB_LIB.T6G(SCH_1):PAGE188_I15@PURE_QUANTA.Q_CAP(CHIPS)':
 'A': CDS_PINID='A';
NODE_NAME     PU29 4
 '@T6G_MB_LIB.T6G(SCH_1):PAGE188_I18@PURE_QUANTA.ISL99390FRZTR5935(CHIPS)':
 'PVCC': CDS_PINID='PVCC';
NODE_NAME     PR201 1
 '@T6G_MB_LIB.T6G(SCH_1):PAGE188_I41@PURE_QUANTA.Q_RES(CHIPS)':
 'A': CDS_PINID='A';
NODE_NAME     PC308_C0P1_5 1
 '@T6G_MB_LIB.T6G(SCH_1):PAGE188_I43@PURE_QUANTA.Q_CAP(CHIPS)':
 'A': CDS_PINID='A';
NODE_NAME     PU24 4
 '@T6G_MB_LIB.T6G(SCH_1):PAGE188_I73@PURE_QUANTA.ISL99390FRZTR5935(CHIPS)':
 'PVCC': CDS_PINID='PVCC';
NODE_NAME     PR213 1
 '@T6G_MB_LIB.T6G(SCH_1):PAGE191_I14@PURE_QUANTA.Q_RES(CHIPS)':
 'A': CDS_PINID='A';
NODE_NAME     PR206 1
 '@T6G_MB_LIB.T6G(SCH_1):PAGE190_I12@PURE_QUANTA.Q_RES(CHIPS)':
 'A': CDS_PINID='A';
NODE_NAME     PC322_SOP1_2 1
 '@T6G_MB_LIB.T6G(SCH_1):PAGE190_I14@PURE_QUANTA.Q_CAP(CHIPS)':
 'A': CDS_PINID='A';
NODE_NAME     PU30 4
 '@T6G_MB_LIB.T6G(SCH_1):PAGE190_I17@PURE_QUANTA.ISL99390FRZTR5935(CHIPS)':
 'PVCC': CDS_PINID='PVCC';
NODE_NAME     PC321_SOP1_1 1
 '@T6G_MB_LIB.T6G(SCH_1):PAGE190_I41@PURE_QUANTA.Q_CAP(CHIPS)':
 'A': CDS_PINID='A';
NODE_NAME     PU31 4
 '@T6G_MB_LIB.T6G(SCH_1):PAGE190_I86@PURE_QUANTA.ISL99390FRZTR5935(CHIPS)':
 'PVCC': CDS_PINID='PVCC';
NET_NAME
'PVDDCR_CPU0_P1_PWM1'
 '@T6G_MB_LIB.T6G(SCH_1):PVDDCR_CPU0_P1_PWM1':
 C_SIGNAL='@t6g_mb_lib.t6g(sch_1):pvddcr_cpu0_p1_pwm1';
NODE_NAME     PU25 12
 '@T6G_MB_LIB.T6G(SCH_1):PAGE185_I133@PURE_QUANTA.RAA229620GNPHA0(CHIPS)':
 'PWM11': CDS_PINID='PWM11';
NODE_NAME     PU4 34
 '@T6G_MB_LIB.T6G(SCH_1):PAGE186_I88@PURE_QUANTA.ISL99390FRZTR5935(CHIPS)':
 'PWM': CDS_PINID='PWM';
NET_NAME
'PVDDCR_CPU0_P1_PWM2'
 '@T6G_MB_LIB.T6G(SCH_1):PVDDCR_CPU0_P1_PWM2':
 C_SIGNAL='@t6g_mb_lib.t6g(sch_1):pvddcr_cpu0_p1_pwm2';
NODE_NAME     PU25 11
 '@T6G_MB_LIB.T6G(SCH_1):PAGE185_I133@PURE_QUANTA.RAA229620GNPHA0(CHIPS)':
 'PWM10': CDS_PINID='PWM10';
NODE_NAME     PU26 34
 '@T6G_MB_LIB.T6G(SCH_1):PAGE186_I91@PURE_QUANTA.ISL99390FRZTR5935(CHIPS)':
 'PWM': CDS_PINID='PWM';
NET_NAME
'PVDDCR_CPU0_P1_PWM3'
 '@T6G_MB_LIB.T6G(SCH_1):PVDDCR_CPU0_P1_PWM3':
 C_SIGNAL='@t6g_mb_lib.t6g(sch_1):pvddcr_cpu0_p1_pwm3';
NODE_NAME     PU25 10
 '@T6G_MB_LIB.T6G(SCH_1):PAGE185_I133@PURE_QUANTA.RAA229620GNPHA0(CHIPS)':
 'PWM9': CDS_PINID='PWM9';
NODE_NAME     PU27 34
 '@T6G_MB_LIB.T6G(SCH_1):PAGE187_I39@PURE_QUANTA.ISL99390FRZTR5935(CHIPS)':
 'PWM': CDS_PINID='PWM';
NET_NAME
'PVDDCR_CPU0_P1_PWM4'
 '@T6G_MB_LIB.T6G(SCH_1):PVDDCR_CPU0_P1_PWM4':
 C_SIGNAL='@t6g_mb_lib.t6g(sch_1):pvddcr_cpu0_p1_pwm4';
NODE_NAME     PU25 9
 '@T6G_MB_LIB.T6G(SCH_1):PAGE185_I133@PURE_QUANTA.RAA229620GNPHA0(CHIPS)':
 'PWM8': CDS_PINID='PWM8';
NODE_NAME     PU28 34
 '@T6G_MB_LIB.T6G(SCH_1):PAGE187_I9@PURE_QUANTA.ISL99390FRZTR5935(CHIPS)':
 'PWM': CDS_PINID='PWM';
NET_NAME
'PVDDCR_CPU0_P1_PWM5'
 '@T6G_MB_LIB.T6G(SCH_1):PVDDCR_CPU0_P1_PWM5':
 C_SIGNAL='@t6g_mb_lib.t6g(sch_1):pvddcr_cpu0_p1_pwm5';
NODE_NAME     PU25 8
 '@T6G_MB_LIB.T6G(SCH_1):PAGE185_I133@PURE_QUANTA.RAA229620GNPHA0(CHIPS)':
 'PWM7': CDS_PINID='PWM7';
NODE_NAME     PU29 34
 '@T6G_MB_LIB.T6G(SCH_1):PAGE188_I18@PURE_QUANTA.ISL99390FRZTR5935(CHIPS)':
 'PWM': CDS_PINID='PWM';
NET_NAME
'PVDDCR_CPU0_P1_PWM6'
 '@T6G_MB_LIB.T6G(SCH_1):PVDDCR_CPU0_P1_PWM6':
 C_SIGNAL='@t6g_mb_lib.t6g(sch_1):pvddcr_cpu0_p1_pwm6';
NODE_NAME     PU25 7
 '@T6G_MB_LIB.T6G(SCH_1):PAGE185_I133@PURE_QUANTA.RAA229620GNPHA0(CHIPS)':
 'PWM6': CDS_PINID='PWM6';
NODE_NAME     PU24 34
 '@T6G_MB_LIB.T6G(SCH_1):PAGE188_I73@PURE_QUANTA.ISL99390FRZTR5935(CHIPS)':
 'PWM': CDS_PINID='PWM';
NET_NAME
'PVDDCR_CPU0_P1_RESET_N'
 '@T6G_MB_LIB.T6G(SCH_1):PVDDCR_CPU0_P1_RESET_N':
 C_SIGNAL='@t6g_mb_lib.t6g(sch_1):pvddcr_cpu0_p1_reset_n';
NODE_NAME     U40 6
 '@T6G_MB_LIB.T6G(SCH_1):PAGE77_I21@PURE_QUANTA.SN74LVC2G07DCKR(CHIPS)':
 '1Y': CDS_PINID='\1y\';
NODE_NAME     R8182 1
 '@T6G_MB_LIB.T6G(SCH_1):PAGE185_I42@PURE_QUANTA.Q_RES(CHIPS)':
 'A': CDS_PINID='A';
NET_NAME
'PVDDCR_CPU0_P1_RESET_N_R'
 '@T6G_MB_LIB.T6G(SCH_1):PVDDCR_CPU0_P1_RESET_N_R':
 C_SIGNAL='@t6g_mb_lib.t6g(sch_1):pvddcr_cpu0_p1_reset_n_r';
NODE_NAME     R8182 2
 '@T6G_MB_LIB.T6G(SCH_1):PAGE185_I42@PURE_QUANTA.Q_RES(CHIPS)':
 'B': CDS_PINID='B';
NODE_NAME     R8184 2
 '@T6G_MB_LIB.T6G(SCH_1):PAGE185_I41@PURE_QUANTA.Q_RES(CHIPS)':
 'B': CDS_PINID='B';
NODE_NAME     PU25 18
 '@T6G_MB_LIB.T6G(SCH_1):PAGE185_I133@PURE_QUANTA.RAA229620GNPHA0(CHIPS)':
 'RESET_L': CDS_PINID='RESET_L';
NET_NAME
'PVDDCR_CPU0_P1_TEMP0'
 '@T6G_MB_LIB.T6G(SCH_1):PVDDCR_CPU0_P1_TEMP0':
 C_SIGNAL='@t6g_mb_lib.t6g(sch_1):pvddcr_cpu0_p1_temp0';
NODE_NAME     PC250 1
 '@T6G_MB_LIB.T6G(SCH_1):PAGE185_I91@PURE_QUANTA.Q_CAP(CHIPS)':
 'A': CDS_PINID='A';
NODE_NAME     PU25 44
 '@T6G_MB_LIB.T6G(SCH_1):PAGE185_I133@PURE_QUANTA.RAA229620GNPHA0(CHIPS)':
 'TEMP0': CDS_PINID='TEMP0';
NODE_NAME     PU4 36
 '@T6G_MB_LIB.T6G(SCH_1):PAGE186_I88@PURE_QUANTA.ISL99390FRZTR5935(CHIPS)':
 'TOUT_FLT': CDS_PINID='TOUT_FLT';
NODE_NAME     PU26 36
 '@T6G_MB_LIB.T6G(SCH_1):PAGE186_I91@PURE_QUANTA.ISL99390FRZTR5935(CHIPS)':
 'TOUT_FLT': CDS_PINID='TOUT_FLT';
NODE_NAME     PU28 36
 '@T6G_MB_LIB.T6G(SCH_1):PAGE187_I9@PURE_QUANTA.ISL99390FRZTR5935(CHIPS)':
 'TOUT_FLT': CDS_PINID='TOUT_FLT';
NODE_NAME     PU27 36
 '@T6G_MB_LIB.T6G(SCH_1):PAGE187_I39@PURE_QUANTA.ISL99390FRZTR5935(CHIPS)':
 'TOUT_FLT': CDS_PINID='TOUT_FLT';
NODE_NAME     PU29 36
 '@T6G_MB_LIB.T6G(SCH_1):PAGE188_I18@PURE_QUANTA.ISL99390FRZTR5935(CHIPS)':
 'TOUT_FLT': CDS_PINID='TOUT_FLT';
NODE_NAME     PU24 36
 '@T6G_MB_LIB.T6G(SCH_1):PAGE188_I73@PURE_QUANTA.ISL99390FRZTR5935(CHIPS)':
 'TOUT_FLT': CDS_PINID='TOUT_FLT';
NET_NAME
'PVDDCR_CPU0_P1_VCC'
 '@T6G_MB_LIB.T6G(SCH_1):PVDDCR_CPU0_P1_VCC':
 C_SIGNAL='@t6g_mb_lib.t6g(sch_1):pvddcr_cpu0_p1_vcc';
NODE_NAME     PC10 1
 '@T6G_MB_LIB.T6G(SCH_1):PAGE185_I116@PURE_QUANTA.Q_CAP(CHIPS)':
 'A': CDS_PINID='A';
NODE_NAME     PC252 1
 '@T6G_MB_LIB.T6G(SCH_1):PAGE185_I127@PURE_QUANTA.Q_CAP(CHIPS)':
 'A': CDS_PINID='A';
NODE_NAME     PR183 1
 '@T6G_MB_LIB.T6G(SCH_1):PAGE185_I129@PURE_QUANTA.Q_RES(CHIPS)':
 'A': CDS_PINID='A';
NODE_NAME     PU25 47
 '@T6G_MB_LIB.T6G(SCH_1):PAGE185_I133@PURE_QUANTA.RAA229620GNPHA0(CHIPS)':
 'VCC': CDS_PINID='VCC';
NET_NAME
'PVDDCR_CPU0_P1_VCC1'
 '@T6G_MB_LIB.T6G(SCH_1):PVDDCR_CPU0_P1_VCC1':
 C_SIGNAL='@t6g_mb_lib.t6g(sch_1):pvddcr_cpu0_p1_vcc1';
NODE_NAME     PC256 1
 '@T6G_MB_LIB.T6G(SCH_1):PAGE186_I36@PURE_QUANTA.Q_CAP(CHIPS)':
 'A': CDS_PINID='A';
NODE_NAME     PR185 2
 '@T6G_MB_LIB.T6G(SCH_1):PAGE186_I43@PURE_QUANTA.Q_RES(CHIPS)':
 'B': CDS_PINID='B';
NODE_NAME     PU4 35
 '@T6G_MB_LIB.T6G(SCH_1):PAGE186_I88@PURE_QUANTA.ISL99390FRZTR5935(CHIPS)':
 'EN': CDS_PINID='EN';
NODE_NAME     PU4 3
 '@T6G_MB_LIB.T6G(SCH_1):PAGE186_I88@PURE_QUANTA.ISL99390FRZTR5935(CHIPS)':
 'VCC': CDS_PINID='VCC';
NET_NAME
'PVDDCR_CPU0_P1_VCC2'
 '@T6G_MB_LIB.T6G(SCH_1):PVDDCR_CPU0_P1_VCC2':
 C_SIGNAL='@t6g_mb_lib.t6g(sch_1):pvddcr_cpu0_p1_vcc2';
NODE_NAME     PR186 2
 '@T6G_MB_LIB.T6G(SCH_1):PAGE186_I11@PURE_QUANTA.Q_RES(CHIPS)':
 'B': CDS_PINID='B';
NODE_NAME     PC257 1
 '@T6G_MB_LIB.T6G(SCH_1):PAGE186_I9@PURE_QUANTA.Q_CAP(CHIPS)':
 'A': CDS_PINID='A';
NODE_NAME     PU26 35
 '@T6G_MB_LIB.T6G(SCH_1):PAGE186_I91@PURE_QUANTA.ISL99390FRZTR5935(CHIPS)':
 'EN': CDS_PINID='EN';
NODE_NAME     PU26 3
 '@T6G_MB_LIB.T6G(SCH_1):PAGE186_I91@PURE_QUANTA.ISL99390FRZTR5935(CHIPS)':
 'VCC': CDS_PINID='VCC';
NET_NAME
'PVDDCR_CPU0_P1_VCC3'
 '@T6G_MB_LIB.T6G(SCH_1):PVDDCR_CPU0_P1_VCC3':
 C_SIGNAL='@t6g_mb_lib.t6g(sch_1):pvddcr_cpu0_p1_vcc3';
NODE_NAME     PC286 1
 '@T6G_MB_LIB.T6G(SCH_1):PAGE187_I37@PURE_QUANTA.Q_CAP(CHIPS)':
 'A': CDS_PINID='A';
NODE_NAME     PR193 2
 '@T6G_MB_LIB.T6G(SCH_1):PAGE187_I38@PURE_QUANTA.Q_RES(CHIPS)':
 'B': CDS_PINID='B';
NODE_NAME     PU27 35
 '@T6G_MB_LIB.T6G(SCH_1):PAGE187_I39@PURE_QUANTA.ISL99390FRZTR5935(CHIPS)':
 'EN': CDS_PINID='EN';
NODE_NAME     PU27 3
 '@T6G_MB_LIB.T6G(SCH_1):PAGE187_I39@PURE_QUANTA.ISL99390FRZTR5935(CHIPS)':
 'VCC': CDS_PINID='VCC';
NET_NAME
'PVDDCR_CPU0_P1_VCC4'
 '@T6G_MB_LIB.T6G(SCH_1):PVDDCR_CPU0_P1_VCC4':
 C_SIGNAL='@t6g_mb_lib.t6g(sch_1):pvddcr_cpu0_p1_vcc4';
NODE_NAME     PC287 1
 '@T6G_MB_LIB.T6G(SCH_1):PAGE187_I6@PURE_QUANTA.Q_CAP(CHIPS)':
 'A': CDS_PINID='A';
NODE_NAME     PU28 35
 '@T6G_MB_LIB.T6G(SCH_1):PAGE187_I9@PURE_QUANTA.ISL99390FRZTR5935(CHIPS)':
 'EN': CDS_PINID='EN';
NODE_NAME     PU28 3
 '@T6G_MB_LIB.T6G(SCH_1):PAGE187_I9@PURE_QUANTA.ISL99390FRZTR5935(CHIPS)':
 'VCC': CDS_PINID='VCC';
NODE_NAME     PR194 2
 '@T6G_MB_LIB.T6G(SCH_1):PAGE187_I12@PURE_QUANTA.Q_RES(CHIPS)':
 'B': CDS_PINID='B';
NET_NAME
'PVDDCR_CPU0_P1_VCC5'
 '@T6G_MB_LIB.T6G(SCH_1):PVDDCR_CPU0_P1_VCC5':
 C_SIGNAL='@t6g_mb_lib.t6g(sch_1):pvddcr_cpu0_p1_vcc5';
NODE_NAME     PU29 35
 '@T6G_MB_LIB.T6G(SCH_1):PAGE188_I18@PURE_QUANTA.ISL99390FRZTR5935(CHIPS)':
 'EN': CDS_PINID='EN';
NODE_NAME     PU29 3
 '@T6G_MB_LIB.T6G(SCH_1):PAGE188_I18@PURE_QUANTA.ISL99390FRZTR5935(CHIPS)':
 'VCC': CDS_PINID='VCC';
NODE_NAME     PC307 1
 '@T6G_MB_LIB.T6G(SCH_1):PAGE188_I39@PURE_QUANTA.Q_CAP(CHIPS)':
 'A': CDS_PINID='A';
NODE_NAME     PR201 2
 '@T6G_MB_LIB.T6G(SCH_1):PAGE188_I41@PURE_QUANTA.Q_RES(CHIPS)':
 'B': CDS_PINID='B';
NET_NAME
'PVDDCR_CPU0_P1_VCC6'
 '@T6G_MB_LIB.T6G(SCH_1):PVDDCR_CPU0_P1_VCC6':
 C_SIGNAL='@t6g_mb_lib.t6g(sch_1):pvddcr_cpu0_p1_vcc6';
NODE_NAME     PC125 1
 '@T6G_MB_LIB.T6G(SCH_1):PAGE188_I10@PURE_QUANTA.Q_CAP(CHIPS)':
 'A': CDS_PINID='A';
NODE_NAME     PR422 2
 '@T6G_MB_LIB.T6G(SCH_1):PAGE188_I12@PURE_QUANTA.Q_RES(CHIPS)':
 'B': CDS_PINID='B';
NODE_NAME     PU24 35
 '@T6G_MB_LIB.T6G(SCH_1):PAGE188_I73@PURE_QUANTA.ISL99390FRZTR5935(CHIPS)':
 'EN': CDS_PINID='EN';
NODE_NAME     PU24 3
 '@T6G_MB_LIB.T6G(SCH_1):PAGE188_I73@PURE_QUANTA.ISL99390FRZTR5935(CHIPS)':
 'VCC': CDS_PINID='VCC';
NET_NAME
'PVDDCR_CPU0_P1_VCCS'
 '@T6G_MB_LIB.T6G(SCH_1):PVDDCR_CPU0_P1_VCCS':
 C_SIGNAL='@t6g_mb_lib.t6g(sch_1):pvddcr_cpu0_p1_vccs';
NODE_NAME     PC11 1
 '@T6G_MB_LIB.T6G(SCH_1):PAGE185_I114@PURE_QUANTA.Q_CAP(CHIPS)':
 'A': CDS_PINID='A';
NODE_NAME     PC254_1 1
 '@T6G_MB_LIB.T6G(SCH_1):PAGE186_I16@PURE_QUANTA.Q_CAP(CHIPS)':
 'A': CDS_PINID='A';
NODE_NAME     PC318_8 1
 '@T6G_MB_LIB.T6G(SCH_1):PAGE190_I4@PURE_QUANTA.Q_CAP(CHIPS)':
 'A': CDS_PINID='A';
NODE_NAME     PU32 39
 '@T6G_MB_LIB.T6G(SCH_1):PAGE191_I38@PURE_QUANTA.ISL99390FRZTR5935(CHIPS)':
 'REFIN': CDS_PINID='REFIN';
NODE_NAME     PC251 1
 '@T6G_MB_LIB.T6G(SCH_1):PAGE185_I125@PURE_QUANTA.Q_CAP(CHIPS)':
 'A': CDS_PINID='A';
NODE_NAME     PU25 48
 '@T6G_MB_LIB.T6G(SCH_1):PAGE185_I133@PURE_QUANTA.RAA229620GNPHA0(CHIPS)':
 'VCCS': CDS_PINID='VCCS';
NODE_NAME     PC255_2 1
 '@T6G_MB_LIB.T6G(SCH_1):PAGE186_I5@PURE_QUANTA.Q_CAP(CHIPS)':
 'A': CDS_PINID='A';
NODE_NAME     PU4 39
 '@T6G_MB_LIB.T6G(SCH_1):PAGE186_I88@PURE_QUANTA.ISL99390FRZTR5935(CHIPS)':
 'REFIN': CDS_PINID='REFIN';
NODE_NAME     PU26 39
 '@T6G_MB_LIB.T6G(SCH_1):PAGE186_I91@PURE_QUANTA.ISL99390FRZTR5935(CHIPS)':
 'REFIN': CDS_PINID='REFIN';
NODE_NAME     PC285_4 1
 '@T6G_MB_LIB.T6G(SCH_1):PAGE187_I2@PURE_QUANTA.Q_CAP(CHIPS)':
 'A': CDS_PINID='A';
NODE_NAME     PU28 39
 '@T6G_MB_LIB.T6G(SCH_1):PAGE187_I9@PURE_QUANTA.ISL99390FRZTR5935(CHIPS)':
 'REFIN': CDS_PINID='REFIN';
NODE_NAME     PC284_3 1
 '@T6G_MB_LIB.T6G(SCH_1):PAGE187_I28@PURE_QUANTA.Q_CAP(CHIPS)':
 'A': CDS_PINID='A';
NODE_NAME     PU27 39
 '@T6G_MB_LIB.T6G(SCH_1):PAGE187_I39@PURE_QUANTA.ISL99390FRZTR5935(CHIPS)':
 'REFIN': CDS_PINID='REFIN';
NODE_NAME     PC124_6 1
 '@T6G_MB_LIB.T6G(SCH_1):PAGE188_I4@PURE_QUANTA.Q_CAP(CHIPS)':
 'A': CDS_PINID='A';
NODE_NAME     PU29 39
 '@T6G_MB_LIB.T6G(SCH_1):PAGE188_I18@PURE_QUANTA.ISL99390FRZTR5935(CHIPS)':
 'REFIN': CDS_PINID='REFIN';
NODE_NAME     PC306_5 1
 '@T6G_MB_LIB.T6G(SCH_1):PAGE188_I34@PURE_QUANTA.Q_CAP(CHIPS)':
 'A': CDS_PINID='A';
NODE_NAME     PU24 39
 '@T6G_MB_LIB.T6G(SCH_1):PAGE188_I73@PURE_QUANTA.ISL99390FRZTR5935(CHIPS)':
 'REFIN': CDS_PINID='REFIN';
NODE_NAME     PC345_9 1
 '@T6G_MB_LIB.T6G(SCH_1):PAGE191_I2@PURE_QUANTA.Q_CAP(CHIPS)':
 'A': CDS_PINID='A';
NODE_NAME     PU30 39
 '@T6G_MB_LIB.T6G(SCH_1):PAGE190_I17@PURE_QUANTA.ISL99390FRZTR5935(CHIPS)':
 'REFIN': CDS_PINID='REFIN';
NODE_NAME     PC317_7 1
 '@T6G_MB_LIB.T6G(SCH_1):PAGE190_I32@PURE_QUANTA.Q_CAP(CHIPS)':
 'A': CDS_PINID='A';
NODE_NAME     PU31 39
 '@T6G_MB_LIB.T6G(SCH_1):PAGE190_I86@PURE_QUANTA.ISL99390FRZTR5935(CHIPS)':
 'REFIN': CDS_PINID='REFIN';
NET_NAME
'PVDDCR_CPU0_P1_VINSEN'
 '@T6G_MB_LIB.T6G(SCH_1):PVDDCR_CPU0_P1_VINSEN':
 C_SIGNAL='@t6g_mb_lib.t6g(sch_1):pvddcr_cpu0_p1_vinsen';
NODE_NAME     PR181 2
 '@T6G_MB_LIB.T6G(SCH_1):PAGE185_I47@PURE_QUANTA.Q_RES(CHIPS)':
 'B': CDS_PINID='B';
NODE_NAME     PR602 1
 '@T6G_MB_LIB.T6G(SCH_1):PAGE185_I48@PURE_QUANTA.Q_RES(CHIPS)':
 'A': CDS_PINID='A';
NODE_NAME     PC6 1
 '@T6G_MB_LIB.T6G(SCH_1):PAGE185_I51@PURE_QUANTA.Q_CAP(CHIPS)':
 'A': CDS_PINID='A';
NODE_NAME     PU25 46
 '@T6G_MB_LIB.T6G(SCH_1):PAGE185_I133@PURE_QUANTA.RAA229620GNPHA0(CHIPS)':
 'VINSEN': CDS_PINID='VINSEN';
NET_NAME
'PVDDCR_CPU0_P1_VMON'
 '@T6G_MB_LIB.T6G(SCH_1):PVDDCR_CPU0_P1_VMON':
 C_SIGNAL='@t6g_mb_lib.t6g(sch_1):pvddcr_cpu0_p1_vmon';
NODE_NAME     PR157 2
 '@T6G_MB_LIB.T6G(SCH_1):PAGE185_I14@PURE_QUANTA.Q_RES(CHIPS)':
 'B': CDS_PINID='B';
NODE_NAME     PR4 1
 '@T6G_MB_LIB.T6G(SCH_1):PAGE185_I20@PURE_QUANTA.Q_RES(CHIPS)':
 'A': CDS_PINID='A';
NODE_NAME     PC243 1
 '@T6G_MB_LIB.T6G(SCH_1):PAGE185_I22@PURE_QUANTA.Q_CAP(CHIPS)':
 'A': CDS_PINID='A';
NODE_NAME     PU25 45
 '@T6G_MB_LIB.T6G(SCH_1):PAGE185_I133@PURE_QUANTA.RAA229620GNPHA0(CHIPS)':
 'VMON||IINSEN': CDS_PINID='\vmon||iinsen\';
NET_NAME
'PVDDCR_CPU0_P1_VOS1'
 '@T6G_MB_LIB.T6G(SCH_1):PVDDCR_CPU0_P1_VOS1':
 C_SIGNAL='@t6g_mb_lib.t6g(sch_1):pvddcr_cpu0_p1_vos1';
NODE_NAME     PR191 1
 '@T6G_MB_LIB.T6G(SCH_1):PAGE186_I35@PURE_QUANTA.Q_RES(CHIPS)':
 'A': CDS_PINID='A';
NODE_NAME     PU4 1
 '@T6G_MB_LIB.T6G(SCH_1):PAGE186_I88@PURE_QUANTA.ISL99390FRZTR5935(CHIPS)':
 'VOS': CDS_PINID='VOS';
NET_NAME
'PVDDCR_CPU0_P1_VOS2'
 '@T6G_MB_LIB.T6G(SCH_1):PVDDCR_CPU0_P1_VOS2':
 C_SIGNAL='@t6g_mb_lib.t6g(sch_1):pvddcr_cpu0_p1_vos2';
NODE_NAME     PR192 1
 '@T6G_MB_LIB.T6G(SCH_1):PAGE186_I23@PURE_QUANTA.Q_RES(CHIPS)':
 'A': CDS_PINID='A';
NODE_NAME     PU26 1
 '@T6G_MB_LIB.T6G(SCH_1):PAGE186_I91@PURE_QUANTA.ISL99390FRZTR5935(CHIPS)':
 'VOS': CDS_PINID='VOS';
NET_NAME
'PVDDCR_CPU0_P1_VOS3'
 '@T6G_MB_LIB.T6G(SCH_1):PVDDCR_CPU0_P1_VOS3':
 C_SIGNAL='@t6g_mb_lib.t6g(sch_1):pvddcr_cpu0_p1_vos3';
NODE_NAME     PR199 1
 '@T6G_MB_LIB.T6G(SCH_1):PAGE187_I27@PURE_QUANTA.Q_RES(CHIPS)':
 'A': CDS_PINID='A';
NODE_NAME     PU27 1
 '@T6G_MB_LIB.T6G(SCH_1):PAGE187_I39@PURE_QUANTA.ISL99390FRZTR5935(CHIPS)':
 'VOS': CDS_PINID='VOS';
NET_NAME
'PVDDCR_CPU0_P1_VOS4'
 '@T6G_MB_LIB.T6G(SCH_1):PVDDCR_CPU0_P1_VOS4':
 C_SIGNAL='@t6g_mb_lib.t6g(sch_1):pvddcr_cpu0_p1_vos4';
NODE_NAME     PU28 1
 '@T6G_MB_LIB.T6G(SCH_1):PAGE187_I9@PURE_QUANTA.ISL99390FRZTR5935(CHIPS)':
 'VOS': CDS_PINID='VOS';
NODE_NAME     PR200 1
 '@T6G_MB_LIB.T6G(SCH_1):PAGE187_I17@PURE_QUANTA.Q_RES(CHIPS)':
 'A': CDS_PINID='A';
NET_NAME
'PVDDCR_CPU0_P1_VOS5'
 '@T6G_MB_LIB.T6G(SCH_1):PVDDCR_CPU0_P1_VOS5':
 C_SIGNAL='@t6g_mb_lib.t6g(sch_1):pvddcr_cpu0_p1_vos5';
NODE_NAME     PU29 1
 '@T6G_MB_LIB.T6G(SCH_1):PAGE188_I18@PURE_QUANTA.ISL99390FRZTR5935(CHIPS)':
 'VOS': CDS_PINID='VOS';
NODE_NAME     PR204 1
 '@T6G_MB_LIB.T6G(SCH_1):PAGE188_I33@PURE_QUANTA.Q_RES(CHIPS)':
 'A': CDS_PINID='A';
NET_NAME
'PVDDCR_CPU0_P1_VOS6'
 '@T6G_MB_LIB.T6G(SCH_1):PVDDCR_CPU0_P1_VOS6':
 C_SIGNAL='@t6g_mb_lib.t6g(sch_1):pvddcr_cpu0_p1_vos6';
NODE_NAME     PR425 1
 '@T6G_MB_LIB.T6G(SCH_1):PAGE188_I22@PURE_QUANTA.Q_RES(CHIPS)':
 'A': CDS_PINID='A';
NODE_NAME     PU24 1
 '@T6G_MB_LIB.T6G(SCH_1):PAGE188_I73@PURE_QUANTA.ISL99390FRZTR5935(CHIPS)':
 'VOS': CDS_PINID='VOS';
NET_NAME
'PVDDCR_CPU1_P0'
 '@T6G_MB_LIB.T6G(SCH_1):PVDDCR_CPU1_P0':
 C_SIGNAL='@t6g_mb_lib.t6g(sch_1):pvddcr_cpu1_p0',
 CDS_GLOBAL_NET='TRUE';
NODE_NAME     U25 BN27
 '@T6G_MB_LIB.T6G(SCH_1):PAGE30_I45@PURE_QUANTA.GENOA_SP5(CHIPS)':
 'VDDCR_CPU1_BN27': CDS_PINID='VDDCR_CPU1_BN27';
NODE_NAME     U25 BN31
 '@T6G_MB_LIB.T6G(SCH_1):PAGE30_I45@PURE_QUANTA.GENOA_SP5(CHIPS)':
 'VDDCR_CPU1_BN31': CDS_PINID='VDDCR_CPU1_BN31';
NODE_NAME     U25 BN35
 '@T6G_MB_LIB.T6G(SCH_1):PAGE30_I45@PURE_QUANTA.GENOA_SP5(CHIPS)':
 'VDDCR_CPU1_BN35': CDS_PINID='VDDCR_CPU1_BN35';
NODE_NAME     U25 BN42
 '@T6G_MB_LIB.T6G(SCH_1):PAGE30_I45@PURE_QUANTA.GENOA_SP5(CHIPS)':
 'VDDCR_CPU1_BN42': CDS_PINID='VDDCR_CPU1_BN42';
NODE_NAME     U25 BN46
 '@T6G_MB_LIB.T6G(SCH_1):PAGE30_I45@PURE_QUANTA.GENOA_SP5(CHIPS)':
 'VDDCR_CPU1_BN46': CDS_PINID='VDDCR_CPU1_BN46';
NODE_NAME     U25 BN50
 '@T6G_MB_LIB.T6G(SCH_1):PAGE30_I45@PURE_QUANTA.GENOA_SP5(CHIPS)':
 'VDDCR_CPU1_BN50': CDS_PINID='VDDCR_CPU1_BN50';
NODE_NAME     U25 BP24
 '@T6G_MB_LIB.T6G(SCH_1):PAGE30_I45@PURE_QUANTA.GENOA_SP5(CHIPS)':
 'VDDCR_CPU1_BP24': CDS_PINID='VDDCR_CPU1_BP24';
NODE_NAME     U25 BP26
 '@T6G_MB_LIB.T6G(SCH_1):PAGE30_I45@PURE_QUANTA.GENOA_SP5(CHIPS)':
 'VDDCR_CPU1_BP26': CDS_PINID='VDDCR_CPU1_BP26';
NODE_NAME     U25 BP28
 '@T6G_MB_LIB.T6G(SCH_1):PAGE30_I45@PURE_QUANTA.GENOA_SP5(CHIPS)':
 'VDDCR_CPU1_BP28': CDS_PINID='VDDCR_CPU1_BP28';
NODE_NAME     U25 BP30
 '@T6G_MB_LIB.T6G(SCH_1):PAGE30_I45@PURE_QUANTA.GENOA_SP5(CHIPS)':
 'VDDCR_CPU1_BP30': CDS_PINID='VDDCR_CPU1_BP30';
NODE_NAME     U25 BP32
 '@T6G_MB_LIB.T6G(SCH_1):PAGE30_I45@PURE_QUANTA.GENOA_SP5(CHIPS)':
 'VDDCR_CPU1_BP32': CDS_PINID='VDDCR_CPU1_BP32';
NODE_NAME     U25 BP34
 '@T6G_MB_LIB.T6G(SCH_1):PAGE30_I45@PURE_QUANTA.GENOA_SP5(CHIPS)':
 'VDDCR_CPU1_BP34': CDS_PINID='VDDCR_CPU1_BP34';
NODE_NAME     U25 BP36
 '@T6G_MB_LIB.T6G(SCH_1):PAGE30_I45@PURE_QUANTA.GENOA_SP5(CHIPS)':
 'VDDCR_CPU1_BP36': CDS_PINID='VDDCR_CPU1_BP36';
NODE_NAME     U25 BP39
 '@T6G_MB_LIB.T6G(SCH_1):PAGE30_I45@PURE_QUANTA.GENOA_SP5(CHIPS)':
 'VDDCR_CPU1_BP39': CDS_PINID='VDDCR_CPU1_BP39';
NODE_NAME     U25 BP41
 '@T6G_MB_LIB.T6G(SCH_1):PAGE30_I45@PURE_QUANTA.GENOA_SP5(CHIPS)':
 'VDDCR_CPU1_BP41': CDS_PINID='VDDCR_CPU1_BP41';
NODE_NAME     U25 BP43
 '@T6G_MB_LIB.T6G(SCH_1):PAGE30_I45@PURE_QUANTA.GENOA_SP5(CHIPS)':
 'VDDCR_CPU1_BP43': CDS_PINID='VDDCR_CPU1_BP43';
NODE_NAME     U25 BP45
 '@T6G_MB_LIB.T6G(SCH_1):PAGE30_I45@PURE_QUANTA.GENOA_SP5(CHIPS)':
 'VDDCR_CPU1_BP45': CDS_PINID='VDDCR_CPU1_BP45';
NODE_NAME     U25 BP47
 '@T6G_MB_LIB.T6G(SCH_1):PAGE30_I45@PURE_QUANTA.GENOA_SP5(CHIPS)':
 'VDDCR_CPU1_BP47': CDS_PINID='VDDCR_CPU1_BP47';
NODE_NAME     U25 BP49
 '@T6G_MB_LIB.T6G(SCH_1):PAGE30_I45@PURE_QUANTA.GENOA_SP5(CHIPS)':
 'VDDCR_CPU1_BP49': CDS_PINID='VDDCR_CPU1_BP49';
NODE_NAME     U25 BR23
 '@T6G_MB_LIB.T6G(SCH_1):PAGE30_I45@PURE_QUANTA.GENOA_SP5(CHIPS)':
 'VDDCR_CPU1_BR23': CDS_PINID='VDDCR_CPU1_BR23';
NODE_NAME     U25 BR25
 '@T6G_MB_LIB.T6G(SCH_1):PAGE30_I45@PURE_QUANTA.GENOA_SP5(CHIPS)':
 'VDDCR_CPU1_BR25': CDS_PINID='VDDCR_CPU1_BR25';
NODE_NAME     U25 BR27
 '@T6G_MB_LIB.T6G(SCH_1):PAGE30_I45@PURE_QUANTA.GENOA_SP5(CHIPS)':
 'VDDCR_CPU1_BR27': CDS_PINID='VDDCR_CPU1_BR27';
NODE_NAME     U25 BR29
 '@T6G_MB_LIB.T6G(SCH_1):PAGE30_I45@PURE_QUANTA.GENOA_SP5(CHIPS)':
 'VDDCR_CPU1_BR29': CDS_PINID='VDDCR_CPU1_BR29';
NODE_NAME     U25 BR31
 '@T6G_MB_LIB.T6G(SCH_1):PAGE30_I45@PURE_QUANTA.GENOA_SP5(CHIPS)':
 'VDDCR_CPU1_BR31': CDS_PINID='VDDCR_CPU1_BR31';
NODE_NAME     U25 BR33
 '@T6G_MB_LIB.T6G(SCH_1):PAGE30_I45@PURE_QUANTA.GENOA_SP5(CHIPS)':
 'VDDCR_CPU1_BR33': CDS_PINID='VDDCR_CPU1_BR33';
NODE_NAME     U25 BR35
 '@T6G_MB_LIB.T6G(SCH_1):PAGE30_I45@PURE_QUANTA.GENOA_SP5(CHIPS)':
 'VDDCR_CPU1_BR35': CDS_PINID='VDDCR_CPU1_BR35';
NODE_NAME     U25 BR40
 '@T6G_MB_LIB.T6G(SCH_1):PAGE30_I45@PURE_QUANTA.GENOA_SP5(CHIPS)':
 'VDDCR_CPU1_BR40': CDS_PINID='VDDCR_CPU1_BR40';
NODE_NAME     U25 BR42
 '@T6G_MB_LIB.T6G(SCH_1):PAGE30_I45@PURE_QUANTA.GENOA_SP5(CHIPS)':
 'VDDCR_CPU1_BR42': CDS_PINID='VDDCR_CPU1_BR42';
NODE_NAME     U25 BR44
 '@T6G_MB_LIB.T6G(SCH_1):PAGE30_I45@PURE_QUANTA.GENOA_SP5(CHIPS)':
 'VDDCR_CPU1_BR44': CDS_PINID='VDDCR_CPU1_BR44';
NODE_NAME     U25 BR46
 '@T6G_MB_LIB.T6G(SCH_1):PAGE30_I45@PURE_QUANTA.GENOA_SP5(CHIPS)':
 'VDDCR_CPU1_BR46': CDS_PINID='VDDCR_CPU1_BR46';
NODE_NAME     U25 BR48
 '@T6G_MB_LIB.T6G(SCH_1):PAGE30_I45@PURE_QUANTA.GENOA_SP5(CHIPS)':
 'VDDCR_CPU1_BR48': CDS_PINID='VDDCR_CPU1_BR48';
NODE_NAME     U25 BR50
 '@T6G_MB_LIB.T6G(SCH_1):PAGE30_I45@PURE_QUANTA.GENOA_SP5(CHIPS)':
 'VDDCR_CPU1_BR50': CDS_PINID='VDDCR_CPU1_BR50';
NODE_NAME     U25 BR52
 '@T6G_MB_LIB.T6G(SCH_1):PAGE30_I45@PURE_QUANTA.GENOA_SP5(CHIPS)':
 'VDDCR_CPU1_BR52': CDS_PINID='VDDCR_CPU1_BR52';
NODE_NAME     U25 BT23
 '@T6G_MB_LIB.T6G(SCH_1):PAGE30_I45@PURE_QUANTA.GENOA_SP5(CHIPS)':
 'VDDCR_CPU1_BT23': CDS_PINID='VDDCR_CPU1_BT23';
NODE_NAME     U25 BT24
 '@T6G_MB_LIB.T6G(SCH_1):PAGE30_I45@PURE_QUANTA.GENOA_SP5(CHIPS)':
 'VDDCR_CPU1_BT24': CDS_PINID='VDDCR_CPU1_BT24';
NODE_NAME     U25 BT26
 '@T6G_MB_LIB.T6G(SCH_1):PAGE30_I45@PURE_QUANTA.GENOA_SP5(CHIPS)':
 'VDDCR_CPU1_BT26': CDS_PINID='VDDCR_CPU1_BT26';
NODE_NAME     U25 BT27
 '@T6G_MB_LIB.T6G(SCH_1):PAGE30_I45@PURE_QUANTA.GENOA_SP5(CHIPS)':
 'VDDCR_CPU1_BT27': CDS_PINID='VDDCR_CPU1_BT27';
NODE_NAME     U25 BT29
 '@T6G_MB_LIB.T6G(SCH_1):PAGE30_I45@PURE_QUANTA.GENOA_SP5(CHIPS)':
 'VDDCR_CPU1_BT29': CDS_PINID='VDDCR_CPU1_BT29';
NODE_NAME     U25 BT30
 '@T6G_MB_LIB.T6G(SCH_1):PAGE30_I45@PURE_QUANTA.GENOA_SP5(CHIPS)':
 'VDDCR_CPU1_BT30': CDS_PINID='VDDCR_CPU1_BT30';
NODE_NAME     U25 BT32
 '@T6G_MB_LIB.T6G(SCH_1):PAGE30_I45@PURE_QUANTA.GENOA_SP5(CHIPS)':
 'VDDCR_CPU1_BT32': CDS_PINID='VDDCR_CPU1_BT32';
NODE_NAME     U25 BT33
 '@T6G_MB_LIB.T6G(SCH_1):PAGE30_I45@PURE_QUANTA.GENOA_SP5(CHIPS)':
 'VDDCR_CPU1_BT33': CDS_PINID='VDDCR_CPU1_BT33';
NODE_NAME     U25 BT43
 '@T6G_MB_LIB.T6G(SCH_1):PAGE30_I45@PURE_QUANTA.GENOA_SP5(CHIPS)':
 'VDDCR_CPU1_BT43': CDS_PINID='VDDCR_CPU1_BT43';
NODE_NAME     U25 BT44
 '@T6G_MB_LIB.T6G(SCH_1):PAGE30_I45@PURE_QUANTA.GENOA_SP5(CHIPS)':
 'VDDCR_CPU1_BT44': CDS_PINID='VDDCR_CPU1_BT44';
NODE_NAME     U25 BT46
 '@T6G_MB_LIB.T6G(SCH_1):PAGE30_I45@PURE_QUANTA.GENOA_SP5(CHIPS)':
 'VDDCR_CPU1_BT46': CDS_PINID='VDDCR_CPU1_BT46';
NODE_NAME     U25 BT47
 '@T6G_MB_LIB.T6G(SCH_1):PAGE30_I45@PURE_QUANTA.GENOA_SP5(CHIPS)':
 'VDDCR_CPU1_BT47': CDS_PINID='VDDCR_CPU1_BT47';
NODE_NAME     U25 BT49
 '@T6G_MB_LIB.T6G(SCH_1):PAGE30_I45@PURE_QUANTA.GENOA_SP5(CHIPS)':
 'VDDCR_CPU1_BT49': CDS_PINID='VDDCR_CPU1_BT49';
NODE_NAME     U25 BT50
 '@T6G_MB_LIB.T6G(SCH_1):PAGE30_I45@PURE_QUANTA.GENOA_SP5(CHIPS)':
 'VDDCR_CPU1_BT50': CDS_PINID='VDDCR_CPU1_BT50';
NODE_NAME     U25 BT52
 '@T6G_MB_LIB.T6G(SCH_1):PAGE30_I45@PURE_QUANTA.GENOA_SP5(CHIPS)':
 'VDDCR_CPU1_BT52': CDS_PINID='VDDCR_CPU1_BT52';
NODE_NAME     U25 BT53
 '@T6G_MB_LIB.T6G(SCH_1):PAGE30_I45@PURE_QUANTA.GENOA_SP5(CHIPS)':
 'VDDCR_CPU1_BT53': CDS_PINID='VDDCR_CPU1_BT53';
NODE_NAME     U25 BW35
 '@T6G_MB_LIB.T6G(SCH_1):PAGE30_I45@PURE_QUANTA.GENOA_SP5(CHIPS)':
 'VDDCR_CPU1_BW35': CDS_PINID='VDDCR_CPU1_BW35';
NODE_NAME     U25 BW36
 '@T6G_MB_LIB.T6G(SCH_1):PAGE30_I45@PURE_QUANTA.GENOA_SP5(CHIPS)':
 'VDDCR_CPU1_BW36': CDS_PINID='VDDCR_CPU1_BW36';
NODE_NAME     U25 BW40
 '@T6G_MB_LIB.T6G(SCH_1):PAGE30_I45@PURE_QUANTA.GENOA_SP5(CHIPS)':
 'VDDCR_CPU1_BW40': CDS_PINID='VDDCR_CPU1_BW40';
NODE_NAME     U25 BW41
 '@T6G_MB_LIB.T6G(SCH_1):PAGE30_I45@PURE_QUANTA.GENOA_SP5(CHIPS)':
 'VDDCR_CPU1_BW41': CDS_PINID='VDDCR_CPU1_BW41';
NODE_NAME     U25 BY23
 '@T6G_MB_LIB.T6G(SCH_1):PAGE30_I45@PURE_QUANTA.GENOA_SP5(CHIPS)':
 'VDDCR_CPU1_BY23': CDS_PINID='VDDCR_CPU1_BY23';
NODE_NAME     U25 BY24
 '@T6G_MB_LIB.T6G(SCH_1):PAGE30_I45@PURE_QUANTA.GENOA_SP5(CHIPS)':
 'VDDCR_CPU1_BY24': CDS_PINID='VDDCR_CPU1_BY24';
NODE_NAME     U25 BY26
 '@T6G_MB_LIB.T6G(SCH_1):PAGE30_I45@PURE_QUANTA.GENOA_SP5(CHIPS)':
 'VDDCR_CPU1_BY26': CDS_PINID='VDDCR_CPU1_BY26';
NODE_NAME     U25 BY27
 '@T6G_MB_LIB.T6G(SCH_1):PAGE30_I45@PURE_QUANTA.GENOA_SP5(CHIPS)':
 'VDDCR_CPU1_BY27': CDS_PINID='VDDCR_CPU1_BY27';
NODE_NAME     U25 BY29
 '@T6G_MB_LIB.T6G(SCH_1):PAGE30_I45@PURE_QUANTA.GENOA_SP5(CHIPS)':
 'VDDCR_CPU1_BY29': CDS_PINID='VDDCR_CPU1_BY29';
NODE_NAME     U25 BY30
 '@T6G_MB_LIB.T6G(SCH_1):PAGE30_I45@PURE_QUANTA.GENOA_SP5(CHIPS)':
 'VDDCR_CPU1_BY30': CDS_PINID='VDDCR_CPU1_BY30';
NODE_NAME     U25 BY32
 '@T6G_MB_LIB.T6G(SCH_1):PAGE30_I45@PURE_QUANTA.GENOA_SP5(CHIPS)':
 'VDDCR_CPU1_BY32': CDS_PINID='VDDCR_CPU1_BY32';
NODE_NAME     U25 BY33
 '@T6G_MB_LIB.T6G(SCH_1):PAGE30_I45@PURE_QUANTA.GENOA_SP5(CHIPS)':
 'VDDCR_CPU1_BY33': CDS_PINID='VDDCR_CPU1_BY33';
NODE_NAME     U25 BY43
 '@T6G_MB_LIB.T6G(SCH_1):PAGE30_I45@PURE_QUANTA.GENOA_SP5(CHIPS)':
 'VDDCR_CPU1_BY43': CDS_PINID='VDDCR_CPU1_BY43';
NODE_NAME     U25 BY44
 '@T6G_MB_LIB.T6G(SCH_1):PAGE30_I45@PURE_QUANTA.GENOA_SP5(CHIPS)':
 'VDDCR_CPU1_BY44': CDS_PINID='VDDCR_CPU1_BY44';
NODE_NAME     U25 BY46
 '@T6G_MB_LIB.T6G(SCH_1):PAGE30_I45@PURE_QUANTA.GENOA_SP5(CHIPS)':
 'VDDCR_CPU1_BY46': CDS_PINID='VDDCR_CPU1_BY46';
NODE_NAME     U25 BY47
 '@T6G_MB_LIB.T6G(SCH_1):PAGE30_I45@PURE_QUANTA.GENOA_SP5(CHIPS)':
 'VDDCR_CPU1_BY47': CDS_PINID='VDDCR_CPU1_BY47';
NODE_NAME     U25 BY49
 '@T6G_MB_LIB.T6G(SCH_1):PAGE30_I45@PURE_QUANTA.GENOA_SP5(CHIPS)':
 'VDDCR_CPU1_BY49': CDS_PINID='VDDCR_CPU1_BY49';
NODE_NAME     U25 BY50
 '@T6G_MB_LIB.T6G(SCH_1):PAGE30_I45@PURE_QUANTA.GENOA_SP5(CHIPS)':
 'VDDCR_CPU1_BY50': CDS_PINID='VDDCR_CPU1_BY50';
NODE_NAME     U25 BY52
 '@T6G_MB_LIB.T6G(SCH_1):PAGE30_I45@PURE_QUANTA.GENOA_SP5(CHIPS)':
 'VDDCR_CPU1_BY52': CDS_PINID='VDDCR_CPU1_BY52';
NODE_NAME     U25 BY53
 '@T6G_MB_LIB.T6G(SCH_1):PAGE30_I45@PURE_QUANTA.GENOA_SP5(CHIPS)':
 'VDDCR_CPU1_BY53': CDS_PINID='VDDCR_CPU1_BY53';
NODE_NAME     U25 CC35
 '@T6G_MB_LIB.T6G(SCH_1):PAGE30_I45@PURE_QUANTA.GENOA_SP5(CHIPS)':
 'VDDCR_CPU1_CC35': CDS_PINID='VDDCR_CPU1_CC35';
NODE_NAME     U25 CC36
 '@T6G_MB_LIB.T6G(SCH_1):PAGE30_I45@PURE_QUANTA.GENOA_SP5(CHIPS)':
 'VDDCR_CPU1_CC36': CDS_PINID='VDDCR_CPU1_CC36';
NODE_NAME     U25 CC40
 '@T6G_MB_LIB.T6G(SCH_1):PAGE30_I45@PURE_QUANTA.GENOA_SP5(CHIPS)':
 'VDDCR_CPU1_CC40': CDS_PINID='VDDCR_CPU1_CC40';
NODE_NAME     U25 CC41
 '@T6G_MB_LIB.T6G(SCH_1):PAGE30_I45@PURE_QUANTA.GENOA_SP5(CHIPS)':
 'VDDCR_CPU1_CC41': CDS_PINID='VDDCR_CPU1_CC41';
NODE_NAME     U25 CD23
 '@T6G_MB_LIB.T6G(SCH_1):PAGE30_I45@PURE_QUANTA.GENOA_SP5(CHIPS)':
 'VDDCR_CPU1_CD23': CDS_PINID='VDDCR_CPU1_CD23';
NODE_NAME     U25 CD24
 '@T6G_MB_LIB.T6G(SCH_1):PAGE30_I45@PURE_QUANTA.GENOA_SP5(CHIPS)':
 'VDDCR_CPU1_CD24': CDS_PINID='VDDCR_CPU1_CD24';
NODE_NAME     U25 CD26
 '@T6G_MB_LIB.T6G(SCH_1):PAGE30_I45@PURE_QUANTA.GENOA_SP5(CHIPS)':
 'VDDCR_CPU1_CD26': CDS_PINID='VDDCR_CPU1_CD26';
NODE_NAME     U25 CD27
 '@T6G_MB_LIB.T6G(SCH_1):PAGE30_I45@PURE_QUANTA.GENOA_SP5(CHIPS)':
 'VDDCR_CPU1_CD27': CDS_PINID='VDDCR_CPU1_CD27';
NODE_NAME     U25 CD29
 '@T6G_MB_LIB.T6G(SCH_1):PAGE30_I45@PURE_QUANTA.GENOA_SP5(CHIPS)':
 'VDDCR_CPU1_CD29': CDS_PINID='VDDCR_CPU1_CD29';
NODE_NAME     U25 CD30
 '@T6G_MB_LIB.T6G(SCH_1):PAGE30_I45@PURE_QUANTA.GENOA_SP5(CHIPS)':
 'VDDCR_CPU1_CD30': CDS_PINID='VDDCR_CPU1_CD30';
NODE_NAME     U25 CD32
 '@T6G_MB_LIB.T6G(SCH_1):PAGE30_I45@PURE_QUANTA.GENOA_SP5(CHIPS)':
 'VDDCR_CPU1_CD32': CDS_PINID='VDDCR_CPU1_CD32';
NODE_NAME     U25 CD33
 '@T6G_MB_LIB.T6G(SCH_1):PAGE30_I45@PURE_QUANTA.GENOA_SP5(CHIPS)':
 'VDDCR_CPU1_CD33': CDS_PINID='VDDCR_CPU1_CD33';
NODE_NAME     U25 CD43
 '@T6G_MB_LIB.T6G(SCH_1):PAGE30_I45@PURE_QUANTA.GENOA_SP5(CHIPS)':
 'VDDCR_CPU1_CD43': CDS_PINID='VDDCR_CPU1_CD43';
NODE_NAME     U25 CD44
 '@T6G_MB_LIB.T6G(SCH_1):PAGE30_I45@PURE_QUANTA.GENOA_SP5(CHIPS)':
 'VDDCR_CPU1_CD44': CDS_PINID='VDDCR_CPU1_CD44';
NODE_NAME     U25 CD46
 '@T6G_MB_LIB.T6G(SCH_1):PAGE30_I45@PURE_QUANTA.GENOA_SP5(CHIPS)':
 'VDDCR_CPU1_CD46': CDS_PINID='VDDCR_CPU1_CD46';
NODE_NAME     U25 CD47
 '@T6G_MB_LIB.T6G(SCH_1):PAGE30_I45@PURE_QUANTA.GENOA_SP5(CHIPS)':
 'VDDCR_CPU1_CD47': CDS_PINID='VDDCR_CPU1_CD47';
NODE_NAME     U25 CD49
 '@T6G_MB_LIB.T6G(SCH_1):PAGE30_I45@PURE_QUANTA.GENOA_SP5(CHIPS)':
 'VDDCR_CPU1_CD49': CDS_PINID='VDDCR_CPU1_CD49';
NODE_NAME     U25 CD50
 '@T6G_MB_LIB.T6G(SCH_1):PAGE30_I45@PURE_QUANTA.GENOA_SP5(CHIPS)':
 'VDDCR_CPU1_CD50': CDS_PINID='VDDCR_CPU1_CD50';
NODE_NAME     U25 CD52
 '@T6G_MB_LIB.T6G(SCH_1):PAGE30_I45@PURE_QUANTA.GENOA_SP5(CHIPS)':
 'VDDCR_CPU1_CD52': CDS_PINID='VDDCR_CPU1_CD52';
NODE_NAME     U25 CD53
 '@T6G_MB_LIB.T6G(SCH_1):PAGE30_I45@PURE_QUANTA.GENOA_SP5(CHIPS)':
 'VDDCR_CPU1_CD53': CDS_PINID='VDDCR_CPU1_CD53';
NODE_NAME     U25 CG35
 '@T6G_MB_LIB.T6G(SCH_1):PAGE30_I45@PURE_QUANTA.GENOA_SP5(CHIPS)':
 'VDDCR_CPU1_CG35': CDS_PINID='VDDCR_CPU1_CG35';
NODE_NAME     U25 CG36
 '@T6G_MB_LIB.T6G(SCH_1):PAGE30_I45@PURE_QUANTA.GENOA_SP5(CHIPS)':
 'VDDCR_CPU1_CG36': CDS_PINID='VDDCR_CPU1_CG36';
NODE_NAME     U25 CG40
 '@T6G_MB_LIB.T6G(SCH_1):PAGE30_I45@PURE_QUANTA.GENOA_SP5(CHIPS)':
 'VDDCR_CPU1_CG40': CDS_PINID='VDDCR_CPU1_CG40';
NODE_NAME     U25 CG41
 '@T6G_MB_LIB.T6G(SCH_1):PAGE30_I45@PURE_QUANTA.GENOA_SP5(CHIPS)':
 'VDDCR_CPU1_CG41': CDS_PINID='VDDCR_CPU1_CG41';
NODE_NAME     U25 CH23
 '@T6G_MB_LIB.T6G(SCH_1):PAGE30_I45@PURE_QUANTA.GENOA_SP5(CHIPS)':
 'VDDCR_CPU1_CH23': CDS_PINID='VDDCR_CPU1_CH23';
NODE_NAME     U25 CH24
 '@T6G_MB_LIB.T6G(SCH_1):PAGE30_I45@PURE_QUANTA.GENOA_SP5(CHIPS)':
 'VDDCR_CPU1_CH24': CDS_PINID='VDDCR_CPU1_CH24';
NODE_NAME     U25 CH26
 '@T6G_MB_LIB.T6G(SCH_1):PAGE30_I45@PURE_QUANTA.GENOA_SP5(CHIPS)':
 'VDDCR_CPU1_CH26': CDS_PINID='VDDCR_CPU1_CH26';
NODE_NAME     U25 CH27
 '@T6G_MB_LIB.T6G(SCH_1):PAGE30_I45@PURE_QUANTA.GENOA_SP5(CHIPS)':
 'VDDCR_CPU1_CH27': CDS_PINID='VDDCR_CPU1_CH27';
NODE_NAME     U25 CH29
 '@T6G_MB_LIB.T6G(SCH_1):PAGE30_I45@PURE_QUANTA.GENOA_SP5(CHIPS)':
 'VDDCR_CPU1_CH29': CDS_PINID='VDDCR_CPU1_CH29';
NODE_NAME     U25 CH30
 '@T6G_MB_LIB.T6G(SCH_1):PAGE30_I45@PURE_QUANTA.GENOA_SP5(CHIPS)':
 'VDDCR_CPU1_CH30': CDS_PINID='VDDCR_CPU1_CH30';
NODE_NAME     U25 CH32
 '@T6G_MB_LIB.T6G(SCH_1):PAGE30_I45@PURE_QUANTA.GENOA_SP5(CHIPS)':
 'VDDCR_CPU1_CH32': CDS_PINID='VDDCR_CPU1_CH32';
NODE_NAME     U25 CH33
 '@T6G_MB_LIB.T6G(SCH_1):PAGE30_I45@PURE_QUANTA.GENOA_SP5(CHIPS)':
 'VDDCR_CPU1_CH33': CDS_PINID='VDDCR_CPU1_CH33';
NODE_NAME     U25 CH43
 '@T6G_MB_LIB.T6G(SCH_1):PAGE30_I45@PURE_QUANTA.GENOA_SP5(CHIPS)':
 'VDDCR_CPU1_CH43': CDS_PINID='VDDCR_CPU1_CH43';
NODE_NAME     U25 CH44
 '@T6G_MB_LIB.T6G(SCH_1):PAGE30_I45@PURE_QUANTA.GENOA_SP5(CHIPS)':
 'VDDCR_CPU1_CH44': CDS_PINID='VDDCR_CPU1_CH44';
NODE_NAME     U25 CH46
 '@T6G_MB_LIB.T6G(SCH_1):PAGE30_I45@PURE_QUANTA.GENOA_SP5(CHIPS)':
 'VDDCR_CPU1_CH46': CDS_PINID='VDDCR_CPU1_CH46';
NODE_NAME     U25 CH47
 '@T6G_MB_LIB.T6G(SCH_1):PAGE30_I45@PURE_QUANTA.GENOA_SP5(CHIPS)':
 'VDDCR_CPU1_CH47': CDS_PINID='VDDCR_CPU1_CH47';
NODE_NAME     U25 CH49
 '@T6G_MB_LIB.T6G(SCH_1):PAGE30_I45@PURE_QUANTA.GENOA_SP5(CHIPS)':
 'VDDCR_CPU1_CH49': CDS_PINID='VDDCR_CPU1_CH49';
NODE_NAME     U25 CH50
 '@T6G_MB_LIB.T6G(SCH_1):PAGE30_I45@PURE_QUANTA.GENOA_SP5(CHIPS)':
 'VDDCR_CPU1_CH50': CDS_PINID='VDDCR_CPU1_CH50';
NODE_NAME     U25 CH52
 '@T6G_MB_LIB.T6G(SCH_1):PAGE30_I45@PURE_QUANTA.GENOA_SP5(CHIPS)':
 'VDDCR_CPU1_CH52': CDS_PINID='VDDCR_CPU1_CH52';
NODE_NAME     U25 CH53
 '@T6G_MB_LIB.T6G(SCH_1):PAGE30_I45@PURE_QUANTA.GENOA_SP5(CHIPS)':
 'VDDCR_CPU1_CH53': CDS_PINID='VDDCR_CPU1_CH53';
NODE_NAME     U25 CK35
 '@T6G_MB_LIB.T6G(SCH_1):PAGE30_I45@PURE_QUANTA.GENOA_SP5(CHIPS)':
 'VDDCR_CPU1_CK35': CDS_PINID='VDDCR_CPU1_CK35';
NODE_NAME     U25 CK36
 '@T6G_MB_LIB.T6G(SCH_1):PAGE30_I45@PURE_QUANTA.GENOA_SP5(CHIPS)':
 'VDDCR_CPU1_CK36': CDS_PINID='VDDCR_CPU1_CK36';
NODE_NAME     U25 CK40
 '@T6G_MB_LIB.T6G(SCH_1):PAGE30_I45@PURE_QUANTA.GENOA_SP5(CHIPS)':
 'VDDCR_CPU1_CK40': CDS_PINID='VDDCR_CPU1_CK40';
NODE_NAME     U25 CK41
 '@T6G_MB_LIB.T6G(SCH_1):PAGE30_I45@PURE_QUANTA.GENOA_SP5(CHIPS)':
 'VDDCR_CPU1_CK41': CDS_PINID='VDDCR_CPU1_CK41';
NODE_NAME     U25 CL29
 '@T6G_MB_LIB.T6G(SCH_1):PAGE30_I45@PURE_QUANTA.GENOA_SP5(CHIPS)':
 'VDDCR_CPU1_CL29': CDS_PINID='VDDCR_CPU1_CL29';
NODE_NAME     U25 CL30
 '@T6G_MB_LIB.T6G(SCH_1):PAGE30_I45@PURE_QUANTA.GENOA_SP5(CHIPS)':
 'VDDCR_CPU1_CL30': CDS_PINID='VDDCR_CPU1_CL30';
NODE_NAME     U25 CL32
 '@T6G_MB_LIB.T6G(SCH_1):PAGE30_I45@PURE_QUANTA.GENOA_SP5(CHIPS)':
 'VDDCR_CPU1_CL32': CDS_PINID='VDDCR_CPU1_CL32';
NODE_NAME     U25 CL33
 '@T6G_MB_LIB.T6G(SCH_1):PAGE30_I45@PURE_QUANTA.GENOA_SP5(CHIPS)':
 'VDDCR_CPU1_CL33': CDS_PINID='VDDCR_CPU1_CL33';
NODE_NAME     U25 CL43
 '@T6G_MB_LIB.T6G(SCH_1):PAGE30_I45@PURE_QUANTA.GENOA_SP5(CHIPS)':
 'VDDCR_CPU1_CL43': CDS_PINID='VDDCR_CPU1_CL43';
NODE_NAME     U25 CL44
 '@T6G_MB_LIB.T6G(SCH_1):PAGE30_I45@PURE_QUANTA.GENOA_SP5(CHIPS)':
 'VDDCR_CPU1_CL44': CDS_PINID='VDDCR_CPU1_CL44';
NODE_NAME     U25 CL46
 '@T6G_MB_LIB.T6G(SCH_1):PAGE30_I45@PURE_QUANTA.GENOA_SP5(CHIPS)':
 'VDDCR_CPU1_CL46': CDS_PINID='VDDCR_CPU1_CL46';
NODE_NAME     U25 CL47
 '@T6G_MB_LIB.T6G(SCH_1):PAGE30_I45@PURE_QUANTA.GENOA_SP5(CHIPS)':
 'VDDCR_CPU1_CL47': CDS_PINID='VDDCR_CPU1_CL47';
NODE_NAME     U25 CN35
 '@T6G_MB_LIB.T6G(SCH_1):PAGE30_I45@PURE_QUANTA.GENOA_SP5(CHIPS)':
 'VDDCR_CPU1_CN35': CDS_PINID='VDDCR_CPU1_CN35';
NODE_NAME     U25 CN36
 '@T6G_MB_LIB.T6G(SCH_1):PAGE30_I45@PURE_QUANTA.GENOA_SP5(CHIPS)':
 'VDDCR_CPU1_CN36': CDS_PINID='VDDCR_CPU1_CN36';
NODE_NAME     U25 CN40
 '@T6G_MB_LIB.T6G(SCH_1):PAGE30_I45@PURE_QUANTA.GENOA_SP5(CHIPS)':
 'VDDCR_CPU1_CN40': CDS_PINID='VDDCR_CPU1_CN40';
NODE_NAME     U25 CN41
 '@T6G_MB_LIB.T6G(SCH_1):PAGE30_I45@PURE_QUANTA.GENOA_SP5(CHIPS)':
 'VDDCR_CPU1_CN41': CDS_PINID='VDDCR_CPU1_CN41';
NODE_NAME     U25 CP23
 '@T6G_MB_LIB.T6G(SCH_1):PAGE30_I45@PURE_QUANTA.GENOA_SP5(CHIPS)':
 'VDDCR_CPU1_CP23': CDS_PINID='VDDCR_CPU1_CP23';
NODE_NAME     U25 CP24
 '@T6G_MB_LIB.T6G(SCH_1):PAGE30_I45@PURE_QUANTA.GENOA_SP5(CHIPS)':
 'VDDCR_CPU1_CP24': CDS_PINID='VDDCR_CPU1_CP24';
NODE_NAME     U25 CP26
 '@T6G_MB_LIB.T6G(SCH_1):PAGE30_I45@PURE_QUANTA.GENOA_SP5(CHIPS)':
 'VDDCR_CPU1_CP26': CDS_PINID='VDDCR_CPU1_CP26';
NODE_NAME     U25 CP27
 '@T6G_MB_LIB.T6G(SCH_1):PAGE30_I45@PURE_QUANTA.GENOA_SP5(CHIPS)':
 'VDDCR_CPU1_CP27': CDS_PINID='VDDCR_CPU1_CP27';
NODE_NAME     U25 CP29
 '@T6G_MB_LIB.T6G(SCH_1):PAGE30_I45@PURE_QUANTA.GENOA_SP5(CHIPS)':
 'VDDCR_CPU1_CP29': CDS_PINID='VDDCR_CPU1_CP29';
NODE_NAME     U25 CP30
 '@T6G_MB_LIB.T6G(SCH_1):PAGE30_I45@PURE_QUANTA.GENOA_SP5(CHIPS)':
 'VDDCR_CPU1_CP30': CDS_PINID='VDDCR_CPU1_CP30';
NODE_NAME     U25 CP32
 '@T6G_MB_LIB.T6G(SCH_1):PAGE30_I45@PURE_QUANTA.GENOA_SP5(CHIPS)':
 'VDDCR_CPU1_CP32': CDS_PINID='VDDCR_CPU1_CP32';
NODE_NAME     U25 CP33
 '@T6G_MB_LIB.T6G(SCH_1):PAGE30_I45@PURE_QUANTA.GENOA_SP5(CHIPS)':
 'VDDCR_CPU1_CP33': CDS_PINID='VDDCR_CPU1_CP33';
NODE_NAME     U25 CP43
 '@T6G_MB_LIB.T6G(SCH_1):PAGE30_I45@PURE_QUANTA.GENOA_SP5(CHIPS)':
 'VDDCR_CPU1_CP43': CDS_PINID='VDDCR_CPU1_CP43';
NODE_NAME     U25 CP44
 '@T6G_MB_LIB.T6G(SCH_1):PAGE30_I45@PURE_QUANTA.GENOA_SP5(CHIPS)':
 'VDDCR_CPU1_CP44': CDS_PINID='VDDCR_CPU1_CP44';
NODE_NAME     U25 CP46
 '@T6G_MB_LIB.T6G(SCH_1):PAGE30_I45@PURE_QUANTA.GENOA_SP5(CHIPS)':
 'VDDCR_CPU1_CP46': CDS_PINID='VDDCR_CPU1_CP46';
NODE_NAME     U25 CP47
 '@T6G_MB_LIB.T6G(SCH_1):PAGE30_I45@PURE_QUANTA.GENOA_SP5(CHIPS)':
 'VDDCR_CPU1_CP47': CDS_PINID='VDDCR_CPU1_CP47';
NODE_NAME     U25 CP49
 '@T6G_MB_LIB.T6G(SCH_1):PAGE30_I45@PURE_QUANTA.GENOA_SP5(CHIPS)':
 'VDDCR_CPU1_CP49': CDS_PINID='VDDCR_CPU1_CP49';
NODE_NAME     U25 CP50
 '@T6G_MB_LIB.T6G(SCH_1):PAGE30_I45@PURE_QUANTA.GENOA_SP5(CHIPS)':
 'VDDCR_CPU1_CP50': CDS_PINID='VDDCR_CPU1_CP50';
NODE_NAME     U25 CP52
 '@T6G_MB_LIB.T6G(SCH_1):PAGE30_I45@PURE_QUANTA.GENOA_SP5(CHIPS)':
 'VDDCR_CPU1_CP52': CDS_PINID='VDDCR_CPU1_CP52';
NODE_NAME     U25 CP53
 '@T6G_MB_LIB.T6G(SCH_1):PAGE30_I45@PURE_QUANTA.GENOA_SP5(CHIPS)':
 'VDDCR_CPU1_CP53': CDS_PINID='VDDCR_CPU1_CP53';
NODE_NAME     U25 CU35
 '@T6G_MB_LIB.T6G(SCH_1):PAGE30_I45@PURE_QUANTA.GENOA_SP5(CHIPS)':
 'VDDCR_CPU1_CU35': CDS_PINID='VDDCR_CPU1_CU35';
NODE_NAME     U25 CU36
 '@T6G_MB_LIB.T6G(SCH_1):PAGE30_I45@PURE_QUANTA.GENOA_SP5(CHIPS)':
 'VDDCR_CPU1_CU36': CDS_PINID='VDDCR_CPU1_CU36';
NODE_NAME     U25 CU40
 '@T6G_MB_LIB.T6G(SCH_1):PAGE30_I45@PURE_QUANTA.GENOA_SP5(CHIPS)':
 'VDDCR_CPU1_CU40': CDS_PINID='VDDCR_CPU1_CU40';
NODE_NAME     U25 CU41
 '@T6G_MB_LIB.T6G(SCH_1):PAGE30_I45@PURE_QUANTA.GENOA_SP5(CHIPS)':
 'VDDCR_CPU1_CU41': CDS_PINID='VDDCR_CPU1_CU41';
NODE_NAME     U25 CV23
 '@T6G_MB_LIB.T6G(SCH_1):PAGE30_I45@PURE_QUANTA.GENOA_SP5(CHIPS)':
 'VDDCR_CPU1_CV23': CDS_PINID='VDDCR_CPU1_CV23';
NODE_NAME     U25 CV24
 '@T6G_MB_LIB.T6G(SCH_1):PAGE30_I45@PURE_QUANTA.GENOA_SP5(CHIPS)':
 'VDDCR_CPU1_CV24': CDS_PINID='VDDCR_CPU1_CV24';
NODE_NAME     U25 CV26
 '@T6G_MB_LIB.T6G(SCH_1):PAGE30_I45@PURE_QUANTA.GENOA_SP5(CHIPS)':
 'VDDCR_CPU1_CV26': CDS_PINID='VDDCR_CPU1_CV26';
NODE_NAME     U25 CV27
 '@T6G_MB_LIB.T6G(SCH_1):PAGE30_I45@PURE_QUANTA.GENOA_SP5(CHIPS)':
 'VDDCR_CPU1_CV27': CDS_PINID='VDDCR_CPU1_CV27';
NODE_NAME     U25 CV29
 '@T6G_MB_LIB.T6G(SCH_1):PAGE30_I45@PURE_QUANTA.GENOA_SP5(CHIPS)':
 'VDDCR_CPU1_CV29': CDS_PINID='VDDCR_CPU1_CV29';
NODE_NAME     U25 CV30
 '@T6G_MB_LIB.T6G(SCH_1):PAGE30_I45@PURE_QUANTA.GENOA_SP5(CHIPS)':
 'VDDCR_CPU1_CV30': CDS_PINID='VDDCR_CPU1_CV30';
NODE_NAME     U25 CV32
 '@T6G_MB_LIB.T6G(SCH_1):PAGE30_I45@PURE_QUANTA.GENOA_SP5(CHIPS)':
 'VDDCR_CPU1_CV32': CDS_PINID='VDDCR_CPU1_CV32';
NODE_NAME     U25 CV33
 '@T6G_MB_LIB.T6G(SCH_1):PAGE30_I45@PURE_QUANTA.GENOA_SP5(CHIPS)':
 'VDDCR_CPU1_CV33': CDS_PINID='VDDCR_CPU1_CV33';
NODE_NAME     U25 CV43
 '@T6G_MB_LIB.T6G(SCH_1):PAGE30_I45@PURE_QUANTA.GENOA_SP5(CHIPS)':
 'VDDCR_CPU1_CV43': CDS_PINID='VDDCR_CPU1_CV43';
NODE_NAME     U25 CV44
 '@T6G_MB_LIB.T6G(SCH_1):PAGE30_I45@PURE_QUANTA.GENOA_SP5(CHIPS)':
 'VDDCR_CPU1_CV44': CDS_PINID='VDDCR_CPU1_CV44';
NODE_NAME     U25 CV46
 '@T6G_MB_LIB.T6G(SCH_1):PAGE30_I45@PURE_QUANTA.GENOA_SP5(CHIPS)':
 'VDDCR_CPU1_CV46': CDS_PINID='VDDCR_CPU1_CV46';
NODE_NAME     U25 CV47
 '@T6G_MB_LIB.T6G(SCH_1):PAGE30_I45@PURE_QUANTA.GENOA_SP5(CHIPS)':
 'VDDCR_CPU1_CV47': CDS_PINID='VDDCR_CPU1_CV47';
NODE_NAME     U25 CV49
 '@T6G_MB_LIB.T6G(SCH_1):PAGE30_I45@PURE_QUANTA.GENOA_SP5(CHIPS)':
 'VDDCR_CPU1_CV49': CDS_PINID='VDDCR_CPU1_CV49';
NODE_NAME     U25 CV50
 '@T6G_MB_LIB.T6G(SCH_1):PAGE30_I45@PURE_QUANTA.GENOA_SP5(CHIPS)':
 'VDDCR_CPU1_CV50': CDS_PINID='VDDCR_CPU1_CV50';
NODE_NAME     U25 CV52
 '@T6G_MB_LIB.T6G(SCH_1):PAGE30_I45@PURE_QUANTA.GENOA_SP5(CHIPS)':
 'VDDCR_CPU1_CV52': CDS_PINID='VDDCR_CPU1_CV52';
NODE_NAME     U25 CV53
 '@T6G_MB_LIB.T6G(SCH_1):PAGE30_I45@PURE_QUANTA.GENOA_SP5(CHIPS)':
 'VDDCR_CPU1_CV53': CDS_PINID='VDDCR_CPU1_CV53';
NODE_NAME     U25 DA35
 '@T6G_MB_LIB.T6G(SCH_1):PAGE30_I45@PURE_QUANTA.GENOA_SP5(CHIPS)':
 'VDDCR_CPU1_DA35': CDS_PINID='VDDCR_CPU1_DA35';
NODE_NAME     U25 DA36
 '@T6G_MB_LIB.T6G(SCH_1):PAGE30_I45@PURE_QUANTA.GENOA_SP5(CHIPS)':
 'VDDCR_CPU1_DA36': CDS_PINID='VDDCR_CPU1_DA36';
NODE_NAME     U25 DA40
 '@T6G_MB_LIB.T6G(SCH_1):PAGE30_I45@PURE_QUANTA.GENOA_SP5(CHIPS)':
 'VDDCR_CPU1_DA40': CDS_PINID='VDDCR_CPU1_DA40';
NODE_NAME     U25 DA41
 '@T6G_MB_LIB.T6G(SCH_1):PAGE30_I45@PURE_QUANTA.GENOA_SP5(CHIPS)':
 'VDDCR_CPU1_DA41': CDS_PINID='VDDCR_CPU1_DA41';
NODE_NAME     U25 DB23
 '@T6G_MB_LIB.T6G(SCH_1):PAGE30_I45@PURE_QUANTA.GENOA_SP5(CHIPS)':
 'VDDCR_CPU1_DB23': CDS_PINID='VDDCR_CPU1_DB23';
NODE_NAME     U25 DB24
 '@T6G_MB_LIB.T6G(SCH_1):PAGE30_I45@PURE_QUANTA.GENOA_SP5(CHIPS)':
 'VDDCR_CPU1_DB24': CDS_PINID='VDDCR_CPU1_DB24';
NODE_NAME     U25 DB26
 '@T6G_MB_LIB.T6G(SCH_1):PAGE30_I45@PURE_QUANTA.GENOA_SP5(CHIPS)':
 'VDDCR_CPU1_DB26': CDS_PINID='VDDCR_CPU1_DB26';
NODE_NAME     U25 DB27
 '@T6G_MB_LIB.T6G(SCH_1):PAGE30_I45@PURE_QUANTA.GENOA_SP5(CHIPS)':
 'VDDCR_CPU1_DB27': CDS_PINID='VDDCR_CPU1_DB27';
NODE_NAME     U25 DB29
 '@T6G_MB_LIB.T6G(SCH_1):PAGE30_I45@PURE_QUANTA.GENOA_SP5(CHIPS)':
 'VDDCR_CPU1_DB29': CDS_PINID='VDDCR_CPU1_DB29';
NODE_NAME     U25 DB30
 '@T6G_MB_LIB.T6G(SCH_1):PAGE30_I45@PURE_QUANTA.GENOA_SP5(CHIPS)':
 'VDDCR_CPU1_DB30': CDS_PINID='VDDCR_CPU1_DB30';
NODE_NAME     U25 DB32
 '@T6G_MB_LIB.T6G(SCH_1):PAGE30_I45@PURE_QUANTA.GENOA_SP5(CHIPS)':
 'VDDCR_CPU1_DB32': CDS_PINID='VDDCR_CPU1_DB32';
NODE_NAME     U25 DB33
 '@T6G_MB_LIB.T6G(SCH_1):PAGE30_I45@PURE_QUANTA.GENOA_SP5(CHIPS)':
 'VDDCR_CPU1_DB33': CDS_PINID='VDDCR_CPU1_DB33';
NODE_NAME     U25 DB43
 '@T6G_MB_LIB.T6G(SCH_1):PAGE30_I45@PURE_QUANTA.GENOA_SP5(CHIPS)':
 'VDDCR_CPU1_DB43': CDS_PINID='VDDCR_CPU1_DB43';
NODE_NAME     U25 DB44
 '@T6G_MB_LIB.T6G(SCH_1):PAGE30_I45@PURE_QUANTA.GENOA_SP5(CHIPS)':
 'VDDCR_CPU1_DB44': CDS_PINID='VDDCR_CPU1_DB44';
NODE_NAME     U25 DB46
 '@T6G_MB_LIB.T6G(SCH_1):PAGE30_I45@PURE_QUANTA.GENOA_SP5(CHIPS)':
 'VDDCR_CPU1_DB46': CDS_PINID='VDDCR_CPU1_DB46';
NODE_NAME     U25 DB47
 '@T6G_MB_LIB.T6G(SCH_1):PAGE30_I45@PURE_QUANTA.GENOA_SP5(CHIPS)':
 'VDDCR_CPU1_DB47': CDS_PINID='VDDCR_CPU1_DB47';
NODE_NAME     U25 DB49
 '@T6G_MB_LIB.T6G(SCH_1):PAGE30_I45@PURE_QUANTA.GENOA_SP5(CHIPS)':
 'VDDCR_CPU1_DB49': CDS_PINID='VDDCR_CPU1_DB49';
NODE_NAME     U25 DB50
 '@T6G_MB_LIB.T6G(SCH_1):PAGE30_I45@PURE_QUANTA.GENOA_SP5(CHIPS)':
 'VDDCR_CPU1_DB50': CDS_PINID='VDDCR_CPU1_DB50';
NODE_NAME     U25 DB52
 '@T6G_MB_LIB.T6G(SCH_1):PAGE30_I45@PURE_QUANTA.GENOA_SP5(CHIPS)':
 'VDDCR_CPU1_DB52': CDS_PINID='VDDCR_CPU1_DB52';
NODE_NAME     U25 DB53
 '@T6G_MB_LIB.T6G(SCH_1):PAGE30_I45@PURE_QUANTA.GENOA_SP5(CHIPS)':
 'VDDCR_CPU1_DB53': CDS_PINID='VDDCR_CPU1_DB53';
NODE_NAME     U25 DC35
 '@T6G_MB_LIB.T6G(SCH_1):PAGE30_I45@PURE_QUANTA.GENOA_SP5(CHIPS)':
 'VDDCR_CPU1_DC35': CDS_PINID='VDDCR_CPU1_DC35';
NODE_NAME     U25 DC36
 '@T6G_MB_LIB.T6G(SCH_1):PAGE30_I45@PURE_QUANTA.GENOA_SP5(CHIPS)':
 'VDDCR_CPU1_DC36': CDS_PINID='VDDCR_CPU1_DC36';
NODE_NAME     U25 DC40
 '@T6G_MB_LIB.T6G(SCH_1):PAGE30_I45@PURE_QUANTA.GENOA_SP5(CHIPS)':
 'VDDCR_CPU1_DC40': CDS_PINID='VDDCR_CPU1_DC40';
NODE_NAME     U25 DC41
 '@T6G_MB_LIB.T6G(SCH_1):PAGE30_I45@PURE_QUANTA.GENOA_SP5(CHIPS)':
 'VDDCR_CPU1_DC41': CDS_PINID='VDDCR_CPU1_DC41';
NODE_NAME     U25 DD22
 '@T6G_MB_LIB.T6G(SCH_1):PAGE30_I45@PURE_QUANTA.GENOA_SP5(CHIPS)':
 'VDDCR_CPU1_DD22': CDS_PINID='VDDCR_CPU1_DD22';
NODE_NAME     U25 DD25
 '@T6G_MB_LIB.T6G(SCH_1):PAGE30_I45@PURE_QUANTA.GENOA_SP5(CHIPS)':
 'VDDCR_CPU1_DD25': CDS_PINID='VDDCR_CPU1_DD25';
NODE_NAME     U25 DD28
 '@T6G_MB_LIB.T6G(SCH_1):PAGE30_I45@PURE_QUANTA.GENOA_SP5(CHIPS)':
 'VDDCR_CPU1_DD28': CDS_PINID='VDDCR_CPU1_DD28';
NODE_NAME     U25 DD31
 '@T6G_MB_LIB.T6G(SCH_1):PAGE30_I45@PURE_QUANTA.GENOA_SP5(CHIPS)':
 'VDDCR_CPU1_DD31': CDS_PINID='VDDCR_CPU1_DD31';
NODE_NAME     U25 DD34
 '@T6G_MB_LIB.T6G(SCH_1):PAGE30_I45@PURE_QUANTA.GENOA_SP5(CHIPS)':
 'VDDCR_CPU1_DD34': CDS_PINID='VDDCR_CPU1_DD34';
NODE_NAME     U25 DD42
 '@T6G_MB_LIB.T6G(SCH_1):PAGE30_I45@PURE_QUANTA.GENOA_SP5(CHIPS)':
 'VDDCR_CPU1_DD42': CDS_PINID='VDDCR_CPU1_DD42';
NODE_NAME     U25 DD45
 '@T6G_MB_LIB.T6G(SCH_1):PAGE30_I45@PURE_QUANTA.GENOA_SP5(CHIPS)':
 'VDDCR_CPU1_DD45': CDS_PINID='VDDCR_CPU1_DD45';
NODE_NAME     U25 DD48
 '@T6G_MB_LIB.T6G(SCH_1):PAGE30_I45@PURE_QUANTA.GENOA_SP5(CHIPS)':
 'VDDCR_CPU1_DD48': CDS_PINID='VDDCR_CPU1_DD48';
NODE_NAME     U25 DD51
 '@T6G_MB_LIB.T6G(SCH_1):PAGE30_I45@PURE_QUANTA.GENOA_SP5(CHIPS)':
 'VDDCR_CPU1_DD51': CDS_PINID='VDDCR_CPU1_DD51';
NODE_NAME     U25 DD54
 '@T6G_MB_LIB.T6G(SCH_1):PAGE30_I45@PURE_QUANTA.GENOA_SP5(CHIPS)':
 'VDDCR_CPU1_DD54': CDS_PINID='VDDCR_CPU1_DD54';
NODE_NAME     U25 DE22
 '@T6G_MB_LIB.T6G(SCH_1):PAGE30_I45@PURE_QUANTA.GENOA_SP5(CHIPS)':
 'VDDCR_CPU1_DE22': CDS_PINID='VDDCR_CPU1_DE22';
NODE_NAME     U25 DE25
 '@T6G_MB_LIB.T6G(SCH_1):PAGE30_I45@PURE_QUANTA.GENOA_SP5(CHIPS)':
 'VDDCR_CPU1_DE25': CDS_PINID='VDDCR_CPU1_DE25';
NODE_NAME     U25 DE28
 '@T6G_MB_LIB.T6G(SCH_1):PAGE30_I45@PURE_QUANTA.GENOA_SP5(CHIPS)':
 'VDDCR_CPU1_DE28': CDS_PINID='VDDCR_CPU1_DE28';
NODE_NAME     U25 DE31
 '@T6G_MB_LIB.T6G(SCH_1):PAGE30_I45@PURE_QUANTA.GENOA_SP5(CHIPS)':
 'VDDCR_CPU1_DE31': CDS_PINID='VDDCR_CPU1_DE31';
NODE_NAME     U25 DE34
 '@T6G_MB_LIB.T6G(SCH_1):PAGE30_I45@PURE_QUANTA.GENOA_SP5(CHIPS)':
 'VDDCR_CPU1_DE34': CDS_PINID='VDDCR_CPU1_DE34';
NODE_NAME     U25 DE35
 '@T6G_MB_LIB.T6G(SCH_1):PAGE30_I45@PURE_QUANTA.GENOA_SP5(CHIPS)':
 'VDDCR_CPU1_DE35': CDS_PINID='VDDCR_CPU1_DE35';
NODE_NAME     U25 DE41
 '@T6G_MB_LIB.T6G(SCH_1):PAGE30_I45@PURE_QUANTA.GENOA_SP5(CHIPS)':
 'VDDCR_CPU1_DE41': CDS_PINID='VDDCR_CPU1_DE41';
NODE_NAME     U25 DE42
 '@T6G_MB_LIB.T6G(SCH_1):PAGE30_I45@PURE_QUANTA.GENOA_SP5(CHIPS)':
 'VDDCR_CPU1_DE42': CDS_PINID='VDDCR_CPU1_DE42';
NODE_NAME     U25 DE45
 '@T6G_MB_LIB.T6G(SCH_1):PAGE30_I45@PURE_QUANTA.GENOA_SP5(CHIPS)':
 'VDDCR_CPU1_DE45': CDS_PINID='VDDCR_CPU1_DE45';
NODE_NAME     U25 DE48
 '@T6G_MB_LIB.T6G(SCH_1):PAGE30_I45@PURE_QUANTA.GENOA_SP5(CHIPS)':
 'VDDCR_CPU1_DE48': CDS_PINID='VDDCR_CPU1_DE48';
NODE_NAME     U25 DE51
 '@T6G_MB_LIB.T6G(SCH_1):PAGE30_I45@PURE_QUANTA.GENOA_SP5(CHIPS)':
 'VDDCR_CPU1_DE51': CDS_PINID='VDDCR_CPU1_DE51';
NODE_NAME     U25 DE54
 '@T6G_MB_LIB.T6G(SCH_1):PAGE30_I45@PURE_QUANTA.GENOA_SP5(CHIPS)':
 'VDDCR_CPU1_DE54': CDS_PINID='VDDCR_CPU1_DE54';
NODE_NAME     U25 DG19
 '@T6G_MB_LIB.T6G(SCH_1):PAGE30_I45@PURE_QUANTA.GENOA_SP5(CHIPS)':
 'VDDCR_CPU1_DG19': CDS_PINID='VDDCR_CPU1_DG19';
NODE_NAME     U25 DG57
 '@T6G_MB_LIB.T6G(SCH_1):PAGE30_I45@PURE_QUANTA.GENOA_SP5(CHIPS)':
 'VDDCR_CPU1_DG57': CDS_PINID='VDDCR_CPU1_DG57';
NODE_NAME     U25 DH19
 '@T6G_MB_LIB.T6G(SCH_1):PAGE30_I45@PURE_QUANTA.GENOA_SP5(CHIPS)':
 'VDDCR_CPU1_DH19': CDS_PINID='VDDCR_CPU1_DH19';
NODE_NAME     U25 DH20
 '@T6G_MB_LIB.T6G(SCH_1):PAGE30_I45@PURE_QUANTA.GENOA_SP5(CHIPS)':
 'VDDCR_CPU1_DH20': CDS_PINID='VDDCR_CPU1_DH20';
NODE_NAME     U25 DH22
 '@T6G_MB_LIB.T6G(SCH_1):PAGE30_I45@PURE_QUANTA.GENOA_SP5(CHIPS)':
 'VDDCR_CPU1_DH22': CDS_PINID='VDDCR_CPU1_DH22';
NODE_NAME     U25 DH23
 '@T6G_MB_LIB.T6G(SCH_1):PAGE30_I45@PURE_QUANTA.GENOA_SP5(CHIPS)':
 'VDDCR_CPU1_DH23': CDS_PINID='VDDCR_CPU1_DH23';
NODE_NAME     U25 DH25
 '@T6G_MB_LIB.T6G(SCH_1):PAGE30_I45@PURE_QUANTA.GENOA_SP5(CHIPS)':
 'VDDCR_CPU1_DH25': CDS_PINID='VDDCR_CPU1_DH25';
NODE_NAME     U25 DH26
 '@T6G_MB_LIB.T6G(SCH_1):PAGE30_I45@PURE_QUANTA.GENOA_SP5(CHIPS)':
 'VDDCR_CPU1_DH26': CDS_PINID='VDDCR_CPU1_DH26';
NODE_NAME     U25 DH28
 '@T6G_MB_LIB.T6G(SCH_1):PAGE30_I45@PURE_QUANTA.GENOA_SP5(CHIPS)':
 'VDDCR_CPU1_DH28': CDS_PINID='VDDCR_CPU1_DH28';
NODE_NAME     U25 DH29
 '@T6G_MB_LIB.T6G(SCH_1):PAGE30_I45@PURE_QUANTA.GENOA_SP5(CHIPS)':
 'VDDCR_CPU1_DH29': CDS_PINID='VDDCR_CPU1_DH29';
NODE_NAME     U25 DH31
 '@T6G_MB_LIB.T6G(SCH_1):PAGE30_I45@PURE_QUANTA.GENOA_SP5(CHIPS)':
 'VDDCR_CPU1_DH31': CDS_PINID='VDDCR_CPU1_DH31';
NODE_NAME     U25 DH32
 '@T6G_MB_LIB.T6G(SCH_1):PAGE30_I45@PURE_QUANTA.GENOA_SP5(CHIPS)':
 'VDDCR_CPU1_DH32': CDS_PINID='VDDCR_CPU1_DH32';
NODE_NAME     U25 DH34
 '@T6G_MB_LIB.T6G(SCH_1):PAGE30_I45@PURE_QUANTA.GENOA_SP5(CHIPS)':
 'VDDCR_CPU1_DH34': CDS_PINID='VDDCR_CPU1_DH34';
NODE_NAME     U25 DH35
 '@T6G_MB_LIB.T6G(SCH_1):PAGE30_I45@PURE_QUANTA.GENOA_SP5(CHIPS)':
 'VDDCR_CPU1_DH35': CDS_PINID='VDDCR_CPU1_DH35';
NODE_NAME     U25 DH41
 '@T6G_MB_LIB.T6G(SCH_1):PAGE30_I45@PURE_QUANTA.GENOA_SP5(CHIPS)':
 'VDDCR_CPU1_DH41': CDS_PINID='VDDCR_CPU1_DH41';
NODE_NAME     U25 DH42
 '@T6G_MB_LIB.T6G(SCH_1):PAGE30_I45@PURE_QUANTA.GENOA_SP5(CHIPS)':
 'VDDCR_CPU1_DH42': CDS_PINID='VDDCR_CPU1_DH42';
NODE_NAME     U25 DH44
 '@T6G_MB_LIB.T6G(SCH_1):PAGE30_I45@PURE_QUANTA.GENOA_SP5(CHIPS)':
 'VDDCR_CPU1_DH44': CDS_PINID='VDDCR_CPU1_DH44';
NODE_NAME     U25 DH45
 '@T6G_MB_LIB.T6G(SCH_1):PAGE30_I45@PURE_QUANTA.GENOA_SP5(CHIPS)':
 'VDDCR_CPU1_DH45': CDS_PINID='VDDCR_CPU1_DH45';
NODE_NAME     U25 DH47
 '@T6G_MB_LIB.T6G(SCH_1):PAGE30_I45@PURE_QUANTA.GENOA_SP5(CHIPS)':
 'VDDCR_CPU1_DH47': CDS_PINID='VDDCR_CPU1_DH47';
NODE_NAME     U25 DH48
 '@T6G_MB_LIB.T6G(SCH_1):PAGE30_I45@PURE_QUANTA.GENOA_SP5(CHIPS)':
 'VDDCR_CPU1_DH48': CDS_PINID='VDDCR_CPU1_DH48';
NODE_NAME     U25 DH50
 '@T6G_MB_LIB.T6G(SCH_1):PAGE30_I45@PURE_QUANTA.GENOA_SP5(CHIPS)':
 'VDDCR_CPU1_DH50': CDS_PINID='VDDCR_CPU1_DH50';
NODE_NAME     U25 DH51
 '@T6G_MB_LIB.T6G(SCH_1):PAGE30_I45@PURE_QUANTA.GENOA_SP5(CHIPS)':
 'VDDCR_CPU1_DH51': CDS_PINID='VDDCR_CPU1_DH51';
NODE_NAME     U25 DH53
 '@T6G_MB_LIB.T6G(SCH_1):PAGE30_I45@PURE_QUANTA.GENOA_SP5(CHIPS)':
 'VDDCR_CPU1_DH53': CDS_PINID='VDDCR_CPU1_DH53';
NODE_NAME     U25 DH54
 '@T6G_MB_LIB.T6G(SCH_1):PAGE30_I45@PURE_QUANTA.GENOA_SP5(CHIPS)':
 'VDDCR_CPU1_DH54': CDS_PINID='VDDCR_CPU1_DH54';
NODE_NAME     U25 DH56
 '@T6G_MB_LIB.T6G(SCH_1):PAGE30_I45@PURE_QUANTA.GENOA_SP5(CHIPS)':
 'VDDCR_CPU1_DH56': CDS_PINID='VDDCR_CPU1_DH56';
NODE_NAME     U25 DH57
 '@T6G_MB_LIB.T6G(SCH_1):PAGE30_I45@PURE_QUANTA.GENOA_SP5(CHIPS)':
 'VDDCR_CPU1_DH57': CDS_PINID='VDDCR_CPU1_DH57';
NODE_NAME     C2205 1
 '@T6G_MB_LIB.T6G(SCH_1):PAGE68_I30@PURE_QUANTA.Q_CAP(CHIPS)':
 'A': CDS_PINID='A';
NODE_NAME     C2204 1
 '@T6G_MB_LIB.T6G(SCH_1):PAGE68_I38@PURE_QUANTA.Q_CAP(CHIPS)':
 'A': CDS_PINID='A';
NODE_NAME     C2203 1
 '@T6G_MB_LIB.T6G(SCH_1):PAGE68_I43@PURE_QUANTA.Q_CAP(CHIPS)':
 'A': CDS_PINID='A';
NODE_NAME     C2202 1
 '@T6G_MB_LIB.T6G(SCH_1):PAGE68_I60@PURE_QUANTA.Q_CAP(CHIPS)':
 'A': CDS_PINID='A';
NODE_NAME     C2201 1
 '@T6G_MB_LIB.T6G(SCH_1):PAGE68_I63@PURE_QUANTA.Q_CAP(CHIPS)':
 'A': CDS_PINID='A';
NODE_NAME     C2211 1
 '@T6G_MB_LIB.T6G(SCH_1):PAGE68_I65@PURE_QUANTA.Q_CAP(CHIPS)':
 'A': CDS_PINID='A';
NODE_NAME     C2217 1
 '@T6G_MB_LIB.T6G(SCH_1):PAGE68_I66@PURE_QUANTA.Q_CAP(CHIPS)':
 'A': CDS_PINID='A';
NODE_NAME     C2223 1
 '@T6G_MB_LIB.T6G(SCH_1):PAGE68_I67@PURE_QUANTA.Q_CAP(CHIPS)':
 'A': CDS_PINID='A';
NODE_NAME     C2229 1
 '@T6G_MB_LIB.T6G(SCH_1):PAGE68_I69@PURE_QUANTA.Q_CAP(CHIPS)':
 'A': CDS_PINID='A';
NODE_NAME     C2210 1
 '@T6G_MB_LIB.T6G(SCH_1):PAGE68_I70@PURE_QUANTA.Q_CAP(CHIPS)':
 'A': CDS_PINID='A';
NODE_NAME     C2216 1
 '@T6G_MB_LIB.T6G(SCH_1):PAGE68_I71@PURE_QUANTA.Q_CAP(CHIPS)':
 'A': CDS_PINID='A';
NODE_NAME     C2209 1
 '@T6G_MB_LIB.T6G(SCH_1):PAGE68_I72@PURE_QUANTA.Q_CAP(CHIPS)':
 'A': CDS_PINID='A';
NODE_NAME     C2215 1
 '@T6G_MB_LIB.T6G(SCH_1):PAGE68_I73@PURE_QUANTA.Q_CAP(CHIPS)':
 'A': CDS_PINID='A';
NODE_NAME     C2222 1
 '@T6G_MB_LIB.T6G(SCH_1):PAGE68_I74@PURE_QUANTA.Q_CAP(CHIPS)':
 'A': CDS_PINID='A';
NODE_NAME     C2228 1
 '@T6G_MB_LIB.T6G(SCH_1):PAGE68_I75@PURE_QUANTA.Q_CAP(CHIPS)':
 'A': CDS_PINID='A';
NODE_NAME     C2234 1
 '@T6G_MB_LIB.T6G(SCH_1):PAGE68_I76@PURE_QUANTA.Q_CAP(CHIPS)':
 'A': CDS_PINID='A';
NODE_NAME     C2221 1
 '@T6G_MB_LIB.T6G(SCH_1):PAGE68_I77@PURE_QUANTA.Q_CAP(CHIPS)':
 'A': CDS_PINID='A';
NODE_NAME     C2227 1
 '@T6G_MB_LIB.T6G(SCH_1):PAGE68_I78@PURE_QUANTA.Q_CAP(CHIPS)':
 'A': CDS_PINID='A';
NODE_NAME     C2233 1
 '@T6G_MB_LIB.T6G(SCH_1):PAGE68_I79@PURE_QUANTA.Q_CAP(CHIPS)':
 'A': CDS_PINID='A';
NODE_NAME     C2240 1
 '@T6G_MB_LIB.T6G(SCH_1):PAGE68_I80@PURE_QUANTA.Q_CAP(CHIPS)':
 'A': CDS_PINID='A';
NODE_NAME     C2246 1
 '@T6G_MB_LIB.T6G(SCH_1):PAGE68_I81@PURE_QUANTA.Q_CAP(CHIPS)':
 'A': CDS_PINID='A';
NODE_NAME     C2239 1
 '@T6G_MB_LIB.T6G(SCH_1):PAGE68_I82@PURE_QUANTA.Q_CAP(CHIPS)':
 'A': CDS_PINID='A';
NODE_NAME     C2245 1
 '@T6G_MB_LIB.T6G(SCH_1):PAGE68_I83@PURE_QUANTA.Q_CAP(CHIPS)':
 'A': CDS_PINID='A';
NODE_NAME     C2251 1
 '@T6G_MB_LIB.T6G(SCH_1):PAGE68_I84@PURE_QUANTA.Q_CAP(CHIPS)':
 'A': CDS_PINID='A';
NODE_NAME     C2256 1
 '@T6G_MB_LIB.T6G(SCH_1):PAGE68_I86@PURE_QUANTA.Q_CAP(CHIPS)':
 'A': CDS_PINID='A';
NODE_NAME     C2250 1
 '@T6G_MB_LIB.T6G(SCH_1):PAGE68_I87@PURE_QUANTA.Q_CAP(CHIPS)':
 'A': CDS_PINID='A';
NODE_NAME     C2255 1
 '@T6G_MB_LIB.T6G(SCH_1):PAGE68_I89@PURE_QUANTA.Q_CAP(CHIPS)':
 'A': CDS_PINID='A';
NODE_NAME     C2208 1
 '@T6G_MB_LIB.T6G(SCH_1):PAGE68_I91@PURE_QUANTA.Q_CAP(CHIPS)':
 'A': CDS_PINID='A';
NODE_NAME     C2214 1
 '@T6G_MB_LIB.T6G(SCH_1):PAGE68_I92@PURE_QUANTA.Q_CAP(CHIPS)':
 'A': CDS_PINID='A';
NODE_NAME     C2207 1
 '@T6G_MB_LIB.T6G(SCH_1):PAGE68_I93@PURE_QUANTA.Q_CAP(CHIPS)':
 'A': CDS_PINID='A';
NODE_NAME     C2213 1
 '@T6G_MB_LIB.T6G(SCH_1):PAGE68_I94@PURE_QUANTA.Q_CAP(CHIPS)':
 'A': CDS_PINID='A';
NODE_NAME     C2220 1
 '@T6G_MB_LIB.T6G(SCH_1):PAGE68_I95@PURE_QUANTA.Q_CAP(CHIPS)':
 'A': CDS_PINID='A';
NODE_NAME     C2226 1
 '@T6G_MB_LIB.T6G(SCH_1):PAGE68_I96@PURE_QUANTA.Q_CAP(CHIPS)':
 'A': CDS_PINID='A';
NODE_NAME     C2232 1
 '@T6G_MB_LIB.T6G(SCH_1):PAGE68_I97@PURE_QUANTA.Q_CAP(CHIPS)':
 'A': CDS_PINID='A';
NODE_NAME     C2219 1
 '@T6G_MB_LIB.T6G(SCH_1):PAGE68_I98@PURE_QUANTA.Q_CAP(CHIPS)':
 'A': CDS_PINID='A';
NODE_NAME     C2225 1
 '@T6G_MB_LIB.T6G(SCH_1):PAGE68_I99@PURE_QUANTA.Q_CAP(CHIPS)':
 'A': CDS_PINID='A';
NODE_NAME     C2231 1
 '@T6G_MB_LIB.T6G(SCH_1):PAGE68_I100@PURE_QUANTA.Q_CAP(CHIPS)':
 'A': CDS_PINID='A';
NODE_NAME     C2238 1
 '@T6G_MB_LIB.T6G(SCH_1):PAGE68_I101@PURE_QUANTA.Q_CAP(CHIPS)':
 'A': CDS_PINID='A';
NODE_NAME     C2244 1
 '@T6G_MB_LIB.T6G(SCH_1):PAGE68_I102@PURE_QUANTA.Q_CAP(CHIPS)':
 'A': CDS_PINID='A';
NODE_NAME     C2237 1
 '@T6G_MB_LIB.T6G(SCH_1):PAGE68_I103@PURE_QUANTA.Q_CAP(CHIPS)':
 'A': CDS_PINID='A';
NODE_NAME     C2243 1
 '@T6G_MB_LIB.T6G(SCH_1):PAGE68_I104@PURE_QUANTA.Q_CAP(CHIPS)':
 'A': CDS_PINID='A';
NODE_NAME     C2249 1
 '@T6G_MB_LIB.T6G(SCH_1):PAGE68_I105@PURE_QUANTA.Q_CAP(CHIPS)':
 'A': CDS_PINID='A';
NODE_NAME     C2254 1
 '@T6G_MB_LIB.T6G(SCH_1):PAGE68_I106@PURE_QUANTA.Q_CAP(CHIPS)':
 'A': CDS_PINID='A';
NODE_NAME     C2248 1
 '@T6G_MB_LIB.T6G(SCH_1):PAGE68_I108@PURE_QUANTA.Q_CAP(CHIPS)':
 'A': CDS_PINID='A';
NODE_NAME     C2253 1
 '@T6G_MB_LIB.T6G(SCH_1):PAGE68_I109@PURE_QUANTA.Q_CAP(CHIPS)':
 'A': CDS_PINID='A';
NODE_NAME     PL11 4
 '@T6G_MB_LIB.T6G(SCH_1):PAGE176_I46@PURE_QUANTA.Q_INDUCTOR4P_14(CHIPS)':
 '4': CDS_PINID='\4\';
NODE_NAME     PC103 1
 '@T6G_MB_LIB.T6G(SCH_1):PAGE176_I75@PURE_QUANTA.Q_CAPP(CHIPS)':
 'A': CDS_PINID='A';
NODE_NAME     PR91 2
 '@T6G_MB_LIB.T6G(SCH_1):PAGE177_I40@PURE_QUANTA.Q_RES(CHIPS)':
 'B': CDS_PINID='B';
NODE_NAME     PL13 4
 '@T6G_MB_LIB.T6G(SCH_1):PAGE177_I42@PURE_QUANTA.Q_INDUCTOR4P_14(CHIPS)':
 '4': CDS_PINID='\4\';
NODE_NAME     PR92 2
 '@T6G_MB_LIB.T6G(SCH_1):PAGE177_I51@PURE_QUANTA.Q_RES(CHIPS)':
 'B': CDS_PINID='B';
NODE_NAME     PC128_4 1
 '@T6G_MB_LIB.T6G(SCH_1):PAGE177_I55@PURE_QUANTA.Q_CAP(CHIPS)':
 'A': CDS_PINID='A';
NODE_NAME     PR51 2
 '@T6G_MB_LIB.T6G(SCH_1):PAGE175_I36@PURE_QUANTA.Q_RES(CHIPS)':
 'B': CDS_PINID='B';
NODE_NAME     PR83 2
 '@T6G_MB_LIB.T6G(SCH_1):PAGE176_I42@PURE_QUANTA.Q_RES(CHIPS)':
 'B': CDS_PINID='B';
NODE_NAME     PR84 2
 '@T6G_MB_LIB.T6G(SCH_1):PAGE176_I54@PURE_QUANTA.Q_RES(CHIPS)':
 'B': CDS_PINID='B';
NODE_NAME     PL10 4
 '@T6G_MB_LIB.T6G(SCH_1):PAGE176_I62@PURE_QUANTA.Q_INDUCTOR4P_14(CHIPS)':
 '4': CDS_PINID='\4\';
NODE_NAME     PC106_2 1
 '@T6G_MB_LIB.T6G(SCH_1):PAGE176_I69@PURE_QUANTA.Q_CAP(CHIPS)':
 'A': CDS_PINID='A';
NODE_NAME     PC102 1
 '@T6G_MB_LIB.T6G(SCH_1):PAGE176_I70@PURE_QUANTA.Q_CAPP(CHIPS)':
 'A': CDS_PINID='A';
NODE_NAME     PC97 1
 '@T6G_MB_LIB.T6G(SCH_1):PAGE176_I71@PURE_QUANTA.Q_CAPP(CHIPS)':
 'A': CDS_PINID='A';
NODE_NAME     PC98 1
 '@T6G_MB_LIB.T6G(SCH_1):PAGE176_I72@PURE_QUANTA.Q_CAPP(CHIPS)':
 'A': CDS_PINID='A';
NODE_NAME     PC100 1
 '@T6G_MB_LIB.T6G(SCH_1):PAGE176_I73@PURE_QUANTA.Q_CAPP(CHIPS)':
 'A': CDS_PINID='A';
NODE_NAME     PC108_2 1
 '@T6G_MB_LIB.T6G(SCH_1):PAGE176_I77@PURE_QUANTA.Q_CAP(CHIPS)':
 'A': CDS_PINID='A';
NODE_NAME     PC99 1
 '@T6G_MB_LIB.T6G(SCH_1):PAGE176_I84@PURE_QUANTA.Q_CAP(CHIPS)':
 'A': CDS_PINID='A';
NODE_NAME     PC102_1 1
 '@T6G_MB_LIB.T6G(SCH_1):PAGE176_I86@PURE_QUANTA.Q_CAP(CHIPS)':
 'A': CDS_PINID='A';
NODE_NAME     PC105_1 1
 '@T6G_MB_LIB.T6G(SCH_1):PAGE176_I89@PURE_QUANTA.Q_CAP(CHIPS)':
 'A': CDS_PINID='A';
NODE_NAME     PR444 1
 '@T6G_MB_LIB.T6G(SCH_1):PAGE176_I90@PURE_QUANTA.Q_RES(CHIPS)':
 'A': CDS_PINID='A';
NODE_NAME     PC127_4 1
 '@T6G_MB_LIB.T6G(SCH_1):PAGE177_I54@PURE_QUANTA.Q_CAP(CHIPS)':
 'A': CDS_PINID='A';
NODE_NAME     PL14 4
 '@T6G_MB_LIB.T6G(SCH_1):PAGE177_I64@PURE_QUANTA.Q_INDUCTOR4P_14(CHIPS)':
 '4': CDS_PINID='\4\';
NODE_NAME     PC129_3 1
 '@T6G_MB_LIB.T6G(SCH_1):PAGE177_I69@PURE_QUANTA.Q_CAP(CHIPS)':
 'A': CDS_PINID='A';
NODE_NAME     PC130_3 1
 '@T6G_MB_LIB.T6G(SCH_1):PAGE177_I71@PURE_QUANTA.Q_CAP(CHIPS)':
 'A': CDS_PINID='A';
NODE_NAME     PR421 2
 '@T6G_MB_LIB.T6G(SCH_1):PAGE178_I35@PURE_QUANTA.Q_RES(CHIPS)':
 'B': CDS_PINID='B';
NODE_NAME     PL7 4
 '@T6G_MB_LIB.T6G(SCH_1):PAGE178_I38@PURE_QUANTA.Q_INDUCTOR4P_14(CHIPS)':
 '4': CDS_PINID='\4\';
NODE_NAME     PR96 2
 '@T6G_MB_LIB.T6G(SCH_1):PAGE178_I49@PURE_QUANTA.Q_RES(CHIPS)':
 'B': CDS_PINID='B';
NODE_NAME     PC120_6 1
 '@T6G_MB_LIB.T6G(SCH_1):PAGE178_I51@PURE_QUANTA.Q_CAP(CHIPS)':
 'A': CDS_PINID='A';
NODE_NAME     PC123_6 1
 '@T6G_MB_LIB.T6G(SCH_1):PAGE178_I53@PURE_QUANTA.Q_CAP(CHIPS)':
 'A': CDS_PINID='A';
NODE_NAME     PL15 4
 '@T6G_MB_LIB.T6G(SCH_1):PAGE178_I63@PURE_QUANTA.Q_INDUCTOR4P_14(CHIPS)':
 '4': CDS_PINID='\4\';
NODE_NAME     PC140_5 1
 '@T6G_MB_LIB.T6G(SCH_1):PAGE178_I69@PURE_QUANTA.Q_CAP(CHIPS)':
 'A': CDS_PINID='A';
NODE_NAME     PC141_5 1
 '@T6G_MB_LIB.T6G(SCH_1):PAGE178_I70@PURE_QUANTA.Q_CAP(CHIPS)':
 'A': CDS_PINID='A';
NET_NAME
'PVDDCR_CPU1_P0_EN1_ADDR_CFG'
 '@T6G_MB_LIB.T6G(SCH_1):PVDDCR_CPU1_P0_EN1_ADDR_CFG':
 C_SIGNAL='@t6g_mb_lib.t6g(sch_1):pvddcr_cpu1_p0_en1_addr_cfg';
NODE_NAME     PR67 1
 '@T6G_MB_LIB.T6G(SCH_1):PAGE175_I12@PURE_QUANTA.Q_RES(CHIPS)':
 'A': CDS_PINID='A';
NODE_NAME     PQ10 D
 '@T6G_MB_LIB.T6G(SCH_1):PAGE175_I13@PURE_QUANTA.MOSFET_PCH_GDS_ESD_PROTECTED(CHIPS)':
 'D': CDS_PINID='D';
NODE_NAME     PU12 42
 '@T6G_MB_LIB.T6G(SCH_1):PAGE175_I128@PURE_QUANTA.RAA229620GNPHA0(CHIPS)':
 'EN1||ADDR_CFG': CDS_PINID='\en1||addr_cfg\';
NET_NAME
'PVDDCR_CPU1_P0_EN_R'
 '@T6G_MB_LIB.T6G(SCH_1):PVDDCR_CPU1_P0_EN_R':
 C_SIGNAL='@t6g_mb_lib.t6g(sch_1):pvddcr_cpu1_p0_en_r';
NODE_NAME     C8069 1
 '@T6G_MB_LIB.T6G(SCH_1):PAGE175_I86@PURE_QUANTA.Q_CAP(CHIPS)':
 'A': CDS_PINID='A';
NODE_NAME     R8058 2
 '@T6G_MB_LIB.T6G(SCH_1):PAGE175_I88@PURE_QUANTA.Q_RES(CHIPS)':
 'B': CDS_PINID='B';
NODE_NAME     PU12 17
 '@T6G_MB_LIB.T6G(SCH_1):PAGE175_I128@PURE_QUANTA.RAA229620GNPHA0(CHIPS)':
 'EN0': CDS_PINID='EN0';
NET_NAME
'PVDDCR_CPU1_P0_IMON1'
 '@T6G_MB_LIB.T6G(SCH_1):PVDDCR_CPU1_P0_IMON1':
 C_SIGNAL='@t6g_mb_lib.t6g(sch_1):pvddcr_cpu1_p0_imon1';
NODE_NAME     PU12 27
 '@T6G_MB_LIB.T6G(SCH_1):PAGE175_I128@PURE_QUANTA.RAA229620GNPHA0(CHIPS)':
 'CS11': CDS_PINID='CS11';
NODE_NAME     PU13 38
 '@T6G_MB_LIB.T6G(SCH_1):PAGE176_I35@PURE_QUANTA.ISL99390FRZTR5935(CHIPS)':
 'IOUT': CDS_PINID='IOUT';
NET_NAME
'PVDDCR_CPU1_P0_IMON2'
 '@T6G_MB_LIB.T6G(SCH_1):PVDDCR_CPU1_P0_IMON2':
 C_SIGNAL='@t6g_mb_lib.t6g(sch_1):pvddcr_cpu1_p0_imon2';
NODE_NAME     PU12 28
 '@T6G_MB_LIB.T6G(SCH_1):PAGE175_I128@PURE_QUANTA.RAA229620GNPHA0(CHIPS)':
 'CS10': CDS_PINID='CS10';
NODE_NAME     PU2 38
 '@T6G_MB_LIB.T6G(SCH_1):PAGE176_I33@PURE_QUANTA.ISL99390FRZTR5935(CHIPS)':
 'IOUT': CDS_PINID='IOUT';
NET_NAME
'PVDDCR_CPU1_P0_IMON3'
 '@T6G_MB_LIB.T6G(SCH_1):PVDDCR_CPU1_P0_IMON3':
 C_SIGNAL='@t6g_mb_lib.t6g(sch_1):pvddcr_cpu1_p0_imon3';
NODE_NAME     PU12 29
 '@T6G_MB_LIB.T6G(SCH_1):PAGE175_I128@PURE_QUANTA.RAA229620GNPHA0(CHIPS)':
 'CS9': CDS_PINID='CS9';
NODE_NAME     PU15 38
 '@T6G_MB_LIB.T6G(SCH_1):PAGE177_I23@PURE_QUANTA.ISL99390FRZTR5935(CHIPS)':
 'IOUT': CDS_PINID='IOUT';
NET_NAME
'PVDDCR_CPU1_P0_IMON4'
 '@T6G_MB_LIB.T6G(SCH_1):PVDDCR_CPU1_P0_IMON4':
 C_SIGNAL='@t6g_mb_lib.t6g(sch_1):pvddcr_cpu1_p0_imon4';
NODE_NAME     PU12 30
 '@T6G_MB_LIB.T6G(SCH_1):PAGE175_I128@PURE_QUANTA.RAA229620GNPHA0(CHIPS)':
 'CS8': CDS_PINID='CS8';
NODE_NAME     PU14 38
 '@T6G_MB_LIB.T6G(SCH_1):PAGE177_I21@PURE_QUANTA.ISL99390FRZTR5935(CHIPS)':
 'IOUT': CDS_PINID='IOUT';
NET_NAME
'PVDDCR_CPU1_P0_IMON5'
 '@T6G_MB_LIB.T6G(SCH_1):PVDDCR_CPU1_P0_IMON5':
 C_SIGNAL='@t6g_mb_lib.t6g(sch_1):pvddcr_cpu1_p0_imon5';
NODE_NAME     PU12 31
 '@T6G_MB_LIB.T6G(SCH_1):PAGE175_I128@PURE_QUANTA.RAA229620GNPHA0(CHIPS)':
 'CS7': CDS_PINID='CS7';
NODE_NAME     PU16 38
 '@T6G_MB_LIB.T6G(SCH_1):PAGE178_I22@PURE_QUANTA.ISL99390FRZTR5935(CHIPS)':
 'IOUT': CDS_PINID='IOUT';
NET_NAME
'PVDDCR_CPU1_P0_IMON6'
 '@T6G_MB_LIB.T6G(SCH_1):PVDDCR_CPU1_P0_IMON6':
 C_SIGNAL='@t6g_mb_lib.t6g(sch_1):pvddcr_cpu1_p0_imon6';
NODE_NAME     PU12 32
 '@T6G_MB_LIB.T6G(SCH_1):PAGE175_I128@PURE_QUANTA.RAA229620GNPHA0(CHIPS)':
 'CS6': CDS_PINID='CS6';
NODE_NAME     PU11 38
 '@T6G_MB_LIB.T6G(SCH_1):PAGE178_I73@PURE_QUANTA.ISL99390FRZTR5935(CHIPS)':
 'IOUT': CDS_PINID='IOUT';
NET_NAME
'PVDDCR_CPU1_P0_LSET1'
 '@T6G_MB_LIB.T6G(SCH_1):PVDDCR_CPU1_P0_LSET1':
 C_SIGNAL='@t6g_mb_lib.t6g(sch_1):pvddcr_cpu1_p0_lset1';
NODE_NAME     PR78 1
 '@T6G_MB_LIB.T6G(SCH_1):PAGE176_I18@PURE_QUANTA.Q_RES(CHIPS)':
 'A': CDS_PINID='A';
NODE_NAME     PU13 37
 '@T6G_MB_LIB.T6G(SCH_1):PAGE176_I35@PURE_QUANTA.ISL99390FRZTR5935(CHIPS)':
 'LSET': CDS_PINID='LSET';
NET_NAME
'PVDDCR_CPU1_P0_LSET2'
 '@T6G_MB_LIB.T6G(SCH_1):PVDDCR_CPU1_P0_LSET2':
 C_SIGNAL='@t6g_mb_lib.t6g(sch_1):pvddcr_cpu1_p0_lset2';
NODE_NAME     PR77 1
 '@T6G_MB_LIB.T6G(SCH_1):PAGE176_I4@PURE_QUANTA.Q_RES(CHIPS)':
 'A': CDS_PINID='A';
NODE_NAME     PU2 37
 '@T6G_MB_LIB.T6G(SCH_1):PAGE176_I33@PURE_QUANTA.ISL99390FRZTR5935(CHIPS)':
 'LSET': CDS_PINID='LSET';
NET_NAME
'PVDDCR_CPU1_P0_LSET3'
 '@T6G_MB_LIB.T6G(SCH_1):PVDDCR_CPU1_P0_LSET3':
 C_SIGNAL='@t6g_mb_lib.t6g(sch_1):pvddcr_cpu1_p0_lset3';
NODE_NAME     PR86 1
 '@T6G_MB_LIB.T6G(SCH_1):PAGE177_I18@PURE_QUANTA.Q_RES(CHIPS)':
 'A': CDS_PINID='A';
NODE_NAME     PU15 37
 '@T6G_MB_LIB.T6G(SCH_1):PAGE177_I23@PURE_QUANTA.ISL99390FRZTR5935(CHIPS)':
 'LSET': CDS_PINID='LSET';
NET_NAME
'PVDDCR_CPU1_P0_LSET4'
 '@T6G_MB_LIB.T6G(SCH_1):PVDDCR_CPU1_P0_LSET4':
 C_SIGNAL='@t6g_mb_lib.t6g(sch_1):pvddcr_cpu1_p0_lset4';
NODE_NAME     PR85 1
 '@T6G_MB_LIB.T6G(SCH_1):PAGE177_I4@PURE_QUANTA.Q_RES(CHIPS)':
 'A': CDS_PINID='A';
NODE_NAME     PU14 37
 '@T6G_MB_LIB.T6G(SCH_1):PAGE177_I21@PURE_QUANTA.ISL99390FRZTR5935(CHIPS)':
 'LSET': CDS_PINID='LSET';
NET_NAME
'PVDDCR_CPU1_P0_LSET5'
 '@T6G_MB_LIB.T6G(SCH_1):PVDDCR_CPU1_P0_LSET5':
 C_SIGNAL='@t6g_mb_lib.t6g(sch_1):pvddcr_cpu1_p0_lset5';
NODE_NAME     PR93 1
 '@T6G_MB_LIB.T6G(SCH_1):PAGE178_I15@PURE_QUANTA.Q_RES(CHIPS)':
 'A': CDS_PINID='A';
NODE_NAME     PU16 37
 '@T6G_MB_LIB.T6G(SCH_1):PAGE178_I22@PURE_QUANTA.ISL99390FRZTR5935(CHIPS)':
 'LSET': CDS_PINID='LSET';
NET_NAME
'PVDDCR_CPU1_P0_LSET6'
 '@T6G_MB_LIB.T6G(SCH_1):PVDDCR_CPU1_P0_LSET6':
 C_SIGNAL='@t6g_mb_lib.t6g(sch_1):pvddcr_cpu1_p0_lset6';
NODE_NAME     PR7 1
 '@T6G_MB_LIB.T6G(SCH_1):PAGE178_I4@PURE_QUANTA.Q_RES(CHIPS)':
 'A': CDS_PINID='A';
NODE_NAME     PU11 37
 '@T6G_MB_LIB.T6G(SCH_1):PAGE178_I73@PURE_QUANTA.ISL99390FRZTR5935(CHIPS)':
 'LSET': CDS_PINID='LSET';
NET_NAME
'PVDDCR_CPU1_P0_OCP_N'
 '@T6G_MB_LIB.T6G(SCH_1):PVDDCR_CPU1_P0_OCP_N':
 C_SIGNAL='@t6g_mb_lib.t6g(sch_1):pvddcr_cpu1_p0_ocp_n';
NODE_NAME     R137 1
 '@T6G_MB_LIB.T6G(SCH_1):PAGE81_I59@PURE_QUANTA.Q_RES(CHIPS)':
 'A': CDS_PINID='A';
NODE_NAME     R8064 1
 '@T6G_MB_LIB.T6G(SCH_1):PAGE175_I66@PURE_QUANTA.Q_RES(CHIPS)':
 'A': CDS_PINID='A';
NET_NAME
'PVDDCR_CPU1_P0_OCP_N_R'
 '@T6G_MB_LIB.T6G(SCH_1):PVDDCR_CPU1_P0_OCP_N_R':
 C_SIGNAL='@t6g_mb_lib.t6g(sch_1):pvddcr_cpu1_p0_ocp_n_r';
NODE_NAME     R8064 2
 '@T6G_MB_LIB.T6G(SCH_1):PAGE175_I66@PURE_QUANTA.Q_RES(CHIPS)':
 'B': CDS_PINID='B';
NODE_NAME     R8075 2
 '@T6G_MB_LIB.T6G(SCH_1):PAGE175_I71@PURE_QUANTA.Q_RES(CHIPS)':
 'B': CDS_PINID='B';
NODE_NAME     PU12 41
 '@T6G_MB_LIB.T6G(SCH_1):PAGE175_I128@PURE_QUANTA.RAA229620GNPHA0(CHIPS)':
 'OCP_L': CDS_PINID='OCP_L';
NET_NAME
'PVDDCR_CPU1_P0_PVCC'
 '@T6G_MB_LIB.T6G(SCH_1):PVDDCR_CPU1_P0_PVCC':
 C_SIGNAL='@t6g_mb_lib.t6g(sch_1):pvddcr_cpu1_p0_pvcc',
 CDS_GLOBAL_NET='TRUE';
NODE_NAME     PR442 1
 '@T6G_MB_LIB.T6G(SCH_1):PAGE176_I21@PURE_QUANTA.Q_RES(CHIPS)':
 'A': CDS_PINID='A';
NODE_NAME     PR88 1
 '@T6G_MB_LIB.T6G(SCH_1):PAGE177_I30@PURE_QUANTA.Q_RES(CHIPS)':
 'A': CDS_PINID='A';
NODE_NAME     PC133_C1P0_5 1
 '@T6G_MB_LIB.T6G(SCH_1):PAGE178_I31@PURE_QUANTA.Q_CAP(CHIPS)':
 'A': CDS_PINID='A';
NODE_NAME     PR108 1
 '@T6G_MB_LIB.T6G(SCH_1):PAGE181_I28@PURE_QUANTA.Q_RES(CHIPS)':
 'A': CDS_PINID='A';
NODE_NAME     PR80 1
 '@T6G_MB_LIB.T6G(SCH_1):PAGE176_I13@PURE_QUANTA.Q_RES(CHIPS)':
 'A': CDS_PINID='A';
NODE_NAME     PC82_C1P0_2 1
 '@T6G_MB_LIB.T6G(SCH_1):PAGE176_I15@PURE_QUANTA.Q_CAP(CHIPS)':
 'A': CDS_PINID='A';
NODE_NAME     PR443 1
 '@T6G_MB_LIB.T6G(SCH_1):PAGE176_I27@PURE_QUANTA.Q_RES(CHIPS)':
 'A': CDS_PINID='A';
NODE_NAME     PR79 1
 '@T6G_MB_LIB.T6G(SCH_1):PAGE176_I29@PURE_QUANTA.Q_RES(CHIPS)':
 'A': CDS_PINID='A';
NODE_NAME     PC81_C1P0_1 1
 '@T6G_MB_LIB.T6G(SCH_1):PAGE176_I30@PURE_QUANTA.Q_CAP(CHIPS)':
 'A': CDS_PINID='A';
NODE_NAME     PU2 4
 '@T6G_MB_LIB.T6G(SCH_1):PAGE176_I33@PURE_QUANTA.ISL99390FRZTR5935(CHIPS)':
 'PVCC': CDS_PINID='PVCC';
NODE_NAME     PU13 4
 '@T6G_MB_LIB.T6G(SCH_1):PAGE176_I35@PURE_QUANTA.ISL99390FRZTR5935(CHIPS)':
 'PVCC': CDS_PINID='PVCC';
NODE_NAME     PR87 1
 '@T6G_MB_LIB.T6G(SCH_1):PAGE177_I13@PURE_QUANTA.Q_RES(CHIPS)':
 'A': CDS_PINID='A';
NODE_NAME     PC111_C1P0_4 1
 '@T6G_MB_LIB.T6G(SCH_1):PAGE177_I16@PURE_QUANTA.Q_CAP(CHIPS)':
 'A': CDS_PINID='A';
NODE_NAME     PU14 4
 '@T6G_MB_LIB.T6G(SCH_1):PAGE177_I21@PURE_QUANTA.ISL99390FRZTR5935(CHIPS)':
 'PVCC': CDS_PINID='PVCC';
NODE_NAME     PU15 4
 '@T6G_MB_LIB.T6G(SCH_1):PAGE177_I23@PURE_QUANTA.ISL99390FRZTR5935(CHIPS)':
 'PVCC': CDS_PINID='PVCC';
NODE_NAME     PC112_C1P0_3 1
 '@T6G_MB_LIB.T6G(SCH_1):PAGE177_I32@PURE_QUANTA.Q_CAP(CHIPS)':
 'A': CDS_PINID='A';
NODE_NAME     PR416 1
 '@T6G_MB_LIB.T6G(SCH_1):PAGE178_I13@PURE_QUANTA.Q_RES(CHIPS)':
 'A': CDS_PINID='A';
NODE_NAME     PC113_C1P0_6 1
 '@T6G_MB_LIB.T6G(SCH_1):PAGE178_I20@PURE_QUANTA.Q_CAP(CHIPS)':
 'A': CDS_PINID='A';
NODE_NAME     PU16 4
 '@T6G_MB_LIB.T6G(SCH_1):PAGE178_I22@PURE_QUANTA.ISL99390FRZTR5935(CHIPS)':
 'PVCC': CDS_PINID='PVCC';
NODE_NAME     PR94 1
 '@T6G_MB_LIB.T6G(SCH_1):PAGE178_I28@PURE_QUANTA.Q_RES(CHIPS)':
 'A': CDS_PINID='A';
NODE_NAME     PU11 4
 '@T6G_MB_LIB.T6G(SCH_1):PAGE178_I73@PURE_QUANTA.ISL99390FRZTR5935(CHIPS)':
 'PVCC': CDS_PINID='PVCC';
NODE_NAME     PR99 1
 '@T6G_MB_LIB.T6G(SCH_1):PAGE180_I12@PURE_QUANTA.Q_RES(CHIPS)':
 'A': CDS_PINID='A';
NODE_NAME     PC144_IOP0_2 1
 '@T6G_MB_LIB.T6G(SCH_1):PAGE180_I13@PURE_QUANTA.Q_CAP(CHIPS)':
 'A': CDS_PINID='A';
NODE_NAME     PU18 4
 '@T6G_MB_LIB.T6G(SCH_1):PAGE180_I15@PURE_QUANTA.ISL99390FRZTR5935(CHIPS)':
 'PVCC': CDS_PINID='PVCC';
NODE_NAME     PR100 1
 '@T6G_MB_LIB.T6G(SCH_1):PAGE180_I29@PURE_QUANTA.Q_RES(CHIPS)':
 'A': CDS_PINID='A';
NODE_NAME     PC147_IOP0_1 1
 '@T6G_MB_LIB.T6G(SCH_1):PAGE180_I31@PURE_QUANTA.Q_CAP(CHIPS)':
 'A': CDS_PINID='A';
NODE_NAME     PU17 4
 '@T6G_MB_LIB.T6G(SCH_1):PAGE180_I84@PURE_QUANTA.ISL99390FRZTR5935(CHIPS)':
 'PVCC': CDS_PINID='PVCC';
NODE_NAME     PR107 1
 '@T6G_MB_LIB.T6G(SCH_1):PAGE181_I12@PURE_QUANTA.Q_RES(CHIPS)':
 'A': CDS_PINID='A';
NODE_NAME     PC173_IOP0_4 1
 '@T6G_MB_LIB.T6G(SCH_1):PAGE181_I13@PURE_QUANTA.Q_CAP(CHIPS)':
 'A': CDS_PINID='A';
NODE_NAME     PC174_IOP0_3 1
 '@T6G_MB_LIB.T6G(SCH_1):PAGE181_I30@PURE_QUANTA.Q_CAP(CHIPS)':
 'A': CDS_PINID='A';
NODE_NAME     PU19 4
 '@T6G_MB_LIB.T6G(SCH_1):PAGE181_I32@PURE_QUANTA.ISL99390FRZTR5935(CHIPS)':
 'PVCC': CDS_PINID='PVCC';
NODE_NAME     PU20 4
 '@T6G_MB_LIB.T6G(SCH_1):PAGE181_I73@PURE_QUANTA.ISL99390FRZTR5935(CHIPS)':
 'PVCC': CDS_PINID='PVCC';
NET_NAME
'PVDDCR_CPU1_P0_PWM1'
 '@T6G_MB_LIB.T6G(SCH_1):PVDDCR_CPU1_P0_PWM1':
 C_SIGNAL='@t6g_mb_lib.t6g(sch_1):pvddcr_cpu1_p0_pwm1';
NODE_NAME     PU12 12
 '@T6G_MB_LIB.T6G(SCH_1):PAGE175_I128@PURE_QUANTA.RAA229620GNPHA0(CHIPS)':
 'PWM11': CDS_PINID='PWM11';
NODE_NAME     PU13 34
 '@T6G_MB_LIB.T6G(SCH_1):PAGE176_I35@PURE_QUANTA.ISL99390FRZTR5935(CHIPS)':
 'PWM': CDS_PINID='PWM';
NET_NAME
'PVDDCR_CPU1_P0_PWM2'
 '@T6G_MB_LIB.T6G(SCH_1):PVDDCR_CPU1_P0_PWM2':
 C_SIGNAL='@t6g_mb_lib.t6g(sch_1):pvddcr_cpu1_p0_pwm2';
NODE_NAME     PU12 11
 '@T6G_MB_LIB.T6G(SCH_1):PAGE175_I128@PURE_QUANTA.RAA229620GNPHA0(CHIPS)':
 'PWM10': CDS_PINID='PWM10';
NODE_NAME     PU2 34
 '@T6G_MB_LIB.T6G(SCH_1):PAGE176_I33@PURE_QUANTA.ISL99390FRZTR5935(CHIPS)':
 'PWM': CDS_PINID='PWM';
NET_NAME
'PVDDCR_CPU1_P0_PWM3'
 '@T6G_MB_LIB.T6G(SCH_1):PVDDCR_CPU1_P0_PWM3':
 C_SIGNAL='@t6g_mb_lib.t6g(sch_1):pvddcr_cpu1_p0_pwm3';
NODE_NAME     PU12 10
 '@T6G_MB_LIB.T6G(SCH_1):PAGE175_I128@PURE_QUANTA.RAA229620GNPHA0(CHIPS)':
 'PWM9': CDS_PINID='PWM9';
NODE_NAME     PU15 34
 '@T6G_MB_LIB.T6G(SCH_1):PAGE177_I23@PURE_QUANTA.ISL99390FRZTR5935(CHIPS)':
 'PWM': CDS_PINID='PWM';
NET_NAME
'PVDDCR_CPU1_P0_PWM4'
 '@T6G_MB_LIB.T6G(SCH_1):PVDDCR_CPU1_P0_PWM4':
 C_SIGNAL='@t6g_mb_lib.t6g(sch_1):pvddcr_cpu1_p0_pwm4';
NODE_NAME     PU12 9
 '@T6G_MB_LIB.T6G(SCH_1):PAGE175_I128@PURE_QUANTA.RAA229620GNPHA0(CHIPS)':
 'PWM8': CDS_PINID='PWM8';
NODE_NAME     PU14 34
 '@T6G_MB_LIB.T6G(SCH_1):PAGE177_I21@PURE_QUANTA.ISL99390FRZTR5935(CHIPS)':
 'PWM': CDS_PINID='PWM';
NET_NAME
'PVDDCR_CPU1_P0_PWM5'
 '@T6G_MB_LIB.T6G(SCH_1):PVDDCR_CPU1_P0_PWM5':
 C_SIGNAL='@t6g_mb_lib.t6g(sch_1):pvddcr_cpu1_p0_pwm5';
NODE_NAME     PU12 8
 '@T6G_MB_LIB.T6G(SCH_1):PAGE175_I128@PURE_QUANTA.RAA229620GNPHA0(CHIPS)':
 'PWM7': CDS_PINID='PWM7';
NODE_NAME     PU16 34
 '@T6G_MB_LIB.T6G(SCH_1):PAGE178_I22@PURE_QUANTA.ISL99390FRZTR5935(CHIPS)':
 'PWM': CDS_PINID='PWM';
NET_NAME
'PVDDCR_CPU1_P0_PWM6'
 '@T6G_MB_LIB.T6G(SCH_1):PVDDCR_CPU1_P0_PWM6':
 C_SIGNAL='@t6g_mb_lib.t6g(sch_1):pvddcr_cpu1_p0_pwm6';
NODE_NAME     PU12 7
 '@T6G_MB_LIB.T6G(SCH_1):PAGE175_I128@PURE_QUANTA.RAA229620GNPHA0(CHIPS)':
 'PWM6': CDS_PINID='PWM6';
NODE_NAME     PU11 34
 '@T6G_MB_LIB.T6G(SCH_1):PAGE178_I73@PURE_QUANTA.ISL99390FRZTR5935(CHIPS)':
 'PWM': CDS_PINID='PWM';
NET_NAME
'PVDDCR_CPU1_P0_RESET_N'
 '@T6G_MB_LIB.T6G(SCH_1):PVDDCR_CPU1_P0_RESET_N':
 C_SIGNAL='@t6g_mb_lib.t6g(sch_1):pvddcr_cpu1_p0_reset_n';
NODE_NAME     U29 4
 '@T6G_MB_LIB.T6G(SCH_1):PAGE77_I15@PURE_QUANTA.SN74LVC2G07DCKR(CHIPS)':
 '2Y': CDS_PINID='\2y\';
NODE_NAME     R8063 1
 '@T6G_MB_LIB.T6G(SCH_1):PAGE175_I67@PURE_QUANTA.Q_RES(CHIPS)':
 'A': CDS_PINID='A';
NET_NAME
'PVDDCR_CPU1_P0_RESET_N_R'
 '@T6G_MB_LIB.T6G(SCH_1):PVDDCR_CPU1_P0_RESET_N_R':
 C_SIGNAL='@t6g_mb_lib.t6g(sch_1):pvddcr_cpu1_p0_reset_n_r';
NODE_NAME     R8063 2
 '@T6G_MB_LIB.T6G(SCH_1):PAGE175_I67@PURE_QUANTA.Q_RES(CHIPS)':
 'B': CDS_PINID='B';
NODE_NAME     R8070 2
 '@T6G_MB_LIB.T6G(SCH_1):PAGE175_I68@PURE_QUANTA.Q_RES(CHIPS)':
 'B': CDS_PINID='B';
NODE_NAME     PU12 18
 '@T6G_MB_LIB.T6G(SCH_1):PAGE175_I128@PURE_QUANTA.RAA229620GNPHA0(CHIPS)':
 'RESET_L': CDS_PINID='RESET_L';
NET_NAME
'PVDDCR_CPU1_P0_SMB_ALERT'
 '@T6G_MB_LIB.T6G(SCH_1):PVDDCR_CPU1_P0_SMB_ALERT':
 C_SIGNAL='@t6g_mb_lib.t6g(sch_1):pvddcr_cpu1_p0_smb_alert';
NODE_NAME     R1186 1
 '@T6G_MB_LIB.T6G(SCH_1):PAGE82_I60@PURE_QUANTA.Q_RES(CHIPS)':
 'A': CDS_PINID='A';
NODE_NAME     U18 L5
 '@T6G_MB_LIB.T6G(SCH_1):PAGE81_I143@PURE_QUANTA.LCMXO3LF9400C5BG484C(CHIPS)':
 'PL14D': CDS_PINID='PL14D';
NODE_NAME     R8073 1
 '@T6G_MB_LIB.T6G(SCH_1):PAGE175_I81@PURE_QUANTA.Q_RES(CHIPS)':
 'A': CDS_PINID='A';
NODE_NAME     C5013 1
 '@T6G_MB_LIB.T6G(SCH_1):PAGE175_I130@PURE_QUANTA.Q_CAP(CHIPS)':
 'A': CDS_PINID='A';
NET_NAME
'PVDDCR_CPU1_P0_SMB_ALERT_R'
 '@T6G_MB_LIB.T6G(SCH_1):PVDDCR_CPU1_P0_SMB_ALERT_R':
 C_SIGNAL='@t6g_mb_lib.t6g(sch_1):pvddcr_cpu1_p0_smb_alert_r';
NODE_NAME     R8073 2
 '@T6G_MB_LIB.T6G(SCH_1):PAGE175_I81@PURE_QUANTA.Q_RES(CHIPS)':
 'B': CDS_PINID='B';
NODE_NAME     PU12 15
 '@T6G_MB_LIB.T6G(SCH_1):PAGE175_I128@PURE_QUANTA.RAA229620GNPHA0(CHIPS)':
 'NPMALERT': CDS_PINID='NPMALERT';
NET_NAME
'PVDDCR_CPU1_P0_TEMP0'
 '@T6G_MB_LIB.T6G(SCH_1):PVDDCR_CPU1_P0_TEMP0':
 C_SIGNAL='@t6g_mb_lib.t6g(sch_1):pvddcr_cpu1_p0_temp0';
NODE_NAME     PC78 1
 '@T6G_MB_LIB.T6G(SCH_1):PAGE175_I73@PURE_QUANTA.Q_CAP(CHIPS)':
 'A': CDS_PINID='A';
NODE_NAME     PU12 44
 '@T6G_MB_LIB.T6G(SCH_1):PAGE175_I128@PURE_QUANTA.RAA229620GNPHA0(CHIPS)':
 'TEMP0': CDS_PINID='TEMP0';
NODE_NAME     PU2 36
 '@T6G_MB_LIB.T6G(SCH_1):PAGE176_I33@PURE_QUANTA.ISL99390FRZTR5935(CHIPS)':
 'TOUT_FLT': CDS_PINID='TOUT_FLT';
NODE_NAME     PU13 36
 '@T6G_MB_LIB.T6G(SCH_1):PAGE176_I35@PURE_QUANTA.ISL99390FRZTR5935(CHIPS)':
 'TOUT_FLT': CDS_PINID='TOUT_FLT';
NODE_NAME     PU14 36
 '@T6G_MB_LIB.T6G(SCH_1):PAGE177_I21@PURE_QUANTA.ISL99390FRZTR5935(CHIPS)':
 'TOUT_FLT': CDS_PINID='TOUT_FLT';
NODE_NAME     PU15 36
 '@T6G_MB_LIB.T6G(SCH_1):PAGE177_I23@PURE_QUANTA.ISL99390FRZTR5935(CHIPS)':
 'TOUT_FLT': CDS_PINID='TOUT_FLT';
NODE_NAME     PU16 36
 '@T6G_MB_LIB.T6G(SCH_1):PAGE178_I22@PURE_QUANTA.ISL99390FRZTR5935(CHIPS)':
 'TOUT_FLT': CDS_PINID='TOUT_FLT';
NODE_NAME     PU11 36
 '@T6G_MB_LIB.T6G(SCH_1):PAGE178_I73@PURE_QUANTA.ISL99390FRZTR5935(CHIPS)':
 'TOUT_FLT': CDS_PINID='TOUT_FLT';
NET_NAME
'PVDDCR_CPU1_P0_VCC'
 '@T6G_MB_LIB.T6G(SCH_1):PVDDCR_CPU1_P0_VCC':
 C_SIGNAL='@t6g_mb_lib.t6g(sch_1):pvddcr_cpu1_p0_vcc';
NODE_NAME     PC14 1
 '@T6G_MB_LIB.T6G(SCH_1):PAGE175_I96@PURE_QUANTA.Q_CAP(CHIPS)':
 'A': CDS_PINID='A';
NODE_NAME     PC75 1
 '@T6G_MB_LIB.T6G(SCH_1):PAGE175_I100@PURE_QUANTA.Q_CAP(CHIPS)':
 'A': CDS_PINID='A';
NODE_NAME     PR76 1
 '@T6G_MB_LIB.T6G(SCH_1):PAGE175_I126@PURE_QUANTA.Q_RES(CHIPS)':
 'A': CDS_PINID='A';
NODE_NAME     PU12 47
 '@T6G_MB_LIB.T6G(SCH_1):PAGE175_I128@PURE_QUANTA.RAA229620GNPHA0(CHIPS)':
 'VCC': CDS_PINID='VCC';
NET_NAME
'PVDDCR_CPU1_P0_VCC1'
 '@T6G_MB_LIB.T6G(SCH_1):PVDDCR_CPU1_P0_VCC1':
 C_SIGNAL='@t6g_mb_lib.t6g(sch_1):pvddcr_cpu1_p0_vcc1';
NODE_NAME     PC79 1
 '@T6G_MB_LIB.T6G(SCH_1):PAGE176_I24@PURE_QUANTA.Q_CAP(CHIPS)':
 'A': CDS_PINID='A';
NODE_NAME     PR79 2
 '@T6G_MB_LIB.T6G(SCH_1):PAGE176_I29@PURE_QUANTA.Q_RES(CHIPS)':
 'B': CDS_PINID='B';
NODE_NAME     PU13 35
 '@T6G_MB_LIB.T6G(SCH_1):PAGE176_I35@PURE_QUANTA.ISL99390FRZTR5935(CHIPS)':
 'EN': CDS_PINID='EN';
NODE_NAME     PU13 3
 '@T6G_MB_LIB.T6G(SCH_1):PAGE176_I35@PURE_QUANTA.ISL99390FRZTR5935(CHIPS)':
 'VCC': CDS_PINID='VCC';
NET_NAME
'PVDDCR_CPU1_P0_VCC2'
 '@T6G_MB_LIB.T6G(SCH_1):PVDDCR_CPU1_P0_VCC2':
 C_SIGNAL='@t6g_mb_lib.t6g(sch_1):pvddcr_cpu1_p0_vcc2';
NODE_NAME     PC80 1
 '@T6G_MB_LIB.T6G(SCH_1):PAGE176_I10@PURE_QUANTA.Q_CAP(CHIPS)':
 'A': CDS_PINID='A';
NODE_NAME     PR80 2
 '@T6G_MB_LIB.T6G(SCH_1):PAGE176_I13@PURE_QUANTA.Q_RES(CHIPS)':
 'B': CDS_PINID='B';
NODE_NAME     PU2 35
 '@T6G_MB_LIB.T6G(SCH_1):PAGE176_I33@PURE_QUANTA.ISL99390FRZTR5935(CHIPS)':
 'EN': CDS_PINID='EN';
NODE_NAME     PU2 3
 '@T6G_MB_LIB.T6G(SCH_1):PAGE176_I33@PURE_QUANTA.ISL99390FRZTR5935(CHIPS)':
 'VCC': CDS_PINID='VCC';
NET_NAME
'PVDDCR_CPU1_P0_VCC3'
 '@T6G_MB_LIB.T6G(SCH_1):PVDDCR_CPU1_P0_VCC3':
 C_SIGNAL='@t6g_mb_lib.t6g(sch_1):pvddcr_cpu1_p0_vcc3';
NODE_NAME     PR88 2
 '@T6G_MB_LIB.T6G(SCH_1):PAGE177_I30@PURE_QUANTA.Q_RES(CHIPS)':
 'B': CDS_PINID='B';
NODE_NAME     PU15 35
 '@T6G_MB_LIB.T6G(SCH_1):PAGE177_I23@PURE_QUANTA.ISL99390FRZTR5935(CHIPS)':
 'EN': CDS_PINID='EN';
NODE_NAME     PU15 3
 '@T6G_MB_LIB.T6G(SCH_1):PAGE177_I23@PURE_QUANTA.ISL99390FRZTR5935(CHIPS)':
 'VCC': CDS_PINID='VCC';
NODE_NAME     PC110 1
 '@T6G_MB_LIB.T6G(SCH_1):PAGE177_I28@PURE_QUANTA.Q_CAP(CHIPS)':
 'A': CDS_PINID='A';
NET_NAME
'PVDDCR_CPU1_P0_VCC4'
 '@T6G_MB_LIB.T6G(SCH_1):PVDDCR_CPU1_P0_VCC4':
 C_SIGNAL='@t6g_mb_lib.t6g(sch_1):pvddcr_cpu1_p0_vcc4';
NODE_NAME     PC109 1
 '@T6G_MB_LIB.T6G(SCH_1):PAGE177_I7@PURE_QUANTA.Q_CAP(CHIPS)':
 'A': CDS_PINID='A';
NODE_NAME     PR87 2
 '@T6G_MB_LIB.T6G(SCH_1):PAGE177_I13@PURE_QUANTA.Q_RES(CHIPS)':
 'B': CDS_PINID='B';
NODE_NAME     PU14 35
 '@T6G_MB_LIB.T6G(SCH_1):PAGE177_I21@PURE_QUANTA.ISL99390FRZTR5935(CHIPS)':
 'EN': CDS_PINID='EN';
NODE_NAME     PU14 3
 '@T6G_MB_LIB.T6G(SCH_1):PAGE177_I21@PURE_QUANTA.ISL99390FRZTR5935(CHIPS)':
 'VCC': CDS_PINID='VCC';
NET_NAME
'PVDDCR_CPU1_P0_VCC5'
 '@T6G_MB_LIB.T6G(SCH_1):PVDDCR_CPU1_P0_VCC5':
 C_SIGNAL='@t6g_mb_lib.t6g(sch_1):pvddcr_cpu1_p0_vcc5';
NODE_NAME     PU16 35
 '@T6G_MB_LIB.T6G(SCH_1):PAGE178_I22@PURE_QUANTA.ISL99390FRZTR5935(CHIPS)':
 'EN': CDS_PINID='EN';
NODE_NAME     PU16 3
 '@T6G_MB_LIB.T6G(SCH_1):PAGE178_I22@PURE_QUANTA.ISL99390FRZTR5935(CHIPS)':
 'VCC': CDS_PINID='VCC';
NODE_NAME     PC131 1
 '@T6G_MB_LIB.T6G(SCH_1):PAGE178_I27@PURE_QUANTA.Q_CAP(CHIPS)':
 'A': CDS_PINID='A';
NODE_NAME     PR94 2
 '@T6G_MB_LIB.T6G(SCH_1):PAGE178_I28@PURE_QUANTA.Q_RES(CHIPS)':
 'B': CDS_PINID='B';
NET_NAME
'PVDDCR_CPU1_P0_VCC6'
 '@T6G_MB_LIB.T6G(SCH_1):PVDDCR_CPU1_P0_VCC6':
 C_SIGNAL='@t6g_mb_lib.t6g(sch_1):pvddcr_cpu1_p0_vcc6';
NODE_NAME     PC112 1
 '@T6G_MB_LIB.T6G(SCH_1):PAGE178_I11@PURE_QUANTA.Q_CAP(CHIPS)':
 'A': CDS_PINID='A';
NODE_NAME     PR416 2
 '@T6G_MB_LIB.T6G(SCH_1):PAGE178_I13@PURE_QUANTA.Q_RES(CHIPS)':
 'B': CDS_PINID='B';
NODE_NAME     PU11 35
 '@T6G_MB_LIB.T6G(SCH_1):PAGE178_I73@PURE_QUANTA.ISL99390FRZTR5935(CHIPS)':
 'EN': CDS_PINID='EN';
NODE_NAME     PU11 3
 '@T6G_MB_LIB.T6G(SCH_1):PAGE178_I73@PURE_QUANTA.ISL99390FRZTR5935(CHIPS)':
 'VCC': CDS_PINID='VCC';
NET_NAME
'PVDDCR_CPU1_P0_VCCS'
 '@T6G_MB_LIB.T6G(SCH_1):PVDDCR_CPU1_P0_VCCS':
 C_SIGNAL='@t6g_mb_lib.t6g(sch_1):pvddcr_cpu1_p0_vccs';
NODE_NAME     PC83_2 1
 '@T6G_MB_LIB.T6G(SCH_1):PAGE176_I2@PURE_QUANTA.Q_CAP(CHIPS)':
 'A': CDS_PINID='A';
NODE_NAME     PC113_4 1
 '@T6G_MB_LIB.T6G(SCH_1):PAGE177_I2@PURE_QUANTA.Q_CAP(CHIPS)':
 'A': CDS_PINID='A';
NODE_NAME     PC15 1
 '@T6G_MB_LIB.T6G(SCH_1):PAGE175_I94@PURE_QUANTA.Q_CAP(CHIPS)':
 'A': CDS_PINID='A';
NODE_NAME     PC76 1
 '@T6G_MB_LIB.T6G(SCH_1):PAGE175_I98@PURE_QUANTA.Q_CAP(CHIPS)':
 'A': CDS_PINID='A';
NODE_NAME     PU12 48
 '@T6G_MB_LIB.T6G(SCH_1):PAGE175_I128@PURE_QUANTA.RAA229620GNPHA0(CHIPS)':
 'VCCS': CDS_PINID='VCCS';
NODE_NAME     PC84_1 1
 '@T6G_MB_LIB.T6G(SCH_1):PAGE176_I12@PURE_QUANTA.Q_CAP(CHIPS)':
 'A': CDS_PINID='A';
NODE_NAME     PU2 39
 '@T6G_MB_LIB.T6G(SCH_1):PAGE176_I33@PURE_QUANTA.ISL99390FRZTR5935(CHIPS)':
 'REFIN': CDS_PINID='REFIN';
NODE_NAME     PU13 39
 '@T6G_MB_LIB.T6G(SCH_1):PAGE176_I35@PURE_QUANTA.ISL99390FRZTR5935(CHIPS)':
 'REFIN': CDS_PINID='REFIN';
NODE_NAME     PC114_3 1
 '@T6G_MB_LIB.T6G(SCH_1):PAGE177_I12@PURE_QUANTA.Q_CAP(CHIPS)':
 'A': CDS_PINID='A';
NODE_NAME     PU14 39
 '@T6G_MB_LIB.T6G(SCH_1):PAGE177_I21@PURE_QUANTA.ISL99390FRZTR5935(CHIPS)':
 'REFIN': CDS_PINID='REFIN';
NODE_NAME     PU15 39
 '@T6G_MB_LIB.T6G(SCH_1):PAGE177_I23@PURE_QUANTA.ISL99390FRZTR5935(CHIPS)':
 'REFIN': CDS_PINID='REFIN';
NODE_NAME     PC111_6 1
 '@T6G_MB_LIB.T6G(SCH_1):PAGE178_I2@PURE_QUANTA.Q_CAP(CHIPS)':
 'A': CDS_PINID='A';
NODE_NAME     PC132_5 1
 '@T6G_MB_LIB.T6G(SCH_1):PAGE178_I10@PURE_QUANTA.Q_CAP(CHIPS)':
 'A': CDS_PINID='A';
NODE_NAME     PU16 39
 '@T6G_MB_LIB.T6G(SCH_1):PAGE178_I22@PURE_QUANTA.ISL99390FRZTR5935(CHIPS)':
 'REFIN': CDS_PINID='REFIN';
NODE_NAME     PU11 39
 '@T6G_MB_LIB.T6G(SCH_1):PAGE178_I73@PURE_QUANTA.ISL99390FRZTR5935(CHIPS)':
 'REFIN': CDS_PINID='REFIN';
NODE_NAME     PC146_8 1
 '@T6G_MB_LIB.T6G(SCH_1):PAGE180_I2@PURE_QUANTA.Q_CAP(CHIPS)':
 'A': CDS_PINID='A';
NODE_NAME     PU18 39
 '@T6G_MB_LIB.T6G(SCH_1):PAGE180_I15@PURE_QUANTA.ISL99390FRZTR5935(CHIPS)':
 'REFIN': CDS_PINID='REFIN';
NODE_NAME     PC145_7 1
 '@T6G_MB_LIB.T6G(SCH_1):PAGE180_I20@PURE_QUANTA.Q_CAP(CHIPS)':
 'A': CDS_PINID='A';
NODE_NAME     PU17 39
 '@T6G_MB_LIB.T6G(SCH_1):PAGE180_I84@PURE_QUANTA.ISL99390FRZTR5935(CHIPS)':
 'REFIN': CDS_PINID='REFIN';
NODE_NAME     PC176_10 1
 '@T6G_MB_LIB.T6G(SCH_1):PAGE181_I1@PURE_QUANTA.Q_CAP(CHIPS)':
 'A': CDS_PINID='A';
NODE_NAME     PC175_9 1
 '@T6G_MB_LIB.T6G(SCH_1):PAGE181_I19@PURE_QUANTA.Q_CAP(CHIPS)':
 'A': CDS_PINID='A';
NODE_NAME     PU19 39
 '@T6G_MB_LIB.T6G(SCH_1):PAGE181_I32@PURE_QUANTA.ISL99390FRZTR5935(CHIPS)':
 'REFIN': CDS_PINID='REFIN';
NODE_NAME     PU20 39
 '@T6G_MB_LIB.T6G(SCH_1):PAGE181_I73@PURE_QUANTA.ISL99390FRZTR5935(CHIPS)':
 'REFIN': CDS_PINID='REFIN';
NET_NAME
'PVDDCR_CPU1_P0_VINSEN'
 '@T6G_MB_LIB.T6G(SCH_1):PVDDCR_CPU1_P0_VINSEN':
 C_SIGNAL='@t6g_mb_lib.t6g(sch_1):pvddcr_cpu1_p0_vinsen';
NODE_NAME     PR74 2
 '@T6G_MB_LIB.T6G(SCH_1):PAGE175_I51@PURE_QUANTA.Q_RES(CHIPS)':
 'B': CDS_PINID='B';
NODE_NAME     PR600 1
 '@T6G_MB_LIB.T6G(SCH_1):PAGE175_I59@PURE_QUANTA.Q_RES(CHIPS)':
 'A': CDS_PINID='A';
NODE_NAME     PC74 1
 '@T6G_MB_LIB.T6G(SCH_1):PAGE175_I60@PURE_QUANTA.Q_CAP(CHIPS)':
 'A': CDS_PINID='A';
NODE_NAME     PU12 46
 '@T6G_MB_LIB.T6G(SCH_1):PAGE175_I128@PURE_QUANTA.RAA229620GNPHA0(CHIPS)':
 'VINSEN': CDS_PINID='VINSEN';
NET_NAME
'PVDDCR_CPU1_P0_VMON'
 '@T6G_MB_LIB.T6G(SCH_1):PVDDCR_CPU1_P0_VMON':
 C_SIGNAL='@t6g_mb_lib.t6g(sch_1):pvddcr_cpu1_p0_vmon';
NODE_NAME     PR54 1
 '@T6G_MB_LIB.T6G(SCH_1):PAGE175_I8@PURE_QUANTA.Q_RES(CHIPS)':
 'A': CDS_PINID='A';
NODE_NAME     PR53 2
 '@T6G_MB_LIB.T6G(SCH_1):PAGE175_I9@PURE_QUANTA.Q_RES(CHIPS)':
 'B': CDS_PINID='B';
NODE_NAME     PC67 1
 '@T6G_MB_LIB.T6G(SCH_1):PAGE175_I50@PURE_QUANTA.Q_CAP(CHIPS)':
 'A': CDS_PINID='A';
NODE_NAME     PU12 45
 '@T6G_MB_LIB.T6G(SCH_1):PAGE175_I128@PURE_QUANTA.RAA229620GNPHA0(CHIPS)':
 'VMON||IINSEN': CDS_PINID='\vmon||iinsen\';
NET_NAME
'PVDDCR_CPU1_P0_VOS1'
 '@T6G_MB_LIB.T6G(SCH_1):PVDDCR_CPU1_P0_VOS1':
 C_SIGNAL='@t6g_mb_lib.t6g(sch_1):pvddcr_cpu1_p0_vos1';
NODE_NAME     PU13 1
 '@T6G_MB_LIB.T6G(SCH_1):PAGE176_I35@PURE_QUANTA.ISL99390FRZTR5935(CHIPS)':
 'VOS': CDS_PINID='VOS';
NODE_NAME     PR84 1
 '@T6G_MB_LIB.T6G(SCH_1):PAGE176_I54@PURE_QUANTA.Q_RES(CHIPS)':
 'A': CDS_PINID='A';
NET_NAME
'PVDDCR_CPU1_P0_VOS2'
 '@T6G_MB_LIB.T6G(SCH_1):PVDDCR_CPU1_P0_VOS2':
 C_SIGNAL='@t6g_mb_lib.t6g(sch_1):pvddcr_cpu1_p0_vos2';
NODE_NAME     PU2 1
 '@T6G_MB_LIB.T6G(SCH_1):PAGE176_I33@PURE_QUANTA.ISL99390FRZTR5935(CHIPS)':
 'VOS': CDS_PINID='VOS';
NODE_NAME     PR83 1
 '@T6G_MB_LIB.T6G(SCH_1):PAGE176_I42@PURE_QUANTA.Q_RES(CHIPS)':
 'A': CDS_PINID='A';
NET_NAME
'PVDDCR_CPU1_P0_VOS3'
 '@T6G_MB_LIB.T6G(SCH_1):PVDDCR_CPU1_P0_VOS3':
 C_SIGNAL='@t6g_mb_lib.t6g(sch_1):pvddcr_cpu1_p0_vos3';
NODE_NAME     PR92 1
 '@T6G_MB_LIB.T6G(SCH_1):PAGE177_I51@PURE_QUANTA.Q_RES(CHIPS)':
 'A': CDS_PINID='A';
NODE_NAME     PU15 1
 '@T6G_MB_LIB.T6G(SCH_1):PAGE177_I23@PURE_QUANTA.ISL99390FRZTR5935(CHIPS)':
 'VOS': CDS_PINID='VOS';
NET_NAME
'PVDDCR_CPU1_P0_VOS4'
 '@T6G_MB_LIB.T6G(SCH_1):PVDDCR_CPU1_P0_VOS4':
 C_SIGNAL='@t6g_mb_lib.t6g(sch_1):pvddcr_cpu1_p0_vos4';
NODE_NAME     PR91 1
 '@T6G_MB_LIB.T6G(SCH_1):PAGE177_I40@PURE_QUANTA.Q_RES(CHIPS)':
 'A': CDS_PINID='A';
NODE_NAME     PU14 1
 '@T6G_MB_LIB.T6G(SCH_1):PAGE177_I21@PURE_QUANTA.ISL99390FRZTR5935(CHIPS)':
 'VOS': CDS_PINID='VOS';
NET_NAME
'PVDDCR_CPU1_P0_VOS5'
 '@T6G_MB_LIB.T6G(SCH_1):PVDDCR_CPU1_P0_VOS5':
 C_SIGNAL='@t6g_mb_lib.t6g(sch_1):pvddcr_cpu1_p0_vos5';
NODE_NAME     PU16 1
 '@T6G_MB_LIB.T6G(SCH_1):PAGE178_I22@PURE_QUANTA.ISL99390FRZTR5935(CHIPS)':
 'VOS': CDS_PINID='VOS';
NODE_NAME     PR96 1
 '@T6G_MB_LIB.T6G(SCH_1):PAGE178_I49@PURE_QUANTA.Q_RES(CHIPS)':
 'A': CDS_PINID='A';
NET_NAME
'PVDDCR_CPU1_P0_VOS6'
 '@T6G_MB_LIB.T6G(SCH_1):PVDDCR_CPU1_P0_VOS6':
 C_SIGNAL='@t6g_mb_lib.t6g(sch_1):pvddcr_cpu1_p0_vos6';
NODE_NAME     PR421 1
 '@T6G_MB_LIB.T6G(SCH_1):PAGE178_I35@PURE_QUANTA.Q_RES(CHIPS)':
 'A': CDS_PINID='A';
NODE_NAME     PU11 1
 '@T6G_MB_LIB.T6G(SCH_1):PAGE178_I73@PURE_QUANTA.ISL99390FRZTR5935(CHIPS)':
 'VOS': CDS_PINID='VOS';
NET_NAME
'PVDDCR_CPU1_P1'
 '@T6G_MB_LIB.T6G(SCH_1):PVDDCR_CPU1_P1':
 C_SIGNAL='@t6g_mb_lib.t6g(sch_1):pvddcr_cpu1_p1',
 CDS_GLOBAL_NET='TRUE';
NODE_NAME     U26 BN27
 '@T6G_MB_LIB.T6G(SCH_1):PAGE57_I32@PURE_QUANTA.GENOA_SP5(CHIPS)':
 'VDDCR_CPU1_BN27': CDS_PINID='VDDCR_CPU1_BN27';
NODE_NAME     U26 BN31
 '@T6G_MB_LIB.T6G(SCH_1):PAGE57_I32@PURE_QUANTA.GENOA_SP5(CHIPS)':
 'VDDCR_CPU1_BN31': CDS_PINID='VDDCR_CPU1_BN31';
NODE_NAME     U26 BN35
 '@T6G_MB_LIB.T6G(SCH_1):PAGE57_I32@PURE_QUANTA.GENOA_SP5(CHIPS)':
 'VDDCR_CPU1_BN35': CDS_PINID='VDDCR_CPU1_BN35';
NODE_NAME     U26 BN42
 '@T6G_MB_LIB.T6G(SCH_1):PAGE57_I32@PURE_QUANTA.GENOA_SP5(CHIPS)':
 'VDDCR_CPU1_BN42': CDS_PINID='VDDCR_CPU1_BN42';
NODE_NAME     U26 BN46
 '@T6G_MB_LIB.T6G(SCH_1):PAGE57_I32@PURE_QUANTA.GENOA_SP5(CHIPS)':
 'VDDCR_CPU1_BN46': CDS_PINID='VDDCR_CPU1_BN46';
NODE_NAME     U26 BN50
 '@T6G_MB_LIB.T6G(SCH_1):PAGE57_I32@PURE_QUANTA.GENOA_SP5(CHIPS)':
 'VDDCR_CPU1_BN50': CDS_PINID='VDDCR_CPU1_BN50';
NODE_NAME     U26 BP24
 '@T6G_MB_LIB.T6G(SCH_1):PAGE57_I32@PURE_QUANTA.GENOA_SP5(CHIPS)':
 'VDDCR_CPU1_BP24': CDS_PINID='VDDCR_CPU1_BP24';
NODE_NAME     U26 BP26
 '@T6G_MB_LIB.T6G(SCH_1):PAGE57_I32@PURE_QUANTA.GENOA_SP5(CHIPS)':
 'VDDCR_CPU1_BP26': CDS_PINID='VDDCR_CPU1_BP26';
NODE_NAME     U26 BP28
 '@T6G_MB_LIB.T6G(SCH_1):PAGE57_I32@PURE_QUANTA.GENOA_SP5(CHIPS)':
 'VDDCR_CPU1_BP28': CDS_PINID='VDDCR_CPU1_BP28';
NODE_NAME     U26 BP30
 '@T6G_MB_LIB.T6G(SCH_1):PAGE57_I32@PURE_QUANTA.GENOA_SP5(CHIPS)':
 'VDDCR_CPU1_BP30': CDS_PINID='VDDCR_CPU1_BP30';
NODE_NAME     U26 BP32
 '@T6G_MB_LIB.T6G(SCH_1):PAGE57_I32@PURE_QUANTA.GENOA_SP5(CHIPS)':
 'VDDCR_CPU1_BP32': CDS_PINID='VDDCR_CPU1_BP32';
NODE_NAME     U26 BP34
 '@T6G_MB_LIB.T6G(SCH_1):PAGE57_I32@PURE_QUANTA.GENOA_SP5(CHIPS)':
 'VDDCR_CPU1_BP34': CDS_PINID='VDDCR_CPU1_BP34';
NODE_NAME     U26 BP36
 '@T6G_MB_LIB.T6G(SCH_1):PAGE57_I32@PURE_QUANTA.GENOA_SP5(CHIPS)':
 'VDDCR_CPU1_BP36': CDS_PINID='VDDCR_CPU1_BP36';
NODE_NAME     U26 BP39
 '@T6G_MB_LIB.T6G(SCH_1):PAGE57_I32@PURE_QUANTA.GENOA_SP5(CHIPS)':
 'VDDCR_CPU1_BP39': CDS_PINID='VDDCR_CPU1_BP39';
NODE_NAME     U26 BP41
 '@T6G_MB_LIB.T6G(SCH_1):PAGE57_I32@PURE_QUANTA.GENOA_SP5(CHIPS)':
 'VDDCR_CPU1_BP41': CDS_PINID='VDDCR_CPU1_BP41';
NODE_NAME     U26 BP43
 '@T6G_MB_LIB.T6G(SCH_1):PAGE57_I32@PURE_QUANTA.GENOA_SP5(CHIPS)':
 'VDDCR_CPU1_BP43': CDS_PINID='VDDCR_CPU1_BP43';
NODE_NAME     U26 BP45
 '@T6G_MB_LIB.T6G(SCH_1):PAGE57_I32@PURE_QUANTA.GENOA_SP5(CHIPS)':
 'VDDCR_CPU1_BP45': CDS_PINID='VDDCR_CPU1_BP45';
NODE_NAME     U26 BP47
 '@T6G_MB_LIB.T6G(SCH_1):PAGE57_I32@PURE_QUANTA.GENOA_SP5(CHIPS)':
 'VDDCR_CPU1_BP47': CDS_PINID='VDDCR_CPU1_BP47';
NODE_NAME     U26 BP49
 '@T6G_MB_LIB.T6G(SCH_1):PAGE57_I32@PURE_QUANTA.GENOA_SP5(CHIPS)':
 'VDDCR_CPU1_BP49': CDS_PINID='VDDCR_CPU1_BP49';
NODE_NAME     U26 BR23
 '@T6G_MB_LIB.T6G(SCH_1):PAGE57_I32@PURE_QUANTA.GENOA_SP5(CHIPS)':
 'VDDCR_CPU1_BR23': CDS_PINID='VDDCR_CPU1_BR23';
NODE_NAME     U26 BR25
 '@T6G_MB_LIB.T6G(SCH_1):PAGE57_I32@PURE_QUANTA.GENOA_SP5(CHIPS)':
 'VDDCR_CPU1_BR25': CDS_PINID='VDDCR_CPU1_BR25';
NODE_NAME     U26 BR27
 '@T6G_MB_LIB.T6G(SCH_1):PAGE57_I32@PURE_QUANTA.GENOA_SP5(CHIPS)':
 'VDDCR_CPU1_BR27': CDS_PINID='VDDCR_CPU1_BR27';
NODE_NAME     U26 BR29
 '@T6G_MB_LIB.T6G(SCH_1):PAGE57_I32@PURE_QUANTA.GENOA_SP5(CHIPS)':
 'VDDCR_CPU1_BR29': CDS_PINID='VDDCR_CPU1_BR29';
NODE_NAME     U26 BR31
 '@T6G_MB_LIB.T6G(SCH_1):PAGE57_I32@PURE_QUANTA.GENOA_SP5(CHIPS)':
 'VDDCR_CPU1_BR31': CDS_PINID='VDDCR_CPU1_BR31';
NODE_NAME     U26 BR33
 '@T6G_MB_LIB.T6G(SCH_1):PAGE57_I32@PURE_QUANTA.GENOA_SP5(CHIPS)':
 'VDDCR_CPU1_BR33': CDS_PINID='VDDCR_CPU1_BR33';
NODE_NAME     U26 BR35
 '@T6G_MB_LIB.T6G(SCH_1):PAGE57_I32@PURE_QUANTA.GENOA_SP5(CHIPS)':
 'VDDCR_CPU1_BR35': CDS_PINID='VDDCR_CPU1_BR35';
NODE_NAME     U26 BR40
 '@T6G_MB_LIB.T6G(SCH_1):PAGE57_I32@PURE_QUANTA.GENOA_SP5(CHIPS)':
 'VDDCR_CPU1_BR40': CDS_PINID='VDDCR_CPU1_BR40';
NODE_NAME     U26 BR42
 '@T6G_MB_LIB.T6G(SCH_1):PAGE57_I32@PURE_QUANTA.GENOA_SP5(CHIPS)':
 'VDDCR_CPU1_BR42': CDS_PINID='VDDCR_CPU1_BR42';
NODE_NAME     U26 BR44
 '@T6G_MB_LIB.T6G(SCH_1):PAGE57_I32@PURE_QUANTA.GENOA_SP5(CHIPS)':
 'VDDCR_CPU1_BR44': CDS_PINID='VDDCR_CPU1_BR44';
NODE_NAME     U26 BR46
 '@T6G_MB_LIB.T6G(SCH_1):PAGE57_I32@PURE_QUANTA.GENOA_SP5(CHIPS)':
 'VDDCR_CPU1_BR46': CDS_PINID='VDDCR_CPU1_BR46';
NODE_NAME     U26 BR48
 '@T6G_MB_LIB.T6G(SCH_1):PAGE57_I32@PURE_QUANTA.GENOA_SP5(CHIPS)':
 'VDDCR_CPU1_BR48': CDS_PINID='VDDCR_CPU1_BR48';
NODE_NAME     U26 BR50
 '@T6G_MB_LIB.T6G(SCH_1):PAGE57_I32@PURE_QUANTA.GENOA_SP5(CHIPS)':
 'VDDCR_CPU1_BR50': CDS_PINID='VDDCR_CPU1_BR50';
NODE_NAME     U26 BR52
 '@T6G_MB_LIB.T6G(SCH_1):PAGE57_I32@PURE_QUANTA.GENOA_SP5(CHIPS)':
 'VDDCR_CPU1_BR52': CDS_PINID='VDDCR_CPU1_BR52';
NODE_NAME     U26 BT23
 '@T6G_MB_LIB.T6G(SCH_1):PAGE57_I32@PURE_QUANTA.GENOA_SP5(CHIPS)':
 'VDDCR_CPU1_BT23': CDS_PINID='VDDCR_CPU1_BT23';
NODE_NAME     U26 BT24
 '@T6G_MB_LIB.T6G(SCH_1):PAGE57_I32@PURE_QUANTA.GENOA_SP5(CHIPS)':
 'VDDCR_CPU1_BT24': CDS_PINID='VDDCR_CPU1_BT24';
NODE_NAME     U26 BT26
 '@T6G_MB_LIB.T6G(SCH_1):PAGE57_I32@PURE_QUANTA.GENOA_SP5(CHIPS)':
 'VDDCR_CPU1_BT26': CDS_PINID='VDDCR_CPU1_BT26';
NODE_NAME     U26 BT27
 '@T6G_MB_LIB.T6G(SCH_1):PAGE57_I32@PURE_QUANTA.GENOA_SP5(CHIPS)':
 'VDDCR_CPU1_BT27': CDS_PINID='VDDCR_CPU1_BT27';
NODE_NAME     U26 BT29
 '@T6G_MB_LIB.T6G(SCH_1):PAGE57_I32@PURE_QUANTA.GENOA_SP5(CHIPS)':
 'VDDCR_CPU1_BT29': CDS_PINID='VDDCR_CPU1_BT29';
NODE_NAME     U26 BT30
 '@T6G_MB_LIB.T6G(SCH_1):PAGE57_I32@PURE_QUANTA.GENOA_SP5(CHIPS)':
 'VDDCR_CPU1_BT30': CDS_PINID='VDDCR_CPU1_BT30';
NODE_NAME     U26 BT32
 '@T6G_MB_LIB.T6G(SCH_1):PAGE57_I32@PURE_QUANTA.GENOA_SP5(CHIPS)':
 'VDDCR_CPU1_BT32': CDS_PINID='VDDCR_CPU1_BT32';
NODE_NAME     U26 BT33
 '@T6G_MB_LIB.T6G(SCH_1):PAGE57_I32@PURE_QUANTA.GENOA_SP5(CHIPS)':
 'VDDCR_CPU1_BT33': CDS_PINID='VDDCR_CPU1_BT33';
NODE_NAME     U26 BT43
 '@T6G_MB_LIB.T6G(SCH_1):PAGE57_I32@PURE_QUANTA.GENOA_SP5(CHIPS)':
 'VDDCR_CPU1_BT43': CDS_PINID='VDDCR_CPU1_BT43';
NODE_NAME     U26 BT44
 '@T6G_MB_LIB.T6G(SCH_1):PAGE57_I32@PURE_QUANTA.GENOA_SP5(CHIPS)':
 'VDDCR_CPU1_BT44': CDS_PINID='VDDCR_CPU1_BT44';
NODE_NAME     U26 BT46
 '@T6G_MB_LIB.T6G(SCH_1):PAGE57_I32@PURE_QUANTA.GENOA_SP5(CHIPS)':
 'VDDCR_CPU1_BT46': CDS_PINID='VDDCR_CPU1_BT46';
NODE_NAME     U26 BT47
 '@T6G_MB_LIB.T6G(SCH_1):PAGE57_I32@PURE_QUANTA.GENOA_SP5(CHIPS)':
 'VDDCR_CPU1_BT47': CDS_PINID='VDDCR_CPU1_BT47';
NODE_NAME     U26 BT49
 '@T6G_MB_LIB.T6G(SCH_1):PAGE57_I32@PURE_QUANTA.GENOA_SP5(CHIPS)':
 'VDDCR_CPU1_BT49': CDS_PINID='VDDCR_CPU1_BT49';
NODE_NAME     U26 BT50
 '@T6G_MB_LIB.T6G(SCH_1):PAGE57_I32@PURE_QUANTA.GENOA_SP5(CHIPS)':
 'VDDCR_CPU1_BT50': CDS_PINID='VDDCR_CPU1_BT50';
NODE_NAME     U26 BT52
 '@T6G_MB_LIB.T6G(SCH_1):PAGE57_I32@PURE_QUANTA.GENOA_SP5(CHIPS)':
 'VDDCR_CPU1_BT52': CDS_PINID='VDDCR_CPU1_BT52';
NODE_NAME     U26 BT53
 '@T6G_MB_LIB.T6G(SCH_1):PAGE57_I32@PURE_QUANTA.GENOA_SP5(CHIPS)':
 'VDDCR_CPU1_BT53': CDS_PINID='VDDCR_CPU1_BT53';
NODE_NAME     U26 BW35
 '@T6G_MB_LIB.T6G(SCH_1):PAGE57_I32@PURE_QUANTA.GENOA_SP5(CHIPS)':
 'VDDCR_CPU1_BW35': CDS_PINID='VDDCR_CPU1_BW35';
NODE_NAME     U26 BW36
 '@T6G_MB_LIB.T6G(SCH_1):PAGE57_I32@PURE_QUANTA.GENOA_SP5(CHIPS)':
 'VDDCR_CPU1_BW36': CDS_PINID='VDDCR_CPU1_BW36';
NODE_NAME     U26 BW40
 '@T6G_MB_LIB.T6G(SCH_1):PAGE57_I32@PURE_QUANTA.GENOA_SP5(CHIPS)':
 'VDDCR_CPU1_BW40': CDS_PINID='VDDCR_CPU1_BW40';
NODE_NAME     U26 BW41
 '@T6G_MB_LIB.T6G(SCH_1):PAGE57_I32@PURE_QUANTA.GENOA_SP5(CHIPS)':
 'VDDCR_CPU1_BW41': CDS_PINID='VDDCR_CPU1_BW41';
NODE_NAME     U26 BY23
 '@T6G_MB_LIB.T6G(SCH_1):PAGE57_I32@PURE_QUANTA.GENOA_SP5(CHIPS)':
 'VDDCR_CPU1_BY23': CDS_PINID='VDDCR_CPU1_BY23';
NODE_NAME     U26 BY24
 '@T6G_MB_LIB.T6G(SCH_1):PAGE57_I32@PURE_QUANTA.GENOA_SP5(CHIPS)':
 'VDDCR_CPU1_BY24': CDS_PINID='VDDCR_CPU1_BY24';
NODE_NAME     U26 BY26
 '@T6G_MB_LIB.T6G(SCH_1):PAGE57_I32@PURE_QUANTA.GENOA_SP5(CHIPS)':
 'VDDCR_CPU1_BY26': CDS_PINID='VDDCR_CPU1_BY26';
NODE_NAME     U26 BY27
 '@T6G_MB_LIB.T6G(SCH_1):PAGE57_I32@PURE_QUANTA.GENOA_SP5(CHIPS)':
 'VDDCR_CPU1_BY27': CDS_PINID='VDDCR_CPU1_BY27';
NODE_NAME     U26 BY29
 '@T6G_MB_LIB.T6G(SCH_1):PAGE57_I32@PURE_QUANTA.GENOA_SP5(CHIPS)':
 'VDDCR_CPU1_BY29': CDS_PINID='VDDCR_CPU1_BY29';
NODE_NAME     U26 BY30
 '@T6G_MB_LIB.T6G(SCH_1):PAGE57_I32@PURE_QUANTA.GENOA_SP5(CHIPS)':
 'VDDCR_CPU1_BY30': CDS_PINID='VDDCR_CPU1_BY30';
NODE_NAME     U26 BY32
 '@T6G_MB_LIB.T6G(SCH_1):PAGE57_I32@PURE_QUANTA.GENOA_SP5(CHIPS)':
 'VDDCR_CPU1_BY32': CDS_PINID='VDDCR_CPU1_BY32';
NODE_NAME     U26 BY33
 '@T6G_MB_LIB.T6G(SCH_1):PAGE57_I32@PURE_QUANTA.GENOA_SP5(CHIPS)':
 'VDDCR_CPU1_BY33': CDS_PINID='VDDCR_CPU1_BY33';
NODE_NAME     U26 BY43
 '@T6G_MB_LIB.T6G(SCH_1):PAGE57_I32@PURE_QUANTA.GENOA_SP5(CHIPS)':
 'VDDCR_CPU1_BY43': CDS_PINID='VDDCR_CPU1_BY43';
NODE_NAME     U26 BY44
 '@T6G_MB_LIB.T6G(SCH_1):PAGE57_I32@PURE_QUANTA.GENOA_SP5(CHIPS)':
 'VDDCR_CPU1_BY44': CDS_PINID='VDDCR_CPU1_BY44';
NODE_NAME     U26 BY46
 '@T6G_MB_LIB.T6G(SCH_1):PAGE57_I32@PURE_QUANTA.GENOA_SP5(CHIPS)':
 'VDDCR_CPU1_BY46': CDS_PINID='VDDCR_CPU1_BY46';
NODE_NAME     U26 BY47
 '@T6G_MB_LIB.T6G(SCH_1):PAGE57_I32@PURE_QUANTA.GENOA_SP5(CHIPS)':
 'VDDCR_CPU1_BY47': CDS_PINID='VDDCR_CPU1_BY47';
NODE_NAME     U26 BY49
 '@T6G_MB_LIB.T6G(SCH_1):PAGE57_I32@PURE_QUANTA.GENOA_SP5(CHIPS)':
 'VDDCR_CPU1_BY49': CDS_PINID='VDDCR_CPU1_BY49';
NODE_NAME     U26 BY50
 '@T6G_MB_LIB.T6G(SCH_1):PAGE57_I32@PURE_QUANTA.GENOA_SP5(CHIPS)':
 'VDDCR_CPU1_BY50': CDS_PINID='VDDCR_CPU1_BY50';
NODE_NAME     U26 BY52
 '@T6G_MB_LIB.T6G(SCH_1):PAGE57_I32@PURE_QUANTA.GENOA_SP5(CHIPS)':
 'VDDCR_CPU1_BY52': CDS_PINID='VDDCR_CPU1_BY52';
NODE_NAME     U26 BY53
 '@T6G_MB_LIB.T6G(SCH_1):PAGE57_I32@PURE_QUANTA.GENOA_SP5(CHIPS)':
 'VDDCR_CPU1_BY53': CDS_PINID='VDDCR_CPU1_BY53';
NODE_NAME     U26 CC35
 '@T6G_MB_LIB.T6G(SCH_1):PAGE57_I32@PURE_QUANTA.GENOA_SP5(CHIPS)':
 'VDDCR_CPU1_CC35': CDS_PINID='VDDCR_CPU1_CC35';
NODE_NAME     U26 CC36
 '@T6G_MB_LIB.T6G(SCH_1):PAGE57_I32@PURE_QUANTA.GENOA_SP5(CHIPS)':
 'VDDCR_CPU1_CC36': CDS_PINID='VDDCR_CPU1_CC36';
NODE_NAME     U26 CC40
 '@T6G_MB_LIB.T6G(SCH_1):PAGE57_I32@PURE_QUANTA.GENOA_SP5(CHIPS)':
 'VDDCR_CPU1_CC40': CDS_PINID='VDDCR_CPU1_CC40';
NODE_NAME     U26 CC41
 '@T6G_MB_LIB.T6G(SCH_1):PAGE57_I32@PURE_QUANTA.GENOA_SP5(CHIPS)':
 'VDDCR_CPU1_CC41': CDS_PINID='VDDCR_CPU1_CC41';
NODE_NAME     U26 CD23
 '@T6G_MB_LIB.T6G(SCH_1):PAGE57_I32@PURE_QUANTA.GENOA_SP5(CHIPS)':
 'VDDCR_CPU1_CD23': CDS_PINID='VDDCR_CPU1_CD23';
NODE_NAME     U26 CD24
 '@T6G_MB_LIB.T6G(SCH_1):PAGE57_I32@PURE_QUANTA.GENOA_SP5(CHIPS)':
 'VDDCR_CPU1_CD24': CDS_PINID='VDDCR_CPU1_CD24';
NODE_NAME     U26 CD26
 '@T6G_MB_LIB.T6G(SCH_1):PAGE57_I32@PURE_QUANTA.GENOA_SP5(CHIPS)':
 'VDDCR_CPU1_CD26': CDS_PINID='VDDCR_CPU1_CD26';
NODE_NAME     U26 CD27
 '@T6G_MB_LIB.T6G(SCH_1):PAGE57_I32@PURE_QUANTA.GENOA_SP5(CHIPS)':
 'VDDCR_CPU1_CD27': CDS_PINID='VDDCR_CPU1_CD27';
NODE_NAME     U26 CD29
 '@T6G_MB_LIB.T6G(SCH_1):PAGE57_I32@PURE_QUANTA.GENOA_SP5(CHIPS)':
 'VDDCR_CPU1_CD29': CDS_PINID='VDDCR_CPU1_CD29';
NODE_NAME     U26 CD30
 '@T6G_MB_LIB.T6G(SCH_1):PAGE57_I32@PURE_QUANTA.GENOA_SP5(CHIPS)':
 'VDDCR_CPU1_CD30': CDS_PINID='VDDCR_CPU1_CD30';
NODE_NAME     U26 CD32
 '@T6G_MB_LIB.T6G(SCH_1):PAGE57_I32@PURE_QUANTA.GENOA_SP5(CHIPS)':
 'VDDCR_CPU1_CD32': CDS_PINID='VDDCR_CPU1_CD32';
NODE_NAME     U26 CD33
 '@T6G_MB_LIB.T6G(SCH_1):PAGE57_I32@PURE_QUANTA.GENOA_SP5(CHIPS)':
 'VDDCR_CPU1_CD33': CDS_PINID='VDDCR_CPU1_CD33';
NODE_NAME     U26 CD43
 '@T6G_MB_LIB.T6G(SCH_1):PAGE57_I32@PURE_QUANTA.GENOA_SP5(CHIPS)':
 'VDDCR_CPU1_CD43': CDS_PINID='VDDCR_CPU1_CD43';
NODE_NAME     U26 CD44
 '@T6G_MB_LIB.T6G(SCH_1):PAGE57_I32@PURE_QUANTA.GENOA_SP5(CHIPS)':
 'VDDCR_CPU1_CD44': CDS_PINID='VDDCR_CPU1_CD44';
NODE_NAME     U26 CD46
 '@T6G_MB_LIB.T6G(SCH_1):PAGE57_I32@PURE_QUANTA.GENOA_SP5(CHIPS)':
 'VDDCR_CPU1_CD46': CDS_PINID='VDDCR_CPU1_CD46';
NODE_NAME     U26 CD47
 '@T6G_MB_LIB.T6G(SCH_1):PAGE57_I32@PURE_QUANTA.GENOA_SP5(CHIPS)':
 'VDDCR_CPU1_CD47': CDS_PINID='VDDCR_CPU1_CD47';
NODE_NAME     U26 CD49
 '@T6G_MB_LIB.T6G(SCH_1):PAGE57_I32@PURE_QUANTA.GENOA_SP5(CHIPS)':
 'VDDCR_CPU1_CD49': CDS_PINID='VDDCR_CPU1_CD49';
NODE_NAME     U26 CD50
 '@T6G_MB_LIB.T6G(SCH_1):PAGE57_I32@PURE_QUANTA.GENOA_SP5(CHIPS)':
 'VDDCR_CPU1_CD50': CDS_PINID='VDDCR_CPU1_CD50';
NODE_NAME     U26 CD52
 '@T6G_MB_LIB.T6G(SCH_1):PAGE57_I32@PURE_QUANTA.GENOA_SP5(CHIPS)':
 'VDDCR_CPU1_CD52': CDS_PINID='VDDCR_CPU1_CD52';
NODE_NAME     U26 CD53
 '@T6G_MB_LIB.T6G(SCH_1):PAGE57_I32@PURE_QUANTA.GENOA_SP5(CHIPS)':
 'VDDCR_CPU1_CD53': CDS_PINID='VDDCR_CPU1_CD53';
NODE_NAME     U26 CG35
 '@T6G_MB_LIB.T6G(SCH_1):PAGE57_I32@PURE_QUANTA.GENOA_SP5(CHIPS)':
 'VDDCR_CPU1_CG35': CDS_PINID='VDDCR_CPU1_CG35';
NODE_NAME     U26 CG36
 '@T6G_MB_LIB.T6G(SCH_1):PAGE57_I32@PURE_QUANTA.GENOA_SP5(CHIPS)':
 'VDDCR_CPU1_CG36': CDS_PINID='VDDCR_CPU1_CG36';
NODE_NAME     U26 CG40
 '@T6G_MB_LIB.T6G(SCH_1):PAGE57_I32@PURE_QUANTA.GENOA_SP5(CHIPS)':
 'VDDCR_CPU1_CG40': CDS_PINID='VDDCR_CPU1_CG40';
NODE_NAME     U26 CG41
 '@T6G_MB_LIB.T6G(SCH_1):PAGE57_I32@PURE_QUANTA.GENOA_SP5(CHIPS)':
 'VDDCR_CPU1_CG41': CDS_PINID='VDDCR_CPU1_CG41';
NODE_NAME     U26 CH23
 '@T6G_MB_LIB.T6G(SCH_1):PAGE57_I32@PURE_QUANTA.GENOA_SP5(CHIPS)':
 'VDDCR_CPU1_CH23': CDS_PINID='VDDCR_CPU1_CH23';
NODE_NAME     U26 CH24
 '@T6G_MB_LIB.T6G(SCH_1):PAGE57_I32@PURE_QUANTA.GENOA_SP5(CHIPS)':
 'VDDCR_CPU1_CH24': CDS_PINID='VDDCR_CPU1_CH24';
NODE_NAME     U26 CH26
 '@T6G_MB_LIB.T6G(SCH_1):PAGE57_I32@PURE_QUANTA.GENOA_SP5(CHIPS)':
 'VDDCR_CPU1_CH26': CDS_PINID='VDDCR_CPU1_CH26';
NODE_NAME     U26 CH27
 '@T6G_MB_LIB.T6G(SCH_1):PAGE57_I32@PURE_QUANTA.GENOA_SP5(CHIPS)':
 'VDDCR_CPU1_CH27': CDS_PINID='VDDCR_CPU1_CH27';
NODE_NAME     U26 CH29
 '@T6G_MB_LIB.T6G(SCH_1):PAGE57_I32@PURE_QUANTA.GENOA_SP5(CHIPS)':
 'VDDCR_CPU1_CH29': CDS_PINID='VDDCR_CPU1_CH29';
NODE_NAME     U26 CH30
 '@T6G_MB_LIB.T6G(SCH_1):PAGE57_I32@PURE_QUANTA.GENOA_SP5(CHIPS)':
 'VDDCR_CPU1_CH30': CDS_PINID='VDDCR_CPU1_CH30';
NODE_NAME     U26 CH32
 '@T6G_MB_LIB.T6G(SCH_1):PAGE57_I32@PURE_QUANTA.GENOA_SP5(CHIPS)':
 'VDDCR_CPU1_CH32': CDS_PINID='VDDCR_CPU1_CH32';
NODE_NAME     U26 CH33
 '@T6G_MB_LIB.T6G(SCH_1):PAGE57_I32@PURE_QUANTA.GENOA_SP5(CHIPS)':
 'VDDCR_CPU1_CH33': CDS_PINID='VDDCR_CPU1_CH33';
NODE_NAME     U26 CH43
 '@T6G_MB_LIB.T6G(SCH_1):PAGE57_I32@PURE_QUANTA.GENOA_SP5(CHIPS)':
 'VDDCR_CPU1_CH43': CDS_PINID='VDDCR_CPU1_CH43';
NODE_NAME     U26 CH44
 '@T6G_MB_LIB.T6G(SCH_1):PAGE57_I32@PURE_QUANTA.GENOA_SP5(CHIPS)':
 'VDDCR_CPU1_CH44': CDS_PINID='VDDCR_CPU1_CH44';
NODE_NAME     U26 CH46
 '@T6G_MB_LIB.T6G(SCH_1):PAGE57_I32@PURE_QUANTA.GENOA_SP5(CHIPS)':
 'VDDCR_CPU1_CH46': CDS_PINID='VDDCR_CPU1_CH46';
NODE_NAME     U26 CH47
 '@T6G_MB_LIB.T6G(SCH_1):PAGE57_I32@PURE_QUANTA.GENOA_SP5(CHIPS)':
 'VDDCR_CPU1_CH47': CDS_PINID='VDDCR_CPU1_CH47';
NODE_NAME     U26 CH49
 '@T6G_MB_LIB.T6G(SCH_1):PAGE57_I32@PURE_QUANTA.GENOA_SP5(CHIPS)':
 'VDDCR_CPU1_CH49': CDS_PINID='VDDCR_CPU1_CH49';
NODE_NAME     U26 CH50
 '@T6G_MB_LIB.T6G(SCH_1):PAGE57_I32@PURE_QUANTA.GENOA_SP5(CHIPS)':
 'VDDCR_CPU1_CH50': CDS_PINID='VDDCR_CPU1_CH50';
NODE_NAME     U26 CH52
 '@T6G_MB_LIB.T6G(SCH_1):PAGE57_I32@PURE_QUANTA.GENOA_SP5(CHIPS)':
 'VDDCR_CPU1_CH52': CDS_PINID='VDDCR_CPU1_CH52';
NODE_NAME     U26 CH53
 '@T6G_MB_LIB.T6G(SCH_1):PAGE57_I32@PURE_QUANTA.GENOA_SP5(CHIPS)':
 'VDDCR_CPU1_CH53': CDS_PINID='VDDCR_CPU1_CH53';
NODE_NAME     U26 CK35
 '@T6G_MB_LIB.T6G(SCH_1):PAGE57_I32@PURE_QUANTA.GENOA_SP5(CHIPS)':
 'VDDCR_CPU1_CK35': CDS_PINID='VDDCR_CPU1_CK35';
NODE_NAME     U26 CK36
 '@T6G_MB_LIB.T6G(SCH_1):PAGE57_I32@PURE_QUANTA.GENOA_SP5(CHIPS)':
 'VDDCR_CPU1_CK36': CDS_PINID='VDDCR_CPU1_CK36';
NODE_NAME     U26 CK40
 '@T6G_MB_LIB.T6G(SCH_1):PAGE57_I32@PURE_QUANTA.GENOA_SP5(CHIPS)':
 'VDDCR_CPU1_CK40': CDS_PINID='VDDCR_CPU1_CK40';
NODE_NAME     U26 CK41
 '@T6G_MB_LIB.T6G(SCH_1):PAGE57_I32@PURE_QUANTA.GENOA_SP5(CHIPS)':
 'VDDCR_CPU1_CK41': CDS_PINID='VDDCR_CPU1_CK41';
NODE_NAME     U26 CL29
 '@T6G_MB_LIB.T6G(SCH_1):PAGE57_I32@PURE_QUANTA.GENOA_SP5(CHIPS)':
 'VDDCR_CPU1_CL29': CDS_PINID='VDDCR_CPU1_CL29';
NODE_NAME     U26 CL30
 '@T6G_MB_LIB.T6G(SCH_1):PAGE57_I32@PURE_QUANTA.GENOA_SP5(CHIPS)':
 'VDDCR_CPU1_CL30': CDS_PINID='VDDCR_CPU1_CL30';
NODE_NAME     U26 CL32
 '@T6G_MB_LIB.T6G(SCH_1):PAGE57_I32@PURE_QUANTA.GENOA_SP5(CHIPS)':
 'VDDCR_CPU1_CL32': CDS_PINID='VDDCR_CPU1_CL32';
NODE_NAME     U26 CL33
 '@T6G_MB_LIB.T6G(SCH_1):PAGE57_I32@PURE_QUANTA.GENOA_SP5(CHIPS)':
 'VDDCR_CPU1_CL33': CDS_PINID='VDDCR_CPU1_CL33';
NODE_NAME     U26 CL43
 '@T6G_MB_LIB.T6G(SCH_1):PAGE57_I32@PURE_QUANTA.GENOA_SP5(CHIPS)':
 'VDDCR_CPU1_CL43': CDS_PINID='VDDCR_CPU1_CL43';
NODE_NAME     U26 CL44
 '@T6G_MB_LIB.T6G(SCH_1):PAGE57_I32@PURE_QUANTA.GENOA_SP5(CHIPS)':
 'VDDCR_CPU1_CL44': CDS_PINID='VDDCR_CPU1_CL44';
NODE_NAME     U26 CL46
 '@T6G_MB_LIB.T6G(SCH_1):PAGE57_I32@PURE_QUANTA.GENOA_SP5(CHIPS)':
 'VDDCR_CPU1_CL46': CDS_PINID='VDDCR_CPU1_CL46';
NODE_NAME     U26 CL47
 '@T6G_MB_LIB.T6G(SCH_1):PAGE57_I32@PURE_QUANTA.GENOA_SP5(CHIPS)':
 'VDDCR_CPU1_CL47': CDS_PINID='VDDCR_CPU1_CL47';
NODE_NAME     U26 CN35
 '@T6G_MB_LIB.T6G(SCH_1):PAGE57_I32@PURE_QUANTA.GENOA_SP5(CHIPS)':
 'VDDCR_CPU1_CN35': CDS_PINID='VDDCR_CPU1_CN35';
NODE_NAME     U26 CN36
 '@T6G_MB_LIB.T6G(SCH_1):PAGE57_I32@PURE_QUANTA.GENOA_SP5(CHIPS)':
 'VDDCR_CPU1_CN36': CDS_PINID='VDDCR_CPU1_CN36';
NODE_NAME     U26 CN40
 '@T6G_MB_LIB.T6G(SCH_1):PAGE57_I32@PURE_QUANTA.GENOA_SP5(CHIPS)':
 'VDDCR_CPU1_CN40': CDS_PINID='VDDCR_CPU1_CN40';
NODE_NAME     U26 CN41
 '@T6G_MB_LIB.T6G(SCH_1):PAGE57_I32@PURE_QUANTA.GENOA_SP5(CHIPS)':
 'VDDCR_CPU1_CN41': CDS_PINID='VDDCR_CPU1_CN41';
NODE_NAME     U26 CP23
 '@T6G_MB_LIB.T6G(SCH_1):PAGE57_I32@PURE_QUANTA.GENOA_SP5(CHIPS)':
 'VDDCR_CPU1_CP23': CDS_PINID='VDDCR_CPU1_CP23';
NODE_NAME     U26 CP24
 '@T6G_MB_LIB.T6G(SCH_1):PAGE57_I32@PURE_QUANTA.GENOA_SP5(CHIPS)':
 'VDDCR_CPU1_CP24': CDS_PINID='VDDCR_CPU1_CP24';
NODE_NAME     U26 CP26
 '@T6G_MB_LIB.T6G(SCH_1):PAGE57_I32@PURE_QUANTA.GENOA_SP5(CHIPS)':
 'VDDCR_CPU1_CP26': CDS_PINID='VDDCR_CPU1_CP26';
NODE_NAME     U26 CP27
 '@T6G_MB_LIB.T6G(SCH_1):PAGE57_I32@PURE_QUANTA.GENOA_SP5(CHIPS)':
 'VDDCR_CPU1_CP27': CDS_PINID='VDDCR_CPU1_CP27';
NODE_NAME     U26 CP29
 '@T6G_MB_LIB.T6G(SCH_1):PAGE57_I32@PURE_QUANTA.GENOA_SP5(CHIPS)':
 'VDDCR_CPU1_CP29': CDS_PINID='VDDCR_CPU1_CP29';
NODE_NAME     U26 CP30
 '@T6G_MB_LIB.T6G(SCH_1):PAGE57_I32@PURE_QUANTA.GENOA_SP5(CHIPS)':
 'VDDCR_CPU1_CP30': CDS_PINID='VDDCR_CPU1_CP30';
NODE_NAME     U26 CP32
 '@T6G_MB_LIB.T6G(SCH_1):PAGE57_I32@PURE_QUANTA.GENOA_SP5(CHIPS)':
 'VDDCR_CPU1_CP32': CDS_PINID='VDDCR_CPU1_CP32';
NODE_NAME     U26 CP33
 '@T6G_MB_LIB.T6G(SCH_1):PAGE57_I32@PURE_QUANTA.GENOA_SP5(CHIPS)':
 'VDDCR_CPU1_CP33': CDS_PINID='VDDCR_CPU1_CP33';
NODE_NAME     U26 CP43
 '@T6G_MB_LIB.T6G(SCH_1):PAGE57_I32@PURE_QUANTA.GENOA_SP5(CHIPS)':
 'VDDCR_CPU1_CP43': CDS_PINID='VDDCR_CPU1_CP43';
NODE_NAME     U26 CP44
 '@T6G_MB_LIB.T6G(SCH_1):PAGE57_I32@PURE_QUANTA.GENOA_SP5(CHIPS)':
 'VDDCR_CPU1_CP44': CDS_PINID='VDDCR_CPU1_CP44';
NODE_NAME     U26 CP46
 '@T6G_MB_LIB.T6G(SCH_1):PAGE57_I32@PURE_QUANTA.GENOA_SP5(CHIPS)':
 'VDDCR_CPU1_CP46': CDS_PINID='VDDCR_CPU1_CP46';
NODE_NAME     U26 CP47
 '@T6G_MB_LIB.T6G(SCH_1):PAGE57_I32@PURE_QUANTA.GENOA_SP5(CHIPS)':
 'VDDCR_CPU1_CP47': CDS_PINID='VDDCR_CPU1_CP47';
NODE_NAME     U26 CP49
 '@T6G_MB_LIB.T6G(SCH_1):PAGE57_I32@PURE_QUANTA.GENOA_SP5(CHIPS)':
 'VDDCR_CPU1_CP49': CDS_PINID='VDDCR_CPU1_CP49';
NODE_NAME     U26 CP50
 '@T6G_MB_LIB.T6G(SCH_1):PAGE57_I32@PURE_QUANTA.GENOA_SP5(CHIPS)':
 'VDDCR_CPU1_CP50': CDS_PINID='VDDCR_CPU1_CP50';
NODE_NAME     U26 CP52
 '@T6G_MB_LIB.T6G(SCH_1):PAGE57_I32@PURE_QUANTA.GENOA_SP5(CHIPS)':
 'VDDCR_CPU1_CP52': CDS_PINID='VDDCR_CPU1_CP52';
NODE_NAME     U26 CP53
 '@T6G_MB_LIB.T6G(SCH_1):PAGE57_I32@PURE_QUANTA.GENOA_SP5(CHIPS)':
 'VDDCR_CPU1_CP53': CDS_PINID='VDDCR_CPU1_CP53';
NODE_NAME     U26 CU35
 '@T6G_MB_LIB.T6G(SCH_1):PAGE57_I32@PURE_QUANTA.GENOA_SP5(CHIPS)':
 'VDDCR_CPU1_CU35': CDS_PINID='VDDCR_CPU1_CU35';
NODE_NAME     U26 CU36
 '@T6G_MB_LIB.T6G(SCH_1):PAGE57_I32@PURE_QUANTA.GENOA_SP5(CHIPS)':
 'VDDCR_CPU1_CU36': CDS_PINID='VDDCR_CPU1_CU36';
NODE_NAME     U26 CU40
 '@T6G_MB_LIB.T6G(SCH_1):PAGE57_I32@PURE_QUANTA.GENOA_SP5(CHIPS)':
 'VDDCR_CPU1_CU40': CDS_PINID='VDDCR_CPU1_CU40';
NODE_NAME     U26 CU41
 '@T6G_MB_LIB.T6G(SCH_1):PAGE57_I32@PURE_QUANTA.GENOA_SP5(CHIPS)':
 'VDDCR_CPU1_CU41': CDS_PINID='VDDCR_CPU1_CU41';
NODE_NAME     U26 CV23
 '@T6G_MB_LIB.T6G(SCH_1):PAGE57_I32@PURE_QUANTA.GENOA_SP5(CHIPS)':
 'VDDCR_CPU1_CV23': CDS_PINID='VDDCR_CPU1_CV23';
NODE_NAME     U26 CV24
 '@T6G_MB_LIB.T6G(SCH_1):PAGE57_I32@PURE_QUANTA.GENOA_SP5(CHIPS)':
 'VDDCR_CPU1_CV24': CDS_PINID='VDDCR_CPU1_CV24';
NODE_NAME     U26 CV26
 '@T6G_MB_LIB.T6G(SCH_1):PAGE57_I32@PURE_QUANTA.GENOA_SP5(CHIPS)':
 'VDDCR_CPU1_CV26': CDS_PINID='VDDCR_CPU1_CV26';
NODE_NAME     U26 CV27
 '@T6G_MB_LIB.T6G(SCH_1):PAGE57_I32@PURE_QUANTA.GENOA_SP5(CHIPS)':
 'VDDCR_CPU1_CV27': CDS_PINID='VDDCR_CPU1_CV27';
NODE_NAME     U26 CV29
 '@T6G_MB_LIB.T6G(SCH_1):PAGE57_I32@PURE_QUANTA.GENOA_SP5(CHIPS)':
 'VDDCR_CPU1_CV29': CDS_PINID='VDDCR_CPU1_CV29';
NODE_NAME     U26 CV30
 '@T6G_MB_LIB.T6G(SCH_1):PAGE57_I32@PURE_QUANTA.GENOA_SP5(CHIPS)':
 'VDDCR_CPU1_CV30': CDS_PINID='VDDCR_CPU1_CV30';
NODE_NAME     U26 CV32
 '@T6G_MB_LIB.T6G(SCH_1):PAGE57_I32@PURE_QUANTA.GENOA_SP5(CHIPS)':
 'VDDCR_CPU1_CV32': CDS_PINID='VDDCR_CPU1_CV32';
NODE_NAME     U26 CV33
 '@T6G_MB_LIB.T6G(SCH_1):PAGE57_I32@PURE_QUANTA.GENOA_SP5(CHIPS)':
 'VDDCR_CPU1_CV33': CDS_PINID='VDDCR_CPU1_CV33';
NODE_NAME     U26 CV43
 '@T6G_MB_LIB.T6G(SCH_1):PAGE57_I32@PURE_QUANTA.GENOA_SP5(CHIPS)':
 'VDDCR_CPU1_CV43': CDS_PINID='VDDCR_CPU1_CV43';
NODE_NAME     U26 CV44
 '@T6G_MB_LIB.T6G(SCH_1):PAGE57_I32@PURE_QUANTA.GENOA_SP5(CHIPS)':
 'VDDCR_CPU1_CV44': CDS_PINID='VDDCR_CPU1_CV44';
NODE_NAME     U26 CV46
 '@T6G_MB_LIB.T6G(SCH_1):PAGE57_I32@PURE_QUANTA.GENOA_SP5(CHIPS)':
 'VDDCR_CPU1_CV46': CDS_PINID='VDDCR_CPU1_CV46';
NODE_NAME     U26 CV47
 '@T6G_MB_LIB.T6G(SCH_1):PAGE57_I32@PURE_QUANTA.GENOA_SP5(CHIPS)':
 'VDDCR_CPU1_CV47': CDS_PINID='VDDCR_CPU1_CV47';
NODE_NAME     U26 CV49
 '@T6G_MB_LIB.T6G(SCH_1):PAGE57_I32@PURE_QUANTA.GENOA_SP5(CHIPS)':
 'VDDCR_CPU1_CV49': CDS_PINID='VDDCR_CPU1_CV49';
NODE_NAME     U26 CV50
 '@T6G_MB_LIB.T6G(SCH_1):PAGE57_I32@PURE_QUANTA.GENOA_SP5(CHIPS)':
 'VDDCR_CPU1_CV50': CDS_PINID='VDDCR_CPU1_CV50';
NODE_NAME     U26 CV52
 '@T6G_MB_LIB.T6G(SCH_1):PAGE57_I32@PURE_QUANTA.GENOA_SP5(CHIPS)':
 'VDDCR_CPU1_CV52': CDS_PINID='VDDCR_CPU1_CV52';
NODE_NAME     U26 CV53
 '@T6G_MB_LIB.T6G(SCH_1):PAGE57_I32@PURE_QUANTA.GENOA_SP5(CHIPS)':
 'VDDCR_CPU1_CV53': CDS_PINID='VDDCR_CPU1_CV53';
NODE_NAME     U26 DA35
 '@T6G_MB_LIB.T6G(SCH_1):PAGE57_I32@PURE_QUANTA.GENOA_SP5(CHIPS)':
 'VDDCR_CPU1_DA35': CDS_PINID='VDDCR_CPU1_DA35';
NODE_NAME     U26 DA36
 '@T6G_MB_LIB.T6G(SCH_1):PAGE57_I32@PURE_QUANTA.GENOA_SP5(CHIPS)':
 'VDDCR_CPU1_DA36': CDS_PINID='VDDCR_CPU1_DA36';
NODE_NAME     U26 DA40
 '@T6G_MB_LIB.T6G(SCH_1):PAGE57_I32@PURE_QUANTA.GENOA_SP5(CHIPS)':
 'VDDCR_CPU1_DA40': CDS_PINID='VDDCR_CPU1_DA40';
NODE_NAME     U26 DA41
 '@T6G_MB_LIB.T6G(SCH_1):PAGE57_I32@PURE_QUANTA.GENOA_SP5(CHIPS)':
 'VDDCR_CPU1_DA41': CDS_PINID='VDDCR_CPU1_DA41';
NODE_NAME     U26 DB23
 '@T6G_MB_LIB.T6G(SCH_1):PAGE57_I32@PURE_QUANTA.GENOA_SP5(CHIPS)':
 'VDDCR_CPU1_DB23': CDS_PINID='VDDCR_CPU1_DB23';
NODE_NAME     U26 DB24
 '@T6G_MB_LIB.T6G(SCH_1):PAGE57_I32@PURE_QUANTA.GENOA_SP5(CHIPS)':
 'VDDCR_CPU1_DB24': CDS_PINID='VDDCR_CPU1_DB24';
NODE_NAME     U26 DB26
 '@T6G_MB_LIB.T6G(SCH_1):PAGE57_I32@PURE_QUANTA.GENOA_SP5(CHIPS)':
 'VDDCR_CPU1_DB26': CDS_PINID='VDDCR_CPU1_DB26';
NODE_NAME     U26 DB27
 '@T6G_MB_LIB.T6G(SCH_1):PAGE57_I32@PURE_QUANTA.GENOA_SP5(CHIPS)':
 'VDDCR_CPU1_DB27': CDS_PINID='VDDCR_CPU1_DB27';
NODE_NAME     U26 DB29
 '@T6G_MB_LIB.T6G(SCH_1):PAGE57_I32@PURE_QUANTA.GENOA_SP5(CHIPS)':
 'VDDCR_CPU1_DB29': CDS_PINID='VDDCR_CPU1_DB29';
NODE_NAME     U26 DB30
 '@T6G_MB_LIB.T6G(SCH_1):PAGE57_I32@PURE_QUANTA.GENOA_SP5(CHIPS)':
 'VDDCR_CPU1_DB30': CDS_PINID='VDDCR_CPU1_DB30';
NODE_NAME     U26 DB32
 '@T6G_MB_LIB.T6G(SCH_1):PAGE57_I32@PURE_QUANTA.GENOA_SP5(CHIPS)':
 'VDDCR_CPU1_DB32': CDS_PINID='VDDCR_CPU1_DB32';
NODE_NAME     U26 DB33
 '@T6G_MB_LIB.T6G(SCH_1):PAGE57_I32@PURE_QUANTA.GENOA_SP5(CHIPS)':
 'VDDCR_CPU1_DB33': CDS_PINID='VDDCR_CPU1_DB33';
NODE_NAME     U26 DB43
 '@T6G_MB_LIB.T6G(SCH_1):PAGE57_I32@PURE_QUANTA.GENOA_SP5(CHIPS)':
 'VDDCR_CPU1_DB43': CDS_PINID='VDDCR_CPU1_DB43';
NODE_NAME     U26 DB44
 '@T6G_MB_LIB.T6G(SCH_1):PAGE57_I32@PURE_QUANTA.GENOA_SP5(CHIPS)':
 'VDDCR_CPU1_DB44': CDS_PINID='VDDCR_CPU1_DB44';
NODE_NAME     U26 DB46
 '@T6G_MB_LIB.T6G(SCH_1):PAGE57_I32@PURE_QUANTA.GENOA_SP5(CHIPS)':
 'VDDCR_CPU1_DB46': CDS_PINID='VDDCR_CPU1_DB46';
NODE_NAME     U26 DB47
 '@T6G_MB_LIB.T6G(SCH_1):PAGE57_I32@PURE_QUANTA.GENOA_SP5(CHIPS)':
 'VDDCR_CPU1_DB47': CDS_PINID='VDDCR_CPU1_DB47';
NODE_NAME     U26 DB49
 '@T6G_MB_LIB.T6G(SCH_1):PAGE57_I32@PURE_QUANTA.GENOA_SP5(CHIPS)':
 'VDDCR_CPU1_DB49': CDS_PINID='VDDCR_CPU1_DB49';
NODE_NAME     U26 DB50
 '@T6G_MB_LIB.T6G(SCH_1):PAGE57_I32@PURE_QUANTA.GENOA_SP5(CHIPS)':
 'VDDCR_CPU1_DB50': CDS_PINID='VDDCR_CPU1_DB50';
NODE_NAME     U26 DB52
 '@T6G_MB_LIB.T6G(SCH_1):PAGE57_I32@PURE_QUANTA.GENOA_SP5(CHIPS)':
 'VDDCR_CPU1_DB52': CDS_PINID='VDDCR_CPU1_DB52';
NODE_NAME     U26 DB53
 '@T6G_MB_LIB.T6G(SCH_1):PAGE57_I32@PURE_QUANTA.GENOA_SP5(CHIPS)':
 'VDDCR_CPU1_DB53': CDS_PINID='VDDCR_CPU1_DB53';
NODE_NAME     U26 DC35
 '@T6G_MB_LIB.T6G(SCH_1):PAGE57_I32@PURE_QUANTA.GENOA_SP5(CHIPS)':
 'VDDCR_CPU1_DC35': CDS_PINID='VDDCR_CPU1_DC35';
NODE_NAME     U26 DC36
 '@T6G_MB_LIB.T6G(SCH_1):PAGE57_I32@PURE_QUANTA.GENOA_SP5(CHIPS)':
 'VDDCR_CPU1_DC36': CDS_PINID='VDDCR_CPU1_DC36';
NODE_NAME     U26 DC40
 '@T6G_MB_LIB.T6G(SCH_1):PAGE57_I32@PURE_QUANTA.GENOA_SP5(CHIPS)':
 'VDDCR_CPU1_DC40': CDS_PINID='VDDCR_CPU1_DC40';
NODE_NAME     U26 DC41
 '@T6G_MB_LIB.T6G(SCH_1):PAGE57_I32@PURE_QUANTA.GENOA_SP5(CHIPS)':
 'VDDCR_CPU1_DC41': CDS_PINID='VDDCR_CPU1_DC41';
NODE_NAME     U26 DD22
 '@T6G_MB_LIB.T6G(SCH_1):PAGE57_I32@PURE_QUANTA.GENOA_SP5(CHIPS)':
 'VDDCR_CPU1_DD22': CDS_PINID='VDDCR_CPU1_DD22';
NODE_NAME     U26 DD25
 '@T6G_MB_LIB.T6G(SCH_1):PAGE57_I32@PURE_QUANTA.GENOA_SP5(CHIPS)':
 'VDDCR_CPU1_DD25': CDS_PINID='VDDCR_CPU1_DD25';
NODE_NAME     U26 DD28
 '@T6G_MB_LIB.T6G(SCH_1):PAGE57_I32@PURE_QUANTA.GENOA_SP5(CHIPS)':
 'VDDCR_CPU1_DD28': CDS_PINID='VDDCR_CPU1_DD28';
NODE_NAME     U26 DD31
 '@T6G_MB_LIB.T6G(SCH_1):PAGE57_I32@PURE_QUANTA.GENOA_SP5(CHIPS)':
 'VDDCR_CPU1_DD31': CDS_PINID='VDDCR_CPU1_DD31';
NODE_NAME     U26 DD34
 '@T6G_MB_LIB.T6G(SCH_1):PAGE57_I32@PURE_QUANTA.GENOA_SP5(CHIPS)':
 'VDDCR_CPU1_DD34': CDS_PINID='VDDCR_CPU1_DD34';
NODE_NAME     U26 DD42
 '@T6G_MB_LIB.T6G(SCH_1):PAGE57_I32@PURE_QUANTA.GENOA_SP5(CHIPS)':
 'VDDCR_CPU1_DD42': CDS_PINID='VDDCR_CPU1_DD42';
NODE_NAME     U26 DD45
 '@T6G_MB_LIB.T6G(SCH_1):PAGE57_I32@PURE_QUANTA.GENOA_SP5(CHIPS)':
 'VDDCR_CPU1_DD45': CDS_PINID='VDDCR_CPU1_DD45';
NODE_NAME     U26 DD48
 '@T6G_MB_LIB.T6G(SCH_1):PAGE57_I32@PURE_QUANTA.GENOA_SP5(CHIPS)':
 'VDDCR_CPU1_DD48': CDS_PINID='VDDCR_CPU1_DD48';
NODE_NAME     U26 DD51
 '@T6G_MB_LIB.T6G(SCH_1):PAGE57_I32@PURE_QUANTA.GENOA_SP5(CHIPS)':
 'VDDCR_CPU1_DD51': CDS_PINID='VDDCR_CPU1_DD51';
NODE_NAME     U26 DD54
 '@T6G_MB_LIB.T6G(SCH_1):PAGE57_I32@PURE_QUANTA.GENOA_SP5(CHIPS)':
 'VDDCR_CPU1_DD54': CDS_PINID='VDDCR_CPU1_DD54';
NODE_NAME     U26 DE22
 '@T6G_MB_LIB.T6G(SCH_1):PAGE57_I32@PURE_QUANTA.GENOA_SP5(CHIPS)':
 'VDDCR_CPU1_DE22': CDS_PINID='VDDCR_CPU1_DE22';
NODE_NAME     U26 DE25
 '@T6G_MB_LIB.T6G(SCH_1):PAGE57_I32@PURE_QUANTA.GENOA_SP5(CHIPS)':
 'VDDCR_CPU1_DE25': CDS_PINID='VDDCR_CPU1_DE25';
NODE_NAME     U26 DE28
 '@T6G_MB_LIB.T6G(SCH_1):PAGE57_I32@PURE_QUANTA.GENOA_SP5(CHIPS)':
 'VDDCR_CPU1_DE28': CDS_PINID='VDDCR_CPU1_DE28';
NODE_NAME     U26 DE31
 '@T6G_MB_LIB.T6G(SCH_1):PAGE57_I32@PURE_QUANTA.GENOA_SP5(CHIPS)':
 'VDDCR_CPU1_DE31': CDS_PINID='VDDCR_CPU1_DE31';
NODE_NAME     U26 DE34
 '@T6G_MB_LIB.T6G(SCH_1):PAGE57_I32@PURE_QUANTA.GENOA_SP5(CHIPS)':
 'VDDCR_CPU1_DE34': CDS_PINID='VDDCR_CPU1_DE34';
NODE_NAME     U26 DE35
 '@T6G_MB_LIB.T6G(SCH_1):PAGE57_I32@PURE_QUANTA.GENOA_SP5(CHIPS)':
 'VDDCR_CPU1_DE35': CDS_PINID='VDDCR_CPU1_DE35';
NODE_NAME     U26 DE41
 '@T6G_MB_LIB.T6G(SCH_1):PAGE57_I32@PURE_QUANTA.GENOA_SP5(CHIPS)':
 'VDDCR_CPU1_DE41': CDS_PINID='VDDCR_CPU1_DE41';
NODE_NAME     U26 DE42
 '@T6G_MB_LIB.T6G(SCH_1):PAGE57_I32@PURE_QUANTA.GENOA_SP5(CHIPS)':
 'VDDCR_CPU1_DE42': CDS_PINID='VDDCR_CPU1_DE42';
NODE_NAME     U26 DE45
 '@T6G_MB_LIB.T6G(SCH_1):PAGE57_I32@PURE_QUANTA.GENOA_SP5(CHIPS)':
 'VDDCR_CPU1_DE45': CDS_PINID='VDDCR_CPU1_DE45';
NODE_NAME     U26 DE48
 '@T6G_MB_LIB.T6G(SCH_1):PAGE57_I32@PURE_QUANTA.GENOA_SP5(CHIPS)':
 'VDDCR_CPU1_DE48': CDS_PINID='VDDCR_CPU1_DE48';
NODE_NAME     U26 DE51
 '@T6G_MB_LIB.T6G(SCH_1):PAGE57_I32@PURE_QUANTA.GENOA_SP5(CHIPS)':
 'VDDCR_CPU1_DE51': CDS_PINID='VDDCR_CPU1_DE51';
NODE_NAME     U26 DE54
 '@T6G_MB_LIB.T6G(SCH_1):PAGE57_I32@PURE_QUANTA.GENOA_SP5(CHIPS)':
 'VDDCR_CPU1_DE54': CDS_PINID='VDDCR_CPU1_DE54';
NODE_NAME     U26 DG19
 '@T6G_MB_LIB.T6G(SCH_1):PAGE57_I32@PURE_QUANTA.GENOA_SP5(CHIPS)':
 'VDDCR_CPU1_DG19': CDS_PINID='VDDCR_CPU1_DG19';
NODE_NAME     U26 DG57
 '@T6G_MB_LIB.T6G(SCH_1):PAGE57_I32@PURE_QUANTA.GENOA_SP5(CHIPS)':
 'VDDCR_CPU1_DG57': CDS_PINID='VDDCR_CPU1_DG57';
NODE_NAME     U26 DH19
 '@T6G_MB_LIB.T6G(SCH_1):PAGE57_I32@PURE_QUANTA.GENOA_SP5(CHIPS)':
 'VDDCR_CPU1_DH19': CDS_PINID='VDDCR_CPU1_DH19';
NODE_NAME     U26 DH20
 '@T6G_MB_LIB.T6G(SCH_1):PAGE57_I32@PURE_QUANTA.GENOA_SP5(CHIPS)':
 'VDDCR_CPU1_DH20': CDS_PINID='VDDCR_CPU1_DH20';
NODE_NAME     U26 DH22
 '@T6G_MB_LIB.T6G(SCH_1):PAGE57_I32@PURE_QUANTA.GENOA_SP5(CHIPS)':
 'VDDCR_CPU1_DH22': CDS_PINID='VDDCR_CPU1_DH22';
NODE_NAME     U26 DH23
 '@T6G_MB_LIB.T6G(SCH_1):PAGE57_I32@PURE_QUANTA.GENOA_SP5(CHIPS)':
 'VDDCR_CPU1_DH23': CDS_PINID='VDDCR_CPU1_DH23';
NODE_NAME     U26 DH25
 '@T6G_MB_LIB.T6G(SCH_1):PAGE57_I32@PURE_QUANTA.GENOA_SP5(CHIPS)':
 'VDDCR_CPU1_DH25': CDS_PINID='VDDCR_CPU1_DH25';
NODE_NAME     U26 DH26
 '@T6G_MB_LIB.T6G(SCH_1):PAGE57_I32@PURE_QUANTA.GENOA_SP5(CHIPS)':
 'VDDCR_CPU1_DH26': CDS_PINID='VDDCR_CPU1_DH26';
NODE_NAME     U26 DH28
 '@T6G_MB_LIB.T6G(SCH_1):PAGE57_I32@PURE_QUANTA.GENOA_SP5(CHIPS)':
 'VDDCR_CPU1_DH28': CDS_PINID='VDDCR_CPU1_DH28';
NODE_NAME     U26 DH29
 '@T6G_MB_LIB.T6G(SCH_1):PAGE57_I32@PURE_QUANTA.GENOA_SP5(CHIPS)':
 'VDDCR_CPU1_DH29': CDS_PINID='VDDCR_CPU1_DH29';
NODE_NAME     U26 DH31
 '@T6G_MB_LIB.T6G(SCH_1):PAGE57_I32@PURE_QUANTA.GENOA_SP5(CHIPS)':
 'VDDCR_CPU1_DH31': CDS_PINID='VDDCR_CPU1_DH31';
NODE_NAME     U26 DH32
 '@T6G_MB_LIB.T6G(SCH_1):PAGE57_I32@PURE_QUANTA.GENOA_SP5(CHIPS)':
 'VDDCR_CPU1_DH32': CDS_PINID='VDDCR_CPU1_DH32';
NODE_NAME     U26 DH34
 '@T6G_MB_LIB.T6G(SCH_1):PAGE57_I32@PURE_QUANTA.GENOA_SP5(CHIPS)':
 'VDDCR_CPU1_DH34': CDS_PINID='VDDCR_CPU1_DH34';
NODE_NAME     U26 DH35
 '@T6G_MB_LIB.T6G(SCH_1):PAGE57_I32@PURE_QUANTA.GENOA_SP5(CHIPS)':
 'VDDCR_CPU1_DH35': CDS_PINID='VDDCR_CPU1_DH35';
NODE_NAME     U26 DH41
 '@T6G_MB_LIB.T6G(SCH_1):PAGE57_I32@PURE_QUANTA.GENOA_SP5(CHIPS)':
 'VDDCR_CPU1_DH41': CDS_PINID='VDDCR_CPU1_DH41';
NODE_NAME     U26 DH42
 '@T6G_MB_LIB.T6G(SCH_1):PAGE57_I32@PURE_QUANTA.GENOA_SP5(CHIPS)':
 'VDDCR_CPU1_DH42': CDS_PINID='VDDCR_CPU1_DH42';
NODE_NAME     U26 DH44
 '@T6G_MB_LIB.T6G(SCH_1):PAGE57_I32@PURE_QUANTA.GENOA_SP5(CHIPS)':
 'VDDCR_CPU1_DH44': CDS_PINID='VDDCR_CPU1_DH44';
NODE_NAME     U26 DH45
 '@T6G_MB_LIB.T6G(SCH_1):PAGE57_I32@PURE_QUANTA.GENOA_SP5(CHIPS)':
 'VDDCR_CPU1_DH45': CDS_PINID='VDDCR_CPU1_DH45';
NODE_NAME     U26 DH47
 '@T6G_MB_LIB.T6G(SCH_1):PAGE57_I32@PURE_QUANTA.GENOA_SP5(CHIPS)':
 'VDDCR_CPU1_DH47': CDS_PINID='VDDCR_CPU1_DH47';
NODE_NAME     U26 DH48
 '@T6G_MB_LIB.T6G(SCH_1):PAGE57_I32@PURE_QUANTA.GENOA_SP5(CHIPS)':
 'VDDCR_CPU1_DH48': CDS_PINID='VDDCR_CPU1_DH48';
NODE_NAME     U26 DH50
 '@T6G_MB_LIB.T6G(SCH_1):PAGE57_I32@PURE_QUANTA.GENOA_SP5(CHIPS)':
 'VDDCR_CPU1_DH50': CDS_PINID='VDDCR_CPU1_DH50';
NODE_NAME     U26 DH51
 '@T6G_MB_LIB.T6G(SCH_1):PAGE57_I32@PURE_QUANTA.GENOA_SP5(CHIPS)':
 'VDDCR_CPU1_DH51': CDS_PINID='VDDCR_CPU1_DH51';
NODE_NAME     U26 DH53
 '@T6G_MB_LIB.T6G(SCH_1):PAGE57_I32@PURE_QUANTA.GENOA_SP5(CHIPS)':
 'VDDCR_CPU1_DH53': CDS_PINID='VDDCR_CPU1_DH53';
NODE_NAME     U26 DH54
 '@T6G_MB_LIB.T6G(SCH_1):PAGE57_I32@PURE_QUANTA.GENOA_SP5(CHIPS)':
 'VDDCR_CPU1_DH54': CDS_PINID='VDDCR_CPU1_DH54';
NODE_NAME     U26 DH56
 '@T6G_MB_LIB.T6G(SCH_1):PAGE57_I32@PURE_QUANTA.GENOA_SP5(CHIPS)':
 'VDDCR_CPU1_DH56': CDS_PINID='VDDCR_CPU1_DH56';
NODE_NAME     U26 DH57
 '@T6G_MB_LIB.T6G(SCH_1):PAGE57_I32@PURE_QUANTA.GENOA_SP5(CHIPS)':
 'VDDCR_CPU1_DH57': CDS_PINID='VDDCR_CPU1_DH57';
NODE_NAME     C2354 1
 '@T6G_MB_LIB.T6G(SCH_1):PAGE72_I40@PURE_QUANTA.Q_CAP(CHIPS)':
 'A': CDS_PINID='A';
NODE_NAME     C2360 1
 '@T6G_MB_LIB.T6G(SCH_1):PAGE72_I41@PURE_QUANTA.Q_CAP(CHIPS)':
 'A': CDS_PINID='A';
NODE_NAME     C2353 1
 '@T6G_MB_LIB.T6G(SCH_1):PAGE72_I51@PURE_QUANTA.Q_CAP(CHIPS)':
 'A': CDS_PINID='A';
NODE_NAME     C2359 1
 '@T6G_MB_LIB.T6G(SCH_1):PAGE72_I53@PURE_QUANTA.Q_CAP(CHIPS)':
 'A': CDS_PINID='A';
NODE_NAME     C2352 1
 '@T6G_MB_LIB.T6G(SCH_1):PAGE72_I55@PURE_QUANTA.Q_CAP(CHIPS)':
 'A': CDS_PINID='A';
NODE_NAME     C2351 1
 '@T6G_MB_LIB.T6G(SCH_1):PAGE72_I56@PURE_QUANTA.Q_CAP(CHIPS)':
 'A': CDS_PINID='A';
NODE_NAME     C2358 1
 '@T6G_MB_LIB.T6G(SCH_1):PAGE72_I57@PURE_QUANTA.Q_CAP(CHIPS)':
 'A': CDS_PINID='A';
NODE_NAME     C2357 1
 '@T6G_MB_LIB.T6G(SCH_1):PAGE72_I58@PURE_QUANTA.Q_CAP(CHIPS)':
 'A': CDS_PINID='A';
NODE_NAME     C2356 1
 '@T6G_MB_LIB.T6G(SCH_1):PAGE72_I68@PURE_QUANTA.Q_CAP(CHIPS)':
 'A': CDS_PINID='A';
NODE_NAME     C2366 1
 '@T6G_MB_LIB.T6G(SCH_1):PAGE72_I70@PURE_QUANTA.Q_CAP(CHIPS)':
 'A': CDS_PINID='A';
NODE_NAME     C2372 1
 '@T6G_MB_LIB.T6G(SCH_1):PAGE72_I71@PURE_QUANTA.Q_CAP(CHIPS)':
 'A': CDS_PINID='A';
NODE_NAME     C2378 1
 '@T6G_MB_LIB.T6G(SCH_1):PAGE72_I72@PURE_QUANTA.Q_CAP(CHIPS)':
 'A': CDS_PINID='A';
NODE_NAME     C2365 1
 '@T6G_MB_LIB.T6G(SCH_1):PAGE72_I74@PURE_QUANTA.Q_CAP(CHIPS)':
 'A': CDS_PINID='A';
NODE_NAME     C2371 1
 '@T6G_MB_LIB.T6G(SCH_1):PAGE72_I75@PURE_QUANTA.Q_CAP(CHIPS)':
 'A': CDS_PINID='A';
NODE_NAME     C2364 1
 '@T6G_MB_LIB.T6G(SCH_1):PAGE72_I76@PURE_QUANTA.Q_CAP(CHIPS)':
 'A': CDS_PINID='A';
NODE_NAME     C2363 1
 '@T6G_MB_LIB.T6G(SCH_1):PAGE72_I77@PURE_QUANTA.Q_CAP(CHIPS)':
 'A': CDS_PINID='A';
NODE_NAME     C2370 1
 '@T6G_MB_LIB.T6G(SCH_1):PAGE72_I78@PURE_QUANTA.Q_CAP(CHIPS)':
 'A': CDS_PINID='A';
NODE_NAME     C2369 1
 '@T6G_MB_LIB.T6G(SCH_1):PAGE72_I79@PURE_QUANTA.Q_CAP(CHIPS)':
 'A': CDS_PINID='A';
NODE_NAME     C2376 1
 '@T6G_MB_LIB.T6G(SCH_1):PAGE72_I80@PURE_QUANTA.Q_CAP(CHIPS)':
 'A': CDS_PINID='A';
NODE_NAME     C2377 1
 '@T6G_MB_LIB.T6G(SCH_1):PAGE72_I81@PURE_QUANTA.Q_CAP(CHIPS)':
 'A': CDS_PINID='A';
NODE_NAME     C2383 1
 '@T6G_MB_LIB.T6G(SCH_1):PAGE72_I82@PURE_QUANTA.Q_CAP(CHIPS)':
 'A': CDS_PINID='A';
NODE_NAME     C2389 1
 '@T6G_MB_LIB.T6G(SCH_1):PAGE72_I83@PURE_QUANTA.Q_CAP(CHIPS)':
 'A': CDS_PINID='A';
NODE_NAME     C2382 1
 '@T6G_MB_LIB.T6G(SCH_1):PAGE72_I84@PURE_QUANTA.Q_CAP(CHIPS)':
 'A': CDS_PINID='A';
NODE_NAME     C2375 1
 '@T6G_MB_LIB.T6G(SCH_1):PAGE72_I85@PURE_QUANTA.Q_CAP(CHIPS)':
 'A': CDS_PINID='A';
NODE_NAME     C2381 1
 '@T6G_MB_LIB.T6G(SCH_1):PAGE72_I86@PURE_QUANTA.Q_CAP(CHIPS)':
 'A': CDS_PINID='A';
NODE_NAME     C2388 1
 '@T6G_MB_LIB.T6G(SCH_1):PAGE72_I87@PURE_QUANTA.Q_CAP(CHIPS)':
 'A': CDS_PINID='A';
NODE_NAME     C2387 1
 '@T6G_MB_LIB.T6G(SCH_1):PAGE72_I88@PURE_QUANTA.Q_CAP(CHIPS)':
 'A': CDS_PINID='A';
NODE_NAME     C2395 1
 '@T6G_MB_LIB.T6G(SCH_1):PAGE72_I89@PURE_QUANTA.Q_CAP(CHIPS)':
 'A': CDS_PINID='A';
NODE_NAME     C2400 1
 '@T6G_MB_LIB.T6G(SCH_1):PAGE72_I90@PURE_QUANTA.Q_CAP(CHIPS)':
 'A': CDS_PINID='A';
NODE_NAME     C2394 1
 '@T6G_MB_LIB.T6G(SCH_1):PAGE72_I91@PURE_QUANTA.Q_CAP(CHIPS)':
 'A': CDS_PINID='A';
NODE_NAME     C2393 1
 '@T6G_MB_LIB.T6G(SCH_1):PAGE72_I92@PURE_QUANTA.Q_CAP(CHIPS)':
 'A': CDS_PINID='A';
NODE_NAME     C2399 1
 '@T6G_MB_LIB.T6G(SCH_1):PAGE72_I93@PURE_QUANTA.Q_CAP(CHIPS)':
 'A': CDS_PINID='A';
NODE_NAME     C2398 1
 '@T6G_MB_LIB.T6G(SCH_1):PAGE72_I94@PURE_QUANTA.Q_CAP(CHIPS)':
 'A': CDS_PINID='A';
NODE_NAME     C2405 1
 '@T6G_MB_LIB.T6G(SCH_1):PAGE72_I96@PURE_QUANTA.Q_CAP(CHIPS)':
 'A': CDS_PINID='A';
NODE_NAME     C2404 1
 '@T6G_MB_LIB.T6G(SCH_1):PAGE72_I98@PURE_QUANTA.Q_CAP(CHIPS)':
 'A': CDS_PINID='A';
NODE_NAME     C2403 1
 '@T6G_MB_LIB.T6G(SCH_1):PAGE72_I100@PURE_QUANTA.Q_CAP(CHIPS)':
 'A': CDS_PINID='A';
NODE_NAME     C2362 1
 '@T6G_MB_LIB.T6G(SCH_1):PAGE72_I101@PURE_QUANTA.Q_CAP(CHIPS)':
 'A': CDS_PINID='A';
NODE_NAME     C2368 1
 '@T6G_MB_LIB.T6G(SCH_1):PAGE72_I102@PURE_QUANTA.Q_CAP(CHIPS)':
 'A': CDS_PINID='A';
NODE_NAME     C2374 1
 '@T6G_MB_LIB.T6G(SCH_1):PAGE72_I103@PURE_QUANTA.Q_CAP(CHIPS)':
 'A': CDS_PINID='A';
NODE_NAME     C2380 1
 '@T6G_MB_LIB.T6G(SCH_1):PAGE72_I104@PURE_QUANTA.Q_CAP(CHIPS)':
 'A': CDS_PINID='A';
NODE_NAME     C2386 1
 '@T6G_MB_LIB.T6G(SCH_1):PAGE72_I105@PURE_QUANTA.Q_CAP(CHIPS)':
 'A': CDS_PINID='A';
NODE_NAME     C2392 1
 '@T6G_MB_LIB.T6G(SCH_1):PAGE72_I106@PURE_QUANTA.Q_CAP(CHIPS)':
 'A': CDS_PINID='A';
NODE_NAME     C2397 1
 '@T6G_MB_LIB.T6G(SCH_1):PAGE72_I107@PURE_QUANTA.Q_CAP(CHIPS)':
 'A': CDS_PINID='A';
NODE_NAME     C2402 1
 '@T6G_MB_LIB.T6G(SCH_1):PAGE72_I109@PURE_QUANTA.Q_CAP(CHIPS)':
 'A': CDS_PINID='A';
NODE_NAME     C2350 1
 '@T6G_MB_LIB.T6G(SCH_1):PAGE72_I110@PURE_QUANTA.Q_CAP(CHIPS)':
 'A': CDS_PINID='A';
NODE_NAME     PC106 1
 '@T6G_MB_LIB.T6G(SCH_1):PAGE193_I65@PURE_QUANTA.Q_CAPP(CHIPS)':
 'A': CDS_PINID='A';
NODE_NAME     PC387 1
 '@T6G_MB_LIB.T6G(SCH_1):PAGE193_I66@PURE_QUANTA.Q_CAPP(CHIPS)':
 'A': CDS_PINID='A';
NODE_NAME     PC388 1
 '@T6G_MB_LIB.T6G(SCH_1):PAGE193_I67@PURE_QUANTA.Q_CAPP(CHIPS)':
 'A': CDS_PINID='A';
NODE_NAME     PC391 1
 '@T6G_MB_LIB.T6G(SCH_1):PAGE193_I74@PURE_QUANTA.Q_CAPP(CHIPS)':
 'A': CDS_PINID='A';
NODE_NAME     PR342 1
 '@T6G_MB_LIB.T6G(SCH_1):PAGE193_I87@PURE_QUANTA.Q_RES(CHIPS)':
 'A': CDS_PINID='A';
NODE_NAME     PR268 2
 '@T6G_MB_LIB.T6G(SCH_1):PAGE194_I38@PURE_QUANTA.Q_RES(CHIPS)':
 'B': CDS_PINID='B';
NODE_NAME     PL43 4
 '@T6G_MB_LIB.T6G(SCH_1):PAGE194_I50@PURE_QUANTA.Q_INDUCTOR4P_14(CHIPS)':
 '4': CDS_PINID='\4\';
NODE_NAME     PR228 2
 '@T6G_MB_LIB.T6G(SCH_1):PAGE192_I34@PURE_QUANTA.Q_RES(CHIPS)':
 'B': CDS_PINID='B';
NODE_NAME     PR260 2
 '@T6G_MB_LIB.T6G(SCH_1):PAGE193_I38@PURE_QUANTA.Q_RES(CHIPS)':
 'B': CDS_PINID='B';
NODE_NAME     PL41 4
 '@T6G_MB_LIB.T6G(SCH_1):PAGE193_I62@PURE_QUANTA.Q_INDUCTOR4P_14(CHIPS)':
 '4': CDS_PINID='\4\';
NODE_NAME     PR261 2
 '@T6G_MB_LIB.T6G(SCH_1):PAGE193_I64@PURE_QUANTA.Q_RES(CHIPS)':
 'B': CDS_PINID='B';
NODE_NAME     PC394_2 1
 '@T6G_MB_LIB.T6G(SCH_1):PAGE193_I68@PURE_QUANTA.Q_CAP(CHIPS)':
 'A': CDS_PINID='A';
NODE_NAME     PC397_2 1
 '@T6G_MB_LIB.T6G(SCH_1):PAGE193_I70@PURE_QUANTA.Q_CAP(CHIPS)':
 'A': CDS_PINID='A';
NODE_NAME     PC389 1
 '@T6G_MB_LIB.T6G(SCH_1):PAGE193_I73@PURE_QUANTA.Q_CAPP(CHIPS)':
 'A': CDS_PINID='A';
NODE_NAME     PL40 4
 '@T6G_MB_LIB.T6G(SCH_1):PAGE193_I77@PURE_QUANTA.Q_INDUCTOR4P_14(CHIPS)':
 '4': CDS_PINID='\4\';
NODE_NAME     PC392 1
 '@T6G_MB_LIB.T6G(SCH_1):PAGE193_I82@PURE_QUANTA.Q_CAP(CHIPS)':
 'A': CDS_PINID='A';
NODE_NAME     PC395_1 1
 '@T6G_MB_LIB.T6G(SCH_1):PAGE193_I85@PURE_QUANTA.Q_CAP(CHIPS)':
 'A': CDS_PINID='A';
NODE_NAME     PC398_1 1
 '@T6G_MB_LIB.T6G(SCH_1):PAGE193_I86@PURE_QUANTA.Q_CAP(CHIPS)':
 'A': CDS_PINID='A';
NODE_NAME     PR269 2
 '@T6G_MB_LIB.T6G(SCH_1):PAGE194_I49@PURE_QUANTA.Q_RES(CHIPS)':
 'B': CDS_PINID='B';
NODE_NAME     PL44 4
 '@T6G_MB_LIB.T6G(SCH_1):PAGE194_I62@PURE_QUANTA.Q_INDUCTOR4P_14(CHIPS)':
 '4': CDS_PINID='\4\';
NODE_NAME     PC417_3 1
 '@T6G_MB_LIB.T6G(SCH_1):PAGE194_I64@PURE_QUANTA.Q_CAP(CHIPS)':
 'A': CDS_PINID='A';
NODE_NAME     PC418_4 1
 '@T6G_MB_LIB.T6G(SCH_1):PAGE194_I65@PURE_QUANTA.Q_CAP(CHIPS)':
 'A': CDS_PINID='A';
NODE_NAME     PC420_4 1
 '@T6G_MB_LIB.T6G(SCH_1):PAGE194_I67@PURE_QUANTA.Q_CAP(CHIPS)':
 'A': CDS_PINID='A';
NODE_NAME     PC419_3 1
 '@T6G_MB_LIB.T6G(SCH_1):PAGE194_I70@PURE_QUANTA.Q_CAP(CHIPS)':
 'A': CDS_PINID='A';
NODE_NAME     PR429 2
 '@T6G_MB_LIB.T6G(SCH_1):PAGE195_I35@PURE_QUANTA.Q_RES(CHIPS)':
 'B': CDS_PINID='B';
NODE_NAME     PR273 2
 '@T6G_MB_LIB.T6G(SCH_1):PAGE195_I49@PURE_QUANTA.Q_RES(CHIPS)':
 'B': CDS_PINID='B';
NODE_NAME     PL69 4
 '@T6G_MB_LIB.T6G(SCH_1):PAGE195_I50@PURE_QUANTA.Q_INDUCTOR4P_14(CHIPS)':
 '4': CDS_PINID='\4\';
NODE_NAME     PL45 4
 '@T6G_MB_LIB.T6G(SCH_1):PAGE195_I63@PURE_QUANTA.Q_INDUCTOR4P_14(CHIPS)':
 '4': CDS_PINID='\4\';
NODE_NAME     PC148_6 1
 '@T6G_MB_LIB.T6G(SCH_1):PAGE195_I65@PURE_QUANTA.Q_CAP(CHIPS)':
 'A': CDS_PINID='A';
NODE_NAME     PC149_6 1
 '@T6G_MB_LIB.T6G(SCH_1):PAGE195_I67@PURE_QUANTA.Q_CAP(CHIPS)':
 'A': CDS_PINID='A';
NODE_NAME     PC430_5 1
 '@T6G_MB_LIB.T6G(SCH_1):PAGE195_I70@PURE_QUANTA.Q_CAP(CHIPS)':
 'A': CDS_PINID='A';
NODE_NAME     PC431_5 1
 '@T6G_MB_LIB.T6G(SCH_1):PAGE195_I71@PURE_QUANTA.Q_CAP(CHIPS)':
 'A': CDS_PINID='A';
NET_NAME
'PVDDCR_CPU1_P1_EN1_ADDR_CFG'
 '@T6G_MB_LIB.T6G(SCH_1):PVDDCR_CPU1_P1_EN1_ADDR_CFG':
 C_SIGNAL='@t6g_mb_lib.t6g(sch_1):pvddcr_cpu1_p1_en1_addr_cfg';
NODE_NAME     PR244 1
 '@T6G_MB_LIB.T6G(SCH_1):PAGE192_I12@PURE_QUANTA.Q_RES(CHIPS)':
 'A': CDS_PINID='A';
NODE_NAME     PQ12 D
 '@T6G_MB_LIB.T6G(SCH_1):PAGE192_I13@PURE_QUANTA.MOSFET_PCH_GDS_ESD_PROTECTED(CHIPS)':
 'D': CDS_PINID='D';
NODE_NAME     PU34 42
 '@T6G_MB_LIB.T6G(SCH_1):PAGE192_I128@PURE_QUANTA.RAA229620GNPHA0(CHIPS)':
 'EN1||ADDR_CFG': CDS_PINID='\en1||addr_cfg\';
NET_NAME
'PVDDCR_CPU1_P1_EN_R'
 '@T6G_MB_LIB.T6G(SCH_1):PVDDCR_CPU1_P1_EN_R':
 C_SIGNAL='@t6g_mb_lib.t6g(sch_1):pvddcr_cpu1_p1_en_r';
NODE_NAME     C8359 1
 '@T6G_MB_LIB.T6G(SCH_1):PAGE192_I85@PURE_QUANTA.Q_CAP(CHIPS)':
 'A': CDS_PINID='A';
NODE_NAME     R8235 2
 '@T6G_MB_LIB.T6G(SCH_1):PAGE192_I87@PURE_QUANTA.Q_RES(CHIPS)':
 'B': CDS_PINID='B';
NODE_NAME     PU34 17
 '@T6G_MB_LIB.T6G(SCH_1):PAGE192_I128@PURE_QUANTA.RAA229620GNPHA0(CHIPS)':
 'EN0': CDS_PINID='EN0';
NET_NAME
'PVDDCR_CPU1_P1_IMON1'
 '@T6G_MB_LIB.T6G(SCH_1):PVDDCR_CPU1_P1_IMON1':
 C_SIGNAL='@t6g_mb_lib.t6g(sch_1):pvddcr_cpu1_p1_imon1';
NODE_NAME     PU34 27
 '@T6G_MB_LIB.T6G(SCH_1):PAGE192_I128@PURE_QUANTA.RAA229620GNPHA0(CHIPS)':
 'CS11': CDS_PINID='CS11';
NODE_NAME     PU35 38
 '@T6G_MB_LIB.T6G(SCH_1):PAGE193_I91@PURE_QUANTA.ISL99390FRZTR5935(CHIPS)':
 'IOUT': CDS_PINID='IOUT';
NET_NAME
'PVDDCR_CPU1_P1_IMON2'
 '@T6G_MB_LIB.T6G(SCH_1):PVDDCR_CPU1_P1_IMON2':
 C_SIGNAL='@t6g_mb_lib.t6g(sch_1):pvddcr_cpu1_p1_imon2';
NODE_NAME     PU34 28
 '@T6G_MB_LIB.T6G(SCH_1):PAGE192_I128@PURE_QUANTA.RAA229620GNPHA0(CHIPS)':
 'CS10': CDS_PINID='CS10';
NODE_NAME     PU5 38
 '@T6G_MB_LIB.T6G(SCH_1):PAGE193_I31@PURE_QUANTA.ISL99390FRZTR5935(CHIPS)':
 'IOUT': CDS_PINID='IOUT';
NET_NAME
'PVDDCR_CPU1_P1_IMON3'
 '@T6G_MB_LIB.T6G(SCH_1):PVDDCR_CPU1_P1_IMON3':
 C_SIGNAL='@t6g_mb_lib.t6g(sch_1):pvddcr_cpu1_p1_imon3';
NODE_NAME     PU34 29
 '@T6G_MB_LIB.T6G(SCH_1):PAGE192_I128@PURE_QUANTA.RAA229620GNPHA0(CHIPS)':
 'CS9': CDS_PINID='CS9';
NODE_NAME     PU37 38
 '@T6G_MB_LIB.T6G(SCH_1):PAGE194_I72@PURE_QUANTA.ISL99390FRZTR5935(CHIPS)':
 'IOUT': CDS_PINID='IOUT';
NET_NAME
'PVDDCR_CPU1_P1_IMON4'
 '@T6G_MB_LIB.T6G(SCH_1):PVDDCR_CPU1_P1_IMON4':
 C_SIGNAL='@t6g_mb_lib.t6g(sch_1):pvddcr_cpu1_p1_imon4';
NODE_NAME     PU34 30
 '@T6G_MB_LIB.T6G(SCH_1):PAGE192_I128@PURE_QUANTA.RAA229620GNPHA0(CHIPS)':
 'CS8': CDS_PINID='CS8';
NODE_NAME     PU36 38
 '@T6G_MB_LIB.T6G(SCH_1):PAGE194_I21@PURE_QUANTA.ISL99390FRZTR5935(CHIPS)':
 'IOUT': CDS_PINID='IOUT';
NET_NAME
'PVDDCR_CPU1_P1_IMON5'
 '@T6G_MB_LIB.T6G(SCH_1):PVDDCR_CPU1_P1_IMON5':
 C_SIGNAL='@t6g_mb_lib.t6g(sch_1):pvddcr_cpu1_p1_imon5';
NODE_NAME     PU34 31
 '@T6G_MB_LIB.T6G(SCH_1):PAGE192_I128@PURE_QUANTA.RAA229620GNPHA0(CHIPS)':
 'CS7': CDS_PINID='CS7';
NODE_NAME     PU38 38
 '@T6G_MB_LIB.T6G(SCH_1):PAGE195_I73@PURE_QUANTA.ISL99390FRZTR5935(CHIPS)':
 'IOUT': CDS_PINID='IOUT';
NET_NAME
'PVDDCR_CPU1_P1_IMON6'
 '@T6G_MB_LIB.T6G(SCH_1):PVDDCR_CPU1_P1_IMON6':
 C_SIGNAL='@t6g_mb_lib.t6g(sch_1):pvddcr_cpu1_p1_imon6';
NODE_NAME     PU34 32
 '@T6G_MB_LIB.T6G(SCH_1):PAGE192_I128@PURE_QUANTA.RAA229620GNPHA0(CHIPS)':
 'CS6': CDS_PINID='CS6';
NODE_NAME     PU33 38
 '@T6G_MB_LIB.T6G(SCH_1):PAGE195_I19@PURE_QUANTA.ISL99390FRZTR5935(CHIPS)':
 'IOUT': CDS_PINID='IOUT';
NET_NAME
'PVDDCR_CPU1_P1_LSET1'
 '@T6G_MB_LIB.T6G(SCH_1):PVDDCR_CPU1_P1_LSET1':
 C_SIGNAL='@t6g_mb_lib.t6g(sch_1):pvddcr_cpu1_p1_lset1';
NODE_NAME     PR255 1
 '@T6G_MB_LIB.T6G(SCH_1):PAGE193_I17@PURE_QUANTA.Q_RES(CHIPS)':
 'A': CDS_PINID='A';
NODE_NAME     PU35 37
 '@T6G_MB_LIB.T6G(SCH_1):PAGE193_I91@PURE_QUANTA.ISL99390FRZTR5935(CHIPS)':
 'LSET': CDS_PINID='LSET';
NET_NAME
'PVDDCR_CPU1_P1_LSET2'
 '@T6G_MB_LIB.T6G(SCH_1):PVDDCR_CPU1_P1_LSET2':
 C_SIGNAL='@t6g_mb_lib.t6g(sch_1):pvddcr_cpu1_p1_lset2';
NODE_NAME     PR254 1
 '@T6G_MB_LIB.T6G(SCH_1):PAGE193_I4@PURE_QUANTA.Q_RES(CHIPS)':
 'A': CDS_PINID='A';
NODE_NAME     PU5 37
 '@T6G_MB_LIB.T6G(SCH_1):PAGE193_I31@PURE_QUANTA.ISL99390FRZTR5935(CHIPS)':
 'LSET': CDS_PINID='LSET';
NET_NAME
'PVDDCR_CPU1_P1_LSET3'
 '@T6G_MB_LIB.T6G(SCH_1):PVDDCR_CPU1_P1_LSET3':
 C_SIGNAL='@t6g_mb_lib.t6g(sch_1):pvddcr_cpu1_p1_lset3';
NODE_NAME     PR263 1
 '@T6G_MB_LIB.T6G(SCH_1):PAGE194_I18@PURE_QUANTA.Q_RES(CHIPS)':
 'A': CDS_PINID='A';
NODE_NAME     PU37 37
 '@T6G_MB_LIB.T6G(SCH_1):PAGE194_I72@PURE_QUANTA.ISL99390FRZTR5935(CHIPS)':
 'LSET': CDS_PINID='LSET';
NET_NAME
'PVDDCR_CPU1_P1_LSET4'
 '@T6G_MB_LIB.T6G(SCH_1):PVDDCR_CPU1_P1_LSET4':
 C_SIGNAL='@t6g_mb_lib.t6g(sch_1):pvddcr_cpu1_p1_lset4';
NODE_NAME     PR262 1
 '@T6G_MB_LIB.T6G(SCH_1):PAGE194_I4@PURE_QUANTA.Q_RES(CHIPS)':
 'A': CDS_PINID='A';
NODE_NAME     PU36 37
 '@T6G_MB_LIB.T6G(SCH_1):PAGE194_I21@PURE_QUANTA.ISL99390FRZTR5935(CHIPS)':
 'LSET': CDS_PINID='LSET';
NET_NAME
'PVDDCR_CPU1_P1_LSET5'
 '@T6G_MB_LIB.T6G(SCH_1):PVDDCR_CPU1_P1_LSET5':
 C_SIGNAL='@t6g_mb_lib.t6g(sch_1):pvddcr_cpu1_p1_lset5';
NODE_NAME     PR270 1
 '@T6G_MB_LIB.T6G(SCH_1):PAGE195_I15@PURE_QUANTA.Q_RES(CHIPS)':
 'A': CDS_PINID='A';
NODE_NAME     PU38 37
 '@T6G_MB_LIB.T6G(SCH_1):PAGE195_I73@PURE_QUANTA.ISL99390FRZTR5935(CHIPS)':
 'LSET': CDS_PINID='LSET';
NET_NAME
'PVDDCR_CPU1_P1_LSET6'
 '@T6G_MB_LIB.T6G(SCH_1):PVDDCR_CPU1_P1_LSET6':
 C_SIGNAL='@t6g_mb_lib.t6g(sch_1):pvddcr_cpu1_p1_lset6';
NODE_NAME     PR426 1
 '@T6G_MB_LIB.T6G(SCH_1):PAGE195_I4@PURE_QUANTA.Q_RES(CHIPS)':
 'A': CDS_PINID='A';
NODE_NAME     PU33 37
 '@T6G_MB_LIB.T6G(SCH_1):PAGE195_I19@PURE_QUANTA.ISL99390FRZTR5935(CHIPS)':
 'LSET': CDS_PINID='LSET';
NET_NAME
'PVDDCR_CPU1_P1_OCP_N'
 '@T6G_MB_LIB.T6G(SCH_1):PVDDCR_CPU1_P1_OCP_N':
 C_SIGNAL='@t6g_mb_lib.t6g(sch_1):pvddcr_cpu1_p1_ocp_n';
NODE_NAME     R141 1
 '@T6G_MB_LIB.T6G(SCH_1):PAGE81_I57@PURE_QUANTA.Q_RES(CHIPS)':
 'A': CDS_PINID='A';
NODE_NAME     R8241 1
 '@T6G_MB_LIB.T6G(SCH_1):PAGE192_I64@PURE_QUANTA.Q_RES(CHIPS)':
 'A': CDS_PINID='A';
NET_NAME
'PVDDCR_CPU1_P1_OCP_N_R'
 '@T6G_MB_LIB.T6G(SCH_1):PVDDCR_CPU1_P1_OCP_N_R':
 C_SIGNAL='@t6g_mb_lib.t6g(sch_1):pvddcr_cpu1_p1_ocp_n_r';
NODE_NAME     R8241 2
 '@T6G_MB_LIB.T6G(SCH_1):PAGE192_I64@PURE_QUANTA.Q_RES(CHIPS)':
 'B': CDS_PINID='B';
NODE_NAME     R8252 2
 '@T6G_MB_LIB.T6G(SCH_1):PAGE192_I71@PURE_QUANTA.Q_RES(CHIPS)':
 'B': CDS_PINID='B';
NODE_NAME     PU34 41
 '@T6G_MB_LIB.T6G(SCH_1):PAGE192_I128@PURE_QUANTA.RAA229620GNPHA0(CHIPS)':
 'OCP_L': CDS_PINID='OCP_L';
NET_NAME
'PVDDCR_CPU1_P1_PVCC'
 '@T6G_MB_LIB.T6G(SCH_1):PVDDCR_CPU1_P1_PVCC':
 C_SIGNAL='@t6g_mb_lib.t6g(sch_1):pvddcr_cpu1_p1_pvcc',
 CDS_GLOBAL_NET='TRUE';
NODE_NAME     PR257 1
 '@T6G_MB_LIB.T6G(SCH_1):PAGE193_I14@PURE_QUANTA.Q_RES(CHIPS)':
 'A': CDS_PINID='A';
NODE_NAME     PC423_C1P1_5 1
 '@T6G_MB_LIB.T6G(SCH_1):PAGE195_I31@PURE_QUANTA.Q_CAP(CHIPS)':
 'A': CDS_PINID='A';
NODE_NAME     PU53 4
 '@T6G_MB_LIB.T6G(SCH_1):PAGE198_I15@PURE_QUANTA.ISL99390FRZTR5935(CHIPS)':
 'PVCC': CDS_PINID='PVCC';
NODE_NAME     PC372_C1P1_2 1
 '@T6G_MB_LIB.T6G(SCH_1):PAGE193_I15@PURE_QUANTA.Q_CAP(CHIPS)':
 'A': CDS_PINID='A';
NODE_NAME     PR256 1
 '@T6G_MB_LIB.T6G(SCH_1):PAGE193_I27@PURE_QUANTA.Q_RES(CHIPS)':
 'A': CDS_PINID='A';
NODE_NAME     PC371_C1P1_1 1
 '@T6G_MB_LIB.T6G(SCH_1):PAGE193_I29@PURE_QUANTA.Q_CAP(CHIPS)':
 'A': CDS_PINID='A';
NODE_NAME     PU5 4
 '@T6G_MB_LIB.T6G(SCH_1):PAGE193_I31@PURE_QUANTA.ISL99390FRZTR5935(CHIPS)':
 'PVCC': CDS_PINID='PVCC';
NODE_NAME     PR340 1
 '@T6G_MB_LIB.T6G(SCH_1):PAGE193_I89@PURE_QUANTA.Q_RES(CHIPS)':
 'A': CDS_PINID='A';
NODE_NAME     PR341 1
 '@T6G_MB_LIB.T6G(SCH_1):PAGE193_I90@PURE_QUANTA.Q_RES(CHIPS)':
 'A': CDS_PINID='A';
NODE_NAME     PU35 4
 '@T6G_MB_LIB.T6G(SCH_1):PAGE193_I91@PURE_QUANTA.ISL99390FRZTR5935(CHIPS)':
 'PVCC': CDS_PINID='PVCC';
NODE_NAME     PR264 1
 '@T6G_MB_LIB.T6G(SCH_1):PAGE194_I13@PURE_QUANTA.Q_RES(CHIPS)':
 'A': CDS_PINID='A';
NODE_NAME     PC401_C1P1_4 1
 '@T6G_MB_LIB.T6G(SCH_1):PAGE194_I16@PURE_QUANTA.Q_CAP(CHIPS)':
 'A': CDS_PINID='A';
NODE_NAME     PU36 4
 '@T6G_MB_LIB.T6G(SCH_1):PAGE194_I21@PURE_QUANTA.ISL99390FRZTR5935(CHIPS)':
 'PVCC': CDS_PINID='PVCC';
NODE_NAME     PR265 1
 '@T6G_MB_LIB.T6G(SCH_1):PAGE194_I29@PURE_QUANTA.Q_RES(CHIPS)':
 'A': CDS_PINID='A';
NODE_NAME     PC402_C1P1_3 1
 '@T6G_MB_LIB.T6G(SCH_1):PAGE194_I31@PURE_QUANTA.Q_CAP(CHIPS)':
 'A': CDS_PINID='A';
NODE_NAME     PU37 4
 '@T6G_MB_LIB.T6G(SCH_1):PAGE194_I72@PURE_QUANTA.ISL99390FRZTR5935(CHIPS)':
 'PVCC': CDS_PINID='PVCC';
NODE_NAME     PR427 1
 '@T6G_MB_LIB.T6G(SCH_1):PAGE195_I13@PURE_QUANTA.Q_RES(CHIPS)':
 'A': CDS_PINID='A';
NODE_NAME     PU33 4
 '@T6G_MB_LIB.T6G(SCH_1):PAGE195_I19@PURE_QUANTA.ISL99390FRZTR5935(CHIPS)':
 'PVCC': CDS_PINID='PVCC';
NODE_NAME     PC139_C1P1_6 1
 '@T6G_MB_LIB.T6G(SCH_1):PAGE195_I22@PURE_QUANTA.Q_CAP(CHIPS)':
 'A': CDS_PINID='A';
NODE_NAME     PR271 1
 '@T6G_MB_LIB.T6G(SCH_1):PAGE195_I28@PURE_QUANTA.Q_RES(CHIPS)':
 'A': CDS_PINID='A';
NODE_NAME     PU38 4
 '@T6G_MB_LIB.T6G(SCH_1):PAGE195_I73@PURE_QUANTA.ISL99390FRZTR5935(CHIPS)':
 'PVCC': CDS_PINID='PVCC';
NODE_NAME     PR276 1
 '@T6G_MB_LIB.T6G(SCH_1):PAGE197_I13@PURE_QUANTA.Q_RES(CHIPS)':
 'A': CDS_PINID='A';
NODE_NAME     PC434_IOP1_2 1
 '@T6G_MB_LIB.T6G(SCH_1):PAGE197_I16@PURE_QUANTA.Q_CAP(CHIPS)':
 'A': CDS_PINID='A';
NODE_NAME     PR277 1
 '@T6G_MB_LIB.T6G(SCH_1):PAGE197_I35@PURE_QUANTA.Q_RES(CHIPS)':
 'A': CDS_PINID='A';
NODE_NAME     PC437_IOP1_1 1
 '@T6G_MB_LIB.T6G(SCH_1):PAGE197_I38@PURE_QUANTA.Q_CAP(CHIPS)':
 'A': CDS_PINID='A';
NODE_NAME     PU39 4
 '@T6G_MB_LIB.T6G(SCH_1):PAGE197_I39@PURE_QUANTA.ISL99390FRZTR5935(CHIPS)':
 'PVCC': CDS_PINID='PVCC';
NODE_NAME     PU40 4
 '@T6G_MB_LIB.T6G(SCH_1):PAGE197_I84@PURE_QUANTA.ISL99390FRZTR5935(CHIPS)':
 'PVCC': CDS_PINID='PVCC';
NODE_NAME     PR370 1
 '@T6G_MB_LIB.T6G(SCH_1):PAGE198_I12@PURE_QUANTA.Q_RES(CHIPS)':
 'A': CDS_PINID='A';
NODE_NAME     PC618_IOP1_4 1
 '@T6G_MB_LIB.T6G(SCH_1):PAGE198_I13@PURE_QUANTA.Q_CAP(CHIPS)':
 'A': CDS_PINID='A';
NODE_NAME     PR371 1
 '@T6G_MB_LIB.T6G(SCH_1):PAGE198_I29@PURE_QUANTA.Q_RES(CHIPS)':
 'A': CDS_PINID='A';
NODE_NAME     PC619_IOP1_3 1
 '@T6G_MB_LIB.T6G(SCH_1):PAGE198_I31@PURE_QUANTA.Q_CAP(CHIPS)':
 'A': CDS_PINID='A';
NODE_NAME     PU52 4
 '@T6G_MB_LIB.T6G(SCH_1):PAGE198_I73@PURE_QUANTA.ISL99390FRZTR5935(CHIPS)':
 'PVCC': CDS_PINID='PVCC';
NET_NAME
'PVDDCR_CPU1_P1_PWM1'
 '@T6G_MB_LIB.T6G(SCH_1):PVDDCR_CPU1_P1_PWM1':
 C_SIGNAL='@t6g_mb_lib.t6g(sch_1):pvddcr_cpu1_p1_pwm1';
NODE_NAME     PU34 12
 '@T6G_MB_LIB.T6G(SCH_1):PAGE192_I128@PURE_QUANTA.RAA229620GNPHA0(CHIPS)':
 'PWM11': CDS_PINID='PWM11';
NODE_NAME     PU35 34
 '@T6G_MB_LIB.T6G(SCH_1):PAGE193_I91@PURE_QUANTA.ISL99390FRZTR5935(CHIPS)':
 'PWM': CDS_PINID='PWM';
NET_NAME
'PVDDCR_CPU1_P1_PWM2'
 '@T6G_MB_LIB.T6G(SCH_1):PVDDCR_CPU1_P1_PWM2':
 C_SIGNAL='@t6g_mb_lib.t6g(sch_1):pvddcr_cpu1_p1_pwm2';
NODE_NAME     PU34 11
 '@T6G_MB_LIB.T6G(SCH_1):PAGE192_I128@PURE_QUANTA.RAA229620GNPHA0(CHIPS)':
 'PWM10': CDS_PINID='PWM10';
NODE_NAME     PU5 34
 '@T6G_MB_LIB.T6G(SCH_1):PAGE193_I31@PURE_QUANTA.ISL99390FRZTR5935(CHIPS)':
 'PWM': CDS_PINID='PWM';
NET_NAME
'PVDDCR_CPU1_P1_PWM3'
 '@T6G_MB_LIB.T6G(SCH_1):PVDDCR_CPU1_P1_PWM3':
 C_SIGNAL='@t6g_mb_lib.t6g(sch_1):pvddcr_cpu1_p1_pwm3';
NODE_NAME     PU34 10
 '@T6G_MB_LIB.T6G(SCH_1):PAGE192_I128@PURE_QUANTA.RAA229620GNPHA0(CHIPS)':
 'PWM9': CDS_PINID='PWM9';
NODE_NAME     PU37 34
 '@T6G_MB_LIB.T6G(SCH_1):PAGE194_I72@PURE_QUANTA.ISL99390FRZTR5935(CHIPS)':
 'PWM': CDS_PINID='PWM';
NET_NAME
'PVDDCR_CPU1_P1_PWM4'
 '@T6G_MB_LIB.T6G(SCH_1):PVDDCR_CPU1_P1_PWM4':
 C_SIGNAL='@t6g_mb_lib.t6g(sch_1):pvddcr_cpu1_p1_pwm4';
NODE_NAME     PU34 9
 '@T6G_MB_LIB.T6G(SCH_1):PAGE192_I128@PURE_QUANTA.RAA229620GNPHA0(CHIPS)':
 'PWM8': CDS_PINID='PWM8';
NODE_NAME     PU36 34
 '@T6G_MB_LIB.T6G(SCH_1):PAGE194_I21@PURE_QUANTA.ISL99390FRZTR5935(CHIPS)':
 'PWM': CDS_PINID='PWM';
NET_NAME
'PVDDCR_CPU1_P1_PWM5'
 '@T6G_MB_LIB.T6G(SCH_1):PVDDCR_CPU1_P1_PWM5':
 C_SIGNAL='@t6g_mb_lib.t6g(sch_1):pvddcr_cpu1_p1_pwm5';
NODE_NAME     PU34 8
 '@T6G_MB_LIB.T6G(SCH_1):PAGE192_I128@PURE_QUANTA.RAA229620GNPHA0(CHIPS)':
 'PWM7': CDS_PINID='PWM7';
NODE_NAME     PU38 34
 '@T6G_MB_LIB.T6G(SCH_1):PAGE195_I73@PURE_QUANTA.ISL99390FRZTR5935(CHIPS)':
 'PWM': CDS_PINID='PWM';
NET_NAME
'PVDDCR_CPU1_P1_PWM6'
 '@T6G_MB_LIB.T6G(SCH_1):PVDDCR_CPU1_P1_PWM6':
 C_SIGNAL='@t6g_mb_lib.t6g(sch_1):pvddcr_cpu1_p1_pwm6';
NODE_NAME     PU34 7
 '@T6G_MB_LIB.T6G(SCH_1):PAGE192_I128@PURE_QUANTA.RAA229620GNPHA0(CHIPS)':
 'PWM6': CDS_PINID='PWM6';
NODE_NAME     PU33 34
 '@T6G_MB_LIB.T6G(SCH_1):PAGE195_I19@PURE_QUANTA.ISL99390FRZTR5935(CHIPS)':
 'PWM': CDS_PINID='PWM';
NET_NAME
'PVDDCR_CPU1_P1_RESET_N'
 '@T6G_MB_LIB.T6G(SCH_1):PVDDCR_CPU1_P1_RESET_N':
 C_SIGNAL='@t6g_mb_lib.t6g(sch_1):pvddcr_cpu1_p1_reset_n';
NODE_NAME     U40 4
 '@T6G_MB_LIB.T6G(SCH_1):PAGE77_I21@PURE_QUANTA.SN74LVC2G07DCKR(CHIPS)':
 '2Y': CDS_PINID='\2y\';
NODE_NAME     R240 1
 '@T6G_MB_LIB.T6G(SCH_1):PAGE192_I65@PURE_QUANTA.Q_RES(CHIPS)':
 'A': CDS_PINID='A';
NET_NAME
'PVDDCR_CPU1_P1_RESET_N_R'
 '@T6G_MB_LIB.T6G(SCH_1):PVDDCR_CPU1_P1_RESET_N_R':
 C_SIGNAL='@t6g_mb_lib.t6g(sch_1):pvddcr_cpu1_p1_reset_n_r';
NODE_NAME     R240 2
 '@T6G_MB_LIB.T6G(SCH_1):PAGE192_I65@PURE_QUANTA.Q_RES(CHIPS)':
 'B': CDS_PINID='B';
NODE_NAME     R8247 2
 '@T6G_MB_LIB.T6G(SCH_1):PAGE192_I66@PURE_QUANTA.Q_RES(CHIPS)':
 'B': CDS_PINID='B';
NODE_NAME     PU34 18
 '@T6G_MB_LIB.T6G(SCH_1):PAGE192_I128@PURE_QUANTA.RAA229620GNPHA0(CHIPS)':
 'RESET_L': CDS_PINID='RESET_L';
NET_NAME
'PVDDCR_CPU1_P1_SMB_ALERT'
 '@T6G_MB_LIB.T6G(SCH_1):PVDDCR_CPU1_P1_SMB_ALERT':
 C_SIGNAL='@t6g_mb_lib.t6g(sch_1):pvddcr_cpu1_p1_smb_alert';
NODE_NAME     R1188 1
 '@T6G_MB_LIB.T6G(SCH_1):PAGE82_I61@PURE_QUANTA.Q_RES(CHIPS)':
 'A': CDS_PINID='A';
NODE_NAME     U18 L6
 '@T6G_MB_LIB.T6G(SCH_1):PAGE81_I143@PURE_QUANTA.LCMXO3LF9400C5BG484C(CHIPS)':
 'PL14C': CDS_PINID='PL14C';
NODE_NAME     R8250 1
 '@T6G_MB_LIB.T6G(SCH_1):PAGE192_I80@PURE_QUANTA.Q_RES(CHIPS)':
 'A': CDS_PINID='A';
NODE_NAME     C5020 2
 '@T6G_MB_LIB.T6G(SCH_1):PAGE192_I133@PURE_QUANTA.Q_CAP(CHIPS)':
 'B': CDS_PINID='B';
NET_NAME
'PVDDCR_CPU1_P1_SMB_ALERT_R'
 '@T6G_MB_LIB.T6G(SCH_1):PVDDCR_CPU1_P1_SMB_ALERT_R':
 C_SIGNAL='@t6g_mb_lib.t6g(sch_1):pvddcr_cpu1_p1_smb_alert_r';
NODE_NAME     R8250 2
 '@T6G_MB_LIB.T6G(SCH_1):PAGE192_I80@PURE_QUANTA.Q_RES(CHIPS)':
 'B': CDS_PINID='B';
NODE_NAME     PU34 15
 '@T6G_MB_LIB.T6G(SCH_1):PAGE192_I128@PURE_QUANTA.RAA229620GNPHA0(CHIPS)':
 'NPMALERT': CDS_PINID='NPMALERT';
NET_NAME
'PVDDCR_CPU1_P1_TEMP0'
 '@T6G_MB_LIB.T6G(SCH_1):PVDDCR_CPU1_P1_TEMP0':
 C_SIGNAL='@t6g_mb_lib.t6g(sch_1):pvddcr_cpu1_p1_temp0';
NODE_NAME     PC368 1
 '@T6G_MB_LIB.T6G(SCH_1):PAGE192_I73@PURE_QUANTA.Q_CAP(CHIPS)':
 'A': CDS_PINID='A';
NODE_NAME     PU34 44
 '@T6G_MB_LIB.T6G(SCH_1):PAGE192_I128@PURE_QUANTA.RAA229620GNPHA0(CHIPS)':
 'TEMP0': CDS_PINID='TEMP0';
NODE_NAME     PU5 36
 '@T6G_MB_LIB.T6G(SCH_1):PAGE193_I31@PURE_QUANTA.ISL99390FRZTR5935(CHIPS)':
 'TOUT_FLT': CDS_PINID='TOUT_FLT';
NODE_NAME     PU35 36
 '@T6G_MB_LIB.T6G(SCH_1):PAGE193_I91@PURE_QUANTA.ISL99390FRZTR5935(CHIPS)':
 'TOUT_FLT': CDS_PINID='TOUT_FLT';
NODE_NAME     PU36 36
 '@T6G_MB_LIB.T6G(SCH_1):PAGE194_I21@PURE_QUANTA.ISL99390FRZTR5935(CHIPS)':
 'TOUT_FLT': CDS_PINID='TOUT_FLT';
NODE_NAME     PU37 36
 '@T6G_MB_LIB.T6G(SCH_1):PAGE194_I72@PURE_QUANTA.ISL99390FRZTR5935(CHIPS)':
 'TOUT_FLT': CDS_PINID='TOUT_FLT';
NODE_NAME     PU33 36
 '@T6G_MB_LIB.T6G(SCH_1):PAGE195_I19@PURE_QUANTA.ISL99390FRZTR5935(CHIPS)':
 'TOUT_FLT': CDS_PINID='TOUT_FLT';
NODE_NAME     PU38 36
 '@T6G_MB_LIB.T6G(SCH_1):PAGE195_I73@PURE_QUANTA.ISL99390FRZTR5935(CHIPS)':
 'TOUT_FLT': CDS_PINID='TOUT_FLT';
NET_NAME
'PVDDCR_CPU1_P1_VCC'
 '@T6G_MB_LIB.T6G(SCH_1):PVDDCR_CPU1_P1_VCC':
 C_SIGNAL='@t6g_mb_lib.t6g(sch_1):pvddcr_cpu1_p1_vcc';
NODE_NAME     PC29 1
 '@T6G_MB_LIB.T6G(SCH_1):PAGE192_I95@PURE_QUANTA.Q_CAP(CHIPS)':
 'A': CDS_PINID='A';
NODE_NAME     PC365 1
 '@T6G_MB_LIB.T6G(SCH_1):PAGE192_I99@PURE_QUANTA.Q_CAP(CHIPS)':
 'A': CDS_PINID='A';
NODE_NAME     PR253 1
 '@T6G_MB_LIB.T6G(SCH_1):PAGE192_I124@PURE_QUANTA.Q_RES(CHIPS)':
 'A': CDS_PINID='A';
NODE_NAME     PU34 47
 '@T6G_MB_LIB.T6G(SCH_1):PAGE192_I128@PURE_QUANTA.RAA229620GNPHA0(CHIPS)':
 'VCC': CDS_PINID='VCC';
NET_NAME
'PVDDCR_CPU1_P1_VCC1'
 '@T6G_MB_LIB.T6G(SCH_1):PVDDCR_CPU1_P1_VCC1':
 C_SIGNAL='@t6g_mb_lib.t6g(sch_1):pvddcr_cpu1_p1_vcc1';
NODE_NAME     PC369 1
 '@T6G_MB_LIB.T6G(SCH_1):PAGE193_I23@PURE_QUANTA.Q_CAP(CHIPS)':
 'A': CDS_PINID='A';
NODE_NAME     PR256 2
 '@T6G_MB_LIB.T6G(SCH_1):PAGE193_I27@PURE_QUANTA.Q_RES(CHIPS)':
 'B': CDS_PINID='B';
NODE_NAME     PU35 35
 '@T6G_MB_LIB.T6G(SCH_1):PAGE193_I91@PURE_QUANTA.ISL99390FRZTR5935(CHIPS)':
 'EN': CDS_PINID='EN';
NODE_NAME     PU35 3
 '@T6G_MB_LIB.T6G(SCH_1):PAGE193_I91@PURE_QUANTA.ISL99390FRZTR5935(CHIPS)':
 'VCC': CDS_PINID='VCC';
NET_NAME
'PVDDCR_CPU1_P1_VCC2'
 '@T6G_MB_LIB.T6G(SCH_1):PVDDCR_CPU1_P1_VCC2':
 C_SIGNAL='@t6g_mb_lib.t6g(sch_1):pvddcr_cpu1_p1_vcc2';
NODE_NAME     PR257 2
 '@T6G_MB_LIB.T6G(SCH_1):PAGE193_I14@PURE_QUANTA.Q_RES(CHIPS)':
 'B': CDS_PINID='B';
NODE_NAME     PC370 1
 '@T6G_MB_LIB.T6G(SCH_1):PAGE193_I12@PURE_QUANTA.Q_CAP(CHIPS)':
 'A': CDS_PINID='A';
NODE_NAME     PU5 35
 '@T6G_MB_LIB.T6G(SCH_1):PAGE193_I31@PURE_QUANTA.ISL99390FRZTR5935(CHIPS)':
 'EN': CDS_PINID='EN';
NODE_NAME     PU5 3
 '@T6G_MB_LIB.T6G(SCH_1):PAGE193_I31@PURE_QUANTA.ISL99390FRZTR5935(CHIPS)':
 'VCC': CDS_PINID='VCC';
NET_NAME
'PVDDCR_CPU1_P1_VCC3'
 '@T6G_MB_LIB.T6G(SCH_1):PVDDCR_CPU1_P1_VCC3':
 C_SIGNAL='@t6g_mb_lib.t6g(sch_1):pvddcr_cpu1_p1_vcc3';
NODE_NAME     PC400 1
 '@T6G_MB_LIB.T6G(SCH_1):PAGE194_I27@PURE_QUANTA.Q_CAP(CHIPS)':
 'A': CDS_PINID='A';
NODE_NAME     PR265 2
 '@T6G_MB_LIB.T6G(SCH_1):PAGE194_I29@PURE_QUANTA.Q_RES(CHIPS)':
 'B': CDS_PINID='B';
NODE_NAME     PU37 35
 '@T6G_MB_LIB.T6G(SCH_1):PAGE194_I72@PURE_QUANTA.ISL99390FRZTR5935(CHIPS)':
 'EN': CDS_PINID='EN';
NODE_NAME     PU37 3
 '@T6G_MB_LIB.T6G(SCH_1):PAGE194_I72@PURE_QUANTA.ISL99390FRZTR5935(CHIPS)':
 'VCC': CDS_PINID='VCC';
NET_NAME
'PVDDCR_CPU1_P1_VCC4'
 '@T6G_MB_LIB.T6G(SCH_1):PVDDCR_CPU1_P1_VCC4':
 C_SIGNAL='@t6g_mb_lib.t6g(sch_1):pvddcr_cpu1_p1_vcc4';
NODE_NAME     PC399 1
 '@T6G_MB_LIB.T6G(SCH_1):PAGE194_I7@PURE_QUANTA.Q_CAP(CHIPS)':
 'A': CDS_PINID='A';
NODE_NAME     PR264 2
 '@T6G_MB_LIB.T6G(SCH_1):PAGE194_I13@PURE_QUANTA.Q_RES(CHIPS)':
 'B': CDS_PINID='B';
NODE_NAME     PU36 35
 '@T6G_MB_LIB.T6G(SCH_1):PAGE194_I21@PURE_QUANTA.ISL99390FRZTR5935(CHIPS)':
 'EN': CDS_PINID='EN';
NODE_NAME     PU36 3
 '@T6G_MB_LIB.T6G(SCH_1):PAGE194_I21@PURE_QUANTA.ISL99390FRZTR5935(CHIPS)':
 'VCC': CDS_PINID='VCC';
NET_NAME
'PVDDCR_CPU1_P1_VCC5'
 '@T6G_MB_LIB.T6G(SCH_1):PVDDCR_CPU1_P1_VCC5':
 C_SIGNAL='@t6g_mb_lib.t6g(sch_1):pvddcr_cpu1_p1_vcc5';
NODE_NAME     PC421 1
 '@T6G_MB_LIB.T6G(SCH_1):PAGE195_I27@PURE_QUANTA.Q_CAP(CHIPS)':
 'A': CDS_PINID='A';
NODE_NAME     PR271 2
 '@T6G_MB_LIB.T6G(SCH_1):PAGE195_I28@PURE_QUANTA.Q_RES(CHIPS)':
 'B': CDS_PINID='B';
NODE_NAME     PU38 35
 '@T6G_MB_LIB.T6G(SCH_1):PAGE195_I73@PURE_QUANTA.ISL99390FRZTR5935(CHIPS)':
 'EN': CDS_PINID='EN';
NODE_NAME     PU38 3
 '@T6G_MB_LIB.T6G(SCH_1):PAGE195_I73@PURE_QUANTA.ISL99390FRZTR5935(CHIPS)':
 'VCC': CDS_PINID='VCC';
NET_NAME
'PVDDCR_CPU1_P1_VCC6'
 '@T6G_MB_LIB.T6G(SCH_1):PVDDCR_CPU1_P1_VCC6':
 C_SIGNAL='@t6g_mb_lib.t6g(sch_1):pvddcr_cpu1_p1_vcc6';
NODE_NAME     PC138 1
 '@T6G_MB_LIB.T6G(SCH_1):PAGE195_I12@PURE_QUANTA.Q_CAP(CHIPS)':
 'A': CDS_PINID='A';
NODE_NAME     PR427 2
 '@T6G_MB_LIB.T6G(SCH_1):PAGE195_I13@PURE_QUANTA.Q_RES(CHIPS)':
 'B': CDS_PINID='B';
NODE_NAME     PU33 35
 '@T6G_MB_LIB.T6G(SCH_1):PAGE195_I19@PURE_QUANTA.ISL99390FRZTR5935(CHIPS)':
 'EN': CDS_PINID='EN';
NODE_NAME     PU33 3
 '@T6G_MB_LIB.T6G(SCH_1):PAGE195_I19@PURE_QUANTA.ISL99390FRZTR5935(CHIPS)':
 'VCC': CDS_PINID='VCC';
NET_NAME
'PVDDCR_CPU1_P1_VCCS'
 '@T6G_MB_LIB.T6G(SCH_1):PVDDCR_CPU1_P1_VCCS':
 C_SIGNAL='@t6g_mb_lib.t6g(sch_1):pvddcr_cpu1_p1_vccs';
NODE_NAME     PC373_2 1
 '@T6G_MB_LIB.T6G(SCH_1):PAGE193_I2@PURE_QUANTA.Q_CAP(CHIPS)':
 'A': CDS_PINID='A';
NODE_NAME     PC403_4 1
 '@T6G_MB_LIB.T6G(SCH_1):PAGE194_I2@PURE_QUANTA.Q_CAP(CHIPS)':
 'A': CDS_PINID='A';
NODE_NAME     PC621_10 1
 '@T6G_MB_LIB.T6G(SCH_1):PAGE198_I2@PURE_QUANTA.Q_CAP(CHIPS)':
 'A': CDS_PINID='A';
NODE_NAME     PU53 39
 '@T6G_MB_LIB.T6G(SCH_1):PAGE198_I15@PURE_QUANTA.ISL99390FRZTR5935(CHIPS)':
 'REFIN': CDS_PINID='REFIN';
NODE_NAME     PC93 1
 '@T6G_MB_LIB.T6G(SCH_1):PAGE192_I93@PURE_QUANTA.Q_CAP(CHIPS)':
 'A': CDS_PINID='A';
NODE_NAME     PC366 1
 '@T6G_MB_LIB.T6G(SCH_1):PAGE192_I97@PURE_QUANTA.Q_CAP(CHIPS)':
 'A': CDS_PINID='A';
NODE_NAME     PU34 48
 '@T6G_MB_LIB.T6G(SCH_1):PAGE192_I128@PURE_QUANTA.RAA229620GNPHA0(CHIPS)':
 'VCCS': CDS_PINID='VCCS';
NODE_NAME     PC374_1 1
 '@T6G_MB_LIB.T6G(SCH_1):PAGE193_I11@PURE_QUANTA.Q_CAP(CHIPS)':
 'A': CDS_PINID='A';
NODE_NAME     PU5 39
 '@T6G_MB_LIB.T6G(SCH_1):PAGE193_I31@PURE_QUANTA.ISL99390FRZTR5935(CHIPS)':
 'REFIN': CDS_PINID='REFIN';
NODE_NAME     PU35 39
 '@T6G_MB_LIB.T6G(SCH_1):PAGE193_I91@PURE_QUANTA.ISL99390FRZTR5935(CHIPS)':
 'REFIN': CDS_PINID='REFIN';
NODE_NAME     PC404_3 1
 '@T6G_MB_LIB.T6G(SCH_1):PAGE194_I12@PURE_QUANTA.Q_CAP(CHIPS)':
 'A': CDS_PINID='A';
NODE_NAME     PU36 39
 '@T6G_MB_LIB.T6G(SCH_1):PAGE194_I21@PURE_QUANTA.ISL99390FRZTR5935(CHIPS)':
 'REFIN': CDS_PINID='REFIN';
NODE_NAME     PU37 39
 '@T6G_MB_LIB.T6G(SCH_1):PAGE194_I72@PURE_QUANTA.ISL99390FRZTR5935(CHIPS)':
 'REFIN': CDS_PINID='REFIN';
NODE_NAME     PC136_6 1
 '@T6G_MB_LIB.T6G(SCH_1):PAGE195_I1@PURE_QUANTA.Q_CAP(CHIPS)':
 'A': CDS_PINID='A';
NODE_NAME     PC422_5 1
 '@T6G_MB_LIB.T6G(SCH_1):PAGE195_I10@PURE_QUANTA.Q_CAP(CHIPS)':
 'A': CDS_PINID='A';
NODE_NAME     PU33 39
 '@T6G_MB_LIB.T6G(SCH_1):PAGE195_I19@PURE_QUANTA.ISL99390FRZTR5935(CHIPS)':
 'REFIN': CDS_PINID='REFIN';
NODE_NAME     PU38 39
 '@T6G_MB_LIB.T6G(SCH_1):PAGE195_I73@PURE_QUANTA.ISL99390FRZTR5935(CHIPS)':
 'REFIN': CDS_PINID='REFIN';
NODE_NAME     PC436_8 1
 '@T6G_MB_LIB.T6G(SCH_1):PAGE197_I3@PURE_QUANTA.Q_CAP(CHIPS)':
 'A': CDS_PINID='A';
NODE_NAME     PC435_7 1
 '@T6G_MB_LIB.T6G(SCH_1):PAGE197_I4@PURE_QUANTA.Q_CAP(CHIPS)':
 'A': CDS_PINID='A';
NODE_NAME     PU39 39
 '@T6G_MB_LIB.T6G(SCH_1):PAGE197_I39@PURE_QUANTA.ISL99390FRZTR5935(CHIPS)':
 'REFIN': CDS_PINID='REFIN';
NODE_NAME     PU40 39
 '@T6G_MB_LIB.T6G(SCH_1):PAGE197_I84@PURE_QUANTA.ISL99390FRZTR5935(CHIPS)':
 'REFIN': CDS_PINID='REFIN';
NODE_NAME     PC620_9 1
 '@T6G_MB_LIB.T6G(SCH_1):PAGE198_I20@PURE_QUANTA.Q_CAP(CHIPS)':
 'A': CDS_PINID='A';
NODE_NAME     PU52 39
 '@T6G_MB_LIB.T6G(SCH_1):PAGE198_I73@PURE_QUANTA.ISL99390FRZTR5935(CHIPS)':
 'REFIN': CDS_PINID='REFIN';
NET_NAME
'PVDDCR_CPU1_P1_VINSEN'
 '@T6G_MB_LIB.T6G(SCH_1):PVDDCR_CPU1_P1_VINSEN':
 C_SIGNAL='@t6g_mb_lib.t6g(sch_1):pvddcr_cpu1_p1_vinsen';
NODE_NAME     PR251 2
 '@T6G_MB_LIB.T6G(SCH_1):PAGE192_I49@PURE_QUANTA.Q_RES(CHIPS)':
 'B': CDS_PINID='B';
NODE_NAME     PR603 1
 '@T6G_MB_LIB.T6G(SCH_1):PAGE192_I55@PURE_QUANTA.Q_RES(CHIPS)':
 'A': CDS_PINID='A';
NODE_NAME     PC364 1
 '@T6G_MB_LIB.T6G(SCH_1):PAGE192_I56@PURE_QUANTA.Q_CAP(CHIPS)':
 'A': CDS_PINID='A';
NODE_NAME     PU34 46
 '@T6G_MB_LIB.T6G(SCH_1):PAGE192_I128@PURE_QUANTA.RAA229620GNPHA0(CHIPS)':
 'VINSEN': CDS_PINID='VINSEN';
NET_NAME
'PVDDCR_CPU1_P1_VMON'
 '@T6G_MB_LIB.T6G(SCH_1):PVDDCR_CPU1_P1_VMON':
 C_SIGNAL='@t6g_mb_lib.t6g(sch_1):pvddcr_cpu1_p1_vmon';
NODE_NAME     PR231 1
 '@T6G_MB_LIB.T6G(SCH_1):PAGE192_I8@PURE_QUANTA.Q_RES(CHIPS)':
 'A': CDS_PINID='A';
NODE_NAME     PR230 2
 '@T6G_MB_LIB.T6G(SCH_1):PAGE192_I9@PURE_QUANTA.Q_RES(CHIPS)':
 'B': CDS_PINID='B';
NODE_NAME     PC357 1
 '@T6G_MB_LIB.T6G(SCH_1):PAGE192_I47@PURE_QUANTA.Q_CAP(CHIPS)':
 'A': CDS_PINID='A';
NODE_NAME     PU34 45
 '@T6G_MB_LIB.T6G(SCH_1):PAGE192_I128@PURE_QUANTA.RAA229620GNPHA0(CHIPS)':
 'VMON||IINSEN': CDS_PINID='\vmon||iinsen\';
NET_NAME
'PVDDCR_CPU1_P1_VOS1'
 '@T6G_MB_LIB.T6G(SCH_1):PVDDCR_CPU1_P1_VOS1':
 C_SIGNAL='@t6g_mb_lib.t6g(sch_1):pvddcr_cpu1_p1_vos1';
NODE_NAME     PR261 1
 '@T6G_MB_LIB.T6G(SCH_1):PAGE193_I64@PURE_QUANTA.Q_RES(CHIPS)':
 'A': CDS_PINID='A';
NODE_NAME     PU35 1
 '@T6G_MB_LIB.T6G(SCH_1):PAGE193_I91@PURE_QUANTA.ISL99390FRZTR5935(CHIPS)':
 'VOS': CDS_PINID='VOS';
NET_NAME
'PVDDCR_CPU1_P1_VOS2'
 '@T6G_MB_LIB.T6G(SCH_1):PVDDCR_CPU1_P1_VOS2':
 C_SIGNAL='@t6g_mb_lib.t6g(sch_1):pvddcr_cpu1_p1_vos2';
NODE_NAME     PU5 1
 '@T6G_MB_LIB.T6G(SCH_1):PAGE193_I31@PURE_QUANTA.ISL99390FRZTR5935(CHIPS)':
 'VOS': CDS_PINID='VOS';
NODE_NAME     PR260 1
 '@T6G_MB_LIB.T6G(SCH_1):PAGE193_I38@PURE_QUANTA.Q_RES(CHIPS)':
 'A': CDS_PINID='A';
NET_NAME
'PVDDCR_CPU1_P1_VOS3'
 '@T6G_MB_LIB.T6G(SCH_1):PVDDCR_CPU1_P1_VOS3':
 C_SIGNAL='@t6g_mb_lib.t6g(sch_1):pvddcr_cpu1_p1_vos3';
NODE_NAME     PR269 1
 '@T6G_MB_LIB.T6G(SCH_1):PAGE194_I49@PURE_QUANTA.Q_RES(CHIPS)':
 'A': CDS_PINID='A';
NODE_NAME     PU37 1
 '@T6G_MB_LIB.T6G(SCH_1):PAGE194_I72@PURE_QUANTA.ISL99390FRZTR5935(CHIPS)':
 'VOS': CDS_PINID='VOS';
NET_NAME
'PVDDCR_CPU1_P1_VOS4'
 '@T6G_MB_LIB.T6G(SCH_1):PVDDCR_CPU1_P1_VOS4':
 C_SIGNAL='@t6g_mb_lib.t6g(sch_1):pvddcr_cpu1_p1_vos4';
NODE_NAME     PR268 1
 '@T6G_MB_LIB.T6G(SCH_1):PAGE194_I38@PURE_QUANTA.Q_RES(CHIPS)':
 'A': CDS_PINID='A';
NODE_NAME     PU36 1
 '@T6G_MB_LIB.T6G(SCH_1):PAGE194_I21@PURE_QUANTA.ISL99390FRZTR5935(CHIPS)':
 'VOS': CDS_PINID='VOS';
NET_NAME
'PVDDCR_CPU1_P1_VOS5'
 '@T6G_MB_LIB.T6G(SCH_1):PVDDCR_CPU1_P1_VOS5':
 C_SIGNAL='@t6g_mb_lib.t6g(sch_1):pvddcr_cpu1_p1_vos5';
NODE_NAME     PR273 1
 '@T6G_MB_LIB.T6G(SCH_1):PAGE195_I49@PURE_QUANTA.Q_RES(CHIPS)':
 'A': CDS_PINID='A';
NODE_NAME     PU38 1
 '@T6G_MB_LIB.T6G(SCH_1):PAGE195_I73@PURE_QUANTA.ISL99390FRZTR5935(CHIPS)':
 'VOS': CDS_PINID='VOS';
NET_NAME
'PVDDCR_CPU1_P1_VOS6'
 '@T6G_MB_LIB.T6G(SCH_1):PVDDCR_CPU1_P1_VOS6':
 C_SIGNAL='@t6g_mb_lib.t6g(sch_1):pvddcr_cpu1_p1_vos6';
NODE_NAME     PU33 1
 '@T6G_MB_LIB.T6G(SCH_1):PAGE195_I19@PURE_QUANTA.ISL99390FRZTR5935(CHIPS)':
 'VOS': CDS_PINID='VOS';
NODE_NAME     PR429 1
 '@T6G_MB_LIB.T6G(SCH_1):PAGE195_I35@PURE_QUANTA.Q_RES(CHIPS)':
 'A': CDS_PINID='A';
NET_NAME
'PVDDCR_SOC_P0'
 '@T6G_MB_LIB.T6G(SCH_1):PVDDCR_SOC_P0':
 C_SIGNAL='@t6g_mb_lib.t6g(sch_1):pvddcr_soc_p0',
 CDS_GLOBAL_NET='TRUE';
NODE_NAME     U25 AA22
 '@T6G_MB_LIB.T6G(SCH_1):PAGE30_I50@PURE_QUANTA.GENOA_SP5(CHIPS)':
 'VDDCR_SOC_AA22': CDS_PINID='VDDCR_SOC_AA22';
NODE_NAME     U25 AC4
 '@T6G_MB_LIB.T6G(SCH_1):PAGE30_I50@PURE_QUANTA.GENOA_SP5(CHIPS)':
 'VDDCR_SOC_AC4': CDS_PINID='VDDCR_SOC_AC4';
NODE_NAME     U25 AC11
 '@T6G_MB_LIB.T6G(SCH_1):PAGE30_I50@PURE_QUANTA.GENOA_SP5(CHIPS)':
 'VDDCR_SOC_AC11': CDS_PINID='VDDCR_SOC_AC11';
NODE_NAME     U25 AC18
 '@T6G_MB_LIB.T6G(SCH_1):PAGE30_I50@PURE_QUANTA.GENOA_SP5(CHIPS)':
 'VDDCR_SOC_AC18': CDS_PINID='VDDCR_SOC_AC18';
NODE_NAME     U25 AD22
 '@T6G_MB_LIB.T6G(SCH_1):PAGE30_I50@PURE_QUANTA.GENOA_SP5(CHIPS)':
 'VDDCR_SOC_AD22': CDS_PINID='VDDCR_SOC_AD22';
NODE_NAME     U25 AF5
 '@T6G_MB_LIB.T6G(SCH_1):PAGE30_I50@PURE_QUANTA.GENOA_SP5(CHIPS)':
 'VDDCR_SOC_AF5': CDS_PINID='VDDCR_SOC_AF5';
NODE_NAME     U25 AF12
 '@T6G_MB_LIB.T6G(SCH_1):PAGE30_I50@PURE_QUANTA.GENOA_SP5(CHIPS)':
 'VDDCR_SOC_AF12': CDS_PINID='VDDCR_SOC_AF12';
NODE_NAME     U25 AF19
 '@T6G_MB_LIB.T6G(SCH_1):PAGE30_I50@PURE_QUANTA.GENOA_SP5(CHIPS)':
 'VDDCR_SOC_AF19': CDS_PINID='VDDCR_SOC_AF19';
NODE_NAME     U25 AH22
 '@T6G_MB_LIB.T6G(SCH_1):PAGE30_I50@PURE_QUANTA.GENOA_SP5(CHIPS)':
 'VDDCR_SOC_AH22': CDS_PINID='VDDCR_SOC_AH22';
NODE_NAME     U25 AJ4
 '@T6G_MB_LIB.T6G(SCH_1):PAGE30_I50@PURE_QUANTA.GENOA_SP5(CHIPS)':
 'VDDCR_SOC_AJ4': CDS_PINID='VDDCR_SOC_AJ4';
NODE_NAME     U25 AJ11
 '@T6G_MB_LIB.T6G(SCH_1):PAGE30_I50@PURE_QUANTA.GENOA_SP5(CHIPS)':
 'VDDCR_SOC_AJ11': CDS_PINID='VDDCR_SOC_AJ11';
NODE_NAME     U25 AJ18
 '@T6G_MB_LIB.T6G(SCH_1):PAGE30_I50@PURE_QUANTA.GENOA_SP5(CHIPS)':
 'VDDCR_SOC_AJ18': CDS_PINID='VDDCR_SOC_AJ18';
NODE_NAME     U25 AM5
 '@T6G_MB_LIB.T6G(SCH_1):PAGE30_I50@PURE_QUANTA.GENOA_SP5(CHIPS)':
 'VDDCR_SOC_AM5': CDS_PINID='VDDCR_SOC_AM5';
NODE_NAME     U25 AM12
 '@T6G_MB_LIB.T6G(SCH_1):PAGE30_I50@PURE_QUANTA.GENOA_SP5(CHIPS)':
 'VDDCR_SOC_AM12': CDS_PINID='VDDCR_SOC_AM12';
NODE_NAME     U25 AM19
 '@T6G_MB_LIB.T6G(SCH_1):PAGE30_I50@PURE_QUANTA.GENOA_SP5(CHIPS)':
 'VDDCR_SOC_AM19': CDS_PINID='VDDCR_SOC_AM19';
NODE_NAME     U25 AM22
 '@T6G_MB_LIB.T6G(SCH_1):PAGE30_I50@PURE_QUANTA.GENOA_SP5(CHIPS)':
 'VDDCR_SOC_AM22': CDS_PINID='VDDCR_SOC_AM22';
NODE_NAME     U25 AR4
 '@T6G_MB_LIB.T6G(SCH_1):PAGE30_I50@PURE_QUANTA.GENOA_SP5(CHIPS)':
 'VDDCR_SOC_AR4': CDS_PINID='VDDCR_SOC_AR4';
NODE_NAME     U25 AR11
 '@T6G_MB_LIB.T6G(SCH_1):PAGE30_I50@PURE_QUANTA.GENOA_SP5(CHIPS)':
 'VDDCR_SOC_AR11': CDS_PINID='VDDCR_SOC_AR11';
NODE_NAME     U25 AR18
 '@T6G_MB_LIB.T6G(SCH_1):PAGE30_I50@PURE_QUANTA.GENOA_SP5(CHIPS)':
 'VDDCR_SOC_AR18': CDS_PINID='VDDCR_SOC_AR18';
NODE_NAME     U25 AT22
 '@T6G_MB_LIB.T6G(SCH_1):PAGE30_I50@PURE_QUANTA.GENOA_SP5(CHIPS)':
 'VDDCR_SOC_AT22': CDS_PINID='VDDCR_SOC_AT22';
NODE_NAME     U25 AU23
 '@T6G_MB_LIB.T6G(SCH_1):PAGE30_I50@PURE_QUANTA.GENOA_SP5(CHIPS)':
 'VDDCR_SOC_AU23': CDS_PINID='VDDCR_SOC_AU23';
NODE_NAME     U25 AU27
 '@T6G_MB_LIB.T6G(SCH_1):PAGE30_I50@PURE_QUANTA.GENOA_SP5(CHIPS)':
 'VDDCR_SOC_AU27': CDS_PINID='VDDCR_SOC_AU27';
NODE_NAME     U25 AU31
 '@T6G_MB_LIB.T6G(SCH_1):PAGE30_I50@PURE_QUANTA.GENOA_SP5(CHIPS)':
 'VDDCR_SOC_AU31': CDS_PINID='VDDCR_SOC_AU31';
NODE_NAME     U25 AU35
 '@T6G_MB_LIB.T6G(SCH_1):PAGE30_I50@PURE_QUANTA.GENOA_SP5(CHIPS)':
 'VDDCR_SOC_AU35': CDS_PINID='VDDCR_SOC_AU35';
NODE_NAME     U25 AU40
 '@T6G_MB_LIB.T6G(SCH_1):PAGE30_I50@PURE_QUANTA.GENOA_SP5(CHIPS)':
 'VDDCR_SOC_AU40': CDS_PINID='VDDCR_SOC_AU40';
NODE_NAME     U25 AV5
 '@T6G_MB_LIB.T6G(SCH_1):PAGE30_I50@PURE_QUANTA.GENOA_SP5(CHIPS)':
 'VDDCR_SOC_AV5': CDS_PINID='VDDCR_SOC_AV5';
NODE_NAME     U25 AV12
 '@T6G_MB_LIB.T6G(SCH_1):PAGE30_I50@PURE_QUANTA.GENOA_SP5(CHIPS)':
 'VDDCR_SOC_AV12': CDS_PINID='VDDCR_SOC_AV12';
NODE_NAME     U25 AV19
 '@T6G_MB_LIB.T6G(SCH_1):PAGE30_I50@PURE_QUANTA.GENOA_SP5(CHIPS)':
 'VDDCR_SOC_AV19': CDS_PINID='VDDCR_SOC_AV19';
NODE_NAME     U25 AV22
 '@T6G_MB_LIB.T6G(SCH_1):PAGE30_I50@PURE_QUANTA.GENOA_SP5(CHIPS)':
 'VDDCR_SOC_AV22': CDS_PINID='VDDCR_SOC_AV22';
NODE_NAME     U25 AV24
 '@T6G_MB_LIB.T6G(SCH_1):PAGE30_I50@PURE_QUANTA.GENOA_SP5(CHIPS)':
 'VDDCR_SOC_AV24': CDS_PINID='VDDCR_SOC_AV24';
NODE_NAME     U25 AV26
 '@T6G_MB_LIB.T6G(SCH_1):PAGE30_I50@PURE_QUANTA.GENOA_SP5(CHIPS)':
 'VDDCR_SOC_AV26': CDS_PINID='VDDCR_SOC_AV26';
NODE_NAME     U25 AV28
 '@T6G_MB_LIB.T6G(SCH_1):PAGE30_I50@PURE_QUANTA.GENOA_SP5(CHIPS)':
 'VDDCR_SOC_AV28': CDS_PINID='VDDCR_SOC_AV28';
NODE_NAME     U25 AV30
 '@T6G_MB_LIB.T6G(SCH_1):PAGE30_I50@PURE_QUANTA.GENOA_SP5(CHIPS)':
 'VDDCR_SOC_AV30': CDS_PINID='VDDCR_SOC_AV30';
NODE_NAME     U25 AV32
 '@T6G_MB_LIB.T6G(SCH_1):PAGE30_I50@PURE_QUANTA.GENOA_SP5(CHIPS)':
 'VDDCR_SOC_AV32': CDS_PINID='VDDCR_SOC_AV32';
NODE_NAME     U25 AV34
 '@T6G_MB_LIB.T6G(SCH_1):PAGE30_I50@PURE_QUANTA.GENOA_SP5(CHIPS)':
 'VDDCR_SOC_AV34': CDS_PINID='VDDCR_SOC_AV34';
NODE_NAME     U25 AV36
 '@T6G_MB_LIB.T6G(SCH_1):PAGE30_I50@PURE_QUANTA.GENOA_SP5(CHIPS)':
 'VDDCR_SOC_AV36': CDS_PINID='VDDCR_SOC_AV36';
NODE_NAME     U25 AV39
 '@T6G_MB_LIB.T6G(SCH_1):PAGE30_I50@PURE_QUANTA.GENOA_SP5(CHIPS)':
 'VDDCR_SOC_AV39': CDS_PINID='VDDCR_SOC_AV39';
NODE_NAME     U25 AV41
 '@T6G_MB_LIB.T6G(SCH_1):PAGE30_I50@PURE_QUANTA.GENOA_SP5(CHIPS)':
 'VDDCR_SOC_AV41': CDS_PINID='VDDCR_SOC_AV41';
NODE_NAME     U25 AV43
 '@T6G_MB_LIB.T6G(SCH_1):PAGE30_I50@PURE_QUANTA.GENOA_SP5(CHIPS)':
 'VDDCR_SOC_AV43': CDS_PINID='VDDCR_SOC_AV43';
NODE_NAME     U25 AV45
 '@T6G_MB_LIB.T6G(SCH_1):PAGE30_I50@PURE_QUANTA.GENOA_SP5(CHIPS)':
 'VDDCR_SOC_AV45': CDS_PINID='VDDCR_SOC_AV45';
NODE_NAME     U25 AV47
 '@T6G_MB_LIB.T6G(SCH_1):PAGE30_I50@PURE_QUANTA.GENOA_SP5(CHIPS)':
 'VDDCR_SOC_AV47': CDS_PINID='VDDCR_SOC_AV47';
NODE_NAME     U25 AW23
 '@T6G_MB_LIB.T6G(SCH_1):PAGE30_I50@PURE_QUANTA.GENOA_SP5(CHIPS)':
 'VDDCR_SOC_AW23': CDS_PINID='VDDCR_SOC_AW23';
NODE_NAME     U25 AW25
 '@T6G_MB_LIB.T6G(SCH_1):PAGE30_I50@PURE_QUANTA.GENOA_SP5(CHIPS)':
 'VDDCR_SOC_AW25': CDS_PINID='VDDCR_SOC_AW25';
NODE_NAME     U25 AW27
 '@T6G_MB_LIB.T6G(SCH_1):PAGE30_I50@PURE_QUANTA.GENOA_SP5(CHIPS)':
 'VDDCR_SOC_AW27': CDS_PINID='VDDCR_SOC_AW27';
NODE_NAME     U25 AW48
 '@T6G_MB_LIB.T6G(SCH_1):PAGE30_I50@PURE_QUANTA.GENOA_SP5(CHIPS)':
 'VDDCR_SOC_AW48': CDS_PINID='VDDCR_SOC_AW48';
NODE_NAME     U25 AY22
 '@T6G_MB_LIB.T6G(SCH_1):PAGE30_I50@PURE_QUANTA.GENOA_SP5(CHIPS)':
 'VDDCR_SOC_AY22': CDS_PINID='VDDCR_SOC_AY22';
NODE_NAME     U25 AY24
 '@T6G_MB_LIB.T6G(SCH_1):PAGE30_I50@PURE_QUANTA.GENOA_SP5(CHIPS)':
 'VDDCR_SOC_AY24': CDS_PINID='VDDCR_SOC_AY24';
NODE_NAME     U25 AY26
 '@T6G_MB_LIB.T6G(SCH_1):PAGE30_I50@PURE_QUANTA.GENOA_SP5(CHIPS)':
 'VDDCR_SOC_AY26': CDS_PINID='VDDCR_SOC_AY26';
NODE_NAME     U25 AY28
 '@T6G_MB_LIB.T6G(SCH_1):PAGE30_I50@PURE_QUANTA.GENOA_SP5(CHIPS)':
 'VDDCR_SOC_AY28': CDS_PINID='VDDCR_SOC_AY28';
NODE_NAME     U25 AY49
 '@T6G_MB_LIB.T6G(SCH_1):PAGE30_I50@PURE_QUANTA.GENOA_SP5(CHIPS)':
 'VDDCR_SOC_AY49': CDS_PINID='VDDCR_SOC_AY49';
NODE_NAME     U25 B5
 '@T6G_MB_LIB.T6G(SCH_1):PAGE30_I50@PURE_QUANTA.GENOA_SP5(CHIPS)':
 'VDDCR_SOC_B5': CDS_PINID='VDDCR_SOC_B5';
NODE_NAME     U25 BA4
 '@T6G_MB_LIB.T6G(SCH_1):PAGE30_I50@PURE_QUANTA.GENOA_SP5(CHIPS)':
 'VDDCR_SOC_BA4': CDS_PINID='VDDCR_SOC_BA4';
NODE_NAME     U25 BA11
 '@T6G_MB_LIB.T6G(SCH_1):PAGE30_I50@PURE_QUANTA.GENOA_SP5(CHIPS)':
 'VDDCR_SOC_BA11': CDS_PINID='VDDCR_SOC_BA11';
NODE_NAME     U25 BA18
 '@T6G_MB_LIB.T6G(SCH_1):PAGE30_I50@PURE_QUANTA.GENOA_SP5(CHIPS)':
 'VDDCR_SOC_BA18': CDS_PINID='VDDCR_SOC_BA18';
NODE_NAME     U25 BA23
 '@T6G_MB_LIB.T6G(SCH_1):PAGE30_I50@PURE_QUANTA.GENOA_SP5(CHIPS)':
 'VDDCR_SOC_BA23': CDS_PINID='VDDCR_SOC_BA23';
NODE_NAME     U25 BA25
 '@T6G_MB_LIB.T6G(SCH_1):PAGE30_I50@PURE_QUANTA.GENOA_SP5(CHIPS)':
 'VDDCR_SOC_BA25': CDS_PINID='VDDCR_SOC_BA25';
NODE_NAME     U25 BA27
 '@T6G_MB_LIB.T6G(SCH_1):PAGE30_I50@PURE_QUANTA.GENOA_SP5(CHIPS)':
 'VDDCR_SOC_BA27': CDS_PINID='VDDCR_SOC_BA27';
NODE_NAME     U25 BA48
 '@T6G_MB_LIB.T6G(SCH_1):PAGE30_I50@PURE_QUANTA.GENOA_SP5(CHIPS)':
 'VDDCR_SOC_BA48': CDS_PINID='VDDCR_SOC_BA48';
NODE_NAME     U25 BB22
 '@T6G_MB_LIB.T6G(SCH_1):PAGE30_I50@PURE_QUANTA.GENOA_SP5(CHIPS)':
 'VDDCR_SOC_BB22': CDS_PINID='VDDCR_SOC_BB22';
NODE_NAME     U25 BB24
 '@T6G_MB_LIB.T6G(SCH_1):PAGE30_I50@PURE_QUANTA.GENOA_SP5(CHIPS)':
 'VDDCR_SOC_BB24': CDS_PINID='VDDCR_SOC_BB24';
NODE_NAME     U25 BB26
 '@T6G_MB_LIB.T6G(SCH_1):PAGE30_I50@PURE_QUANTA.GENOA_SP5(CHIPS)':
 'VDDCR_SOC_BB26': CDS_PINID='VDDCR_SOC_BB26';
NODE_NAME     U25 BB28
 '@T6G_MB_LIB.T6G(SCH_1):PAGE30_I50@PURE_QUANTA.GENOA_SP5(CHIPS)':
 'VDDCR_SOC_BB28': CDS_PINID='VDDCR_SOC_BB28';
NODE_NAME     U25 BB49
 '@T6G_MB_LIB.T6G(SCH_1):PAGE30_I50@PURE_QUANTA.GENOA_SP5(CHIPS)':
 'VDDCR_SOC_BB49': CDS_PINID='VDDCR_SOC_BB49';
NODE_NAME     U25 BC23
 '@T6G_MB_LIB.T6G(SCH_1):PAGE30_I50@PURE_QUANTA.GENOA_SP5(CHIPS)':
 'VDDCR_SOC_BC23': CDS_PINID='VDDCR_SOC_BC23';
NODE_NAME     U25 BC25
 '@T6G_MB_LIB.T6G(SCH_1):PAGE30_I50@PURE_QUANTA.GENOA_SP5(CHIPS)':
 'VDDCR_SOC_BC25': CDS_PINID='VDDCR_SOC_BC25';
NODE_NAME     U25 BC27
 '@T6G_MB_LIB.T6G(SCH_1):PAGE30_I50@PURE_QUANTA.GENOA_SP5(CHIPS)':
 'VDDCR_SOC_BC27': CDS_PINID='VDDCR_SOC_BC27';
NODE_NAME     U25 BC48
 '@T6G_MB_LIB.T6G(SCH_1):PAGE30_I50@PURE_QUANTA.GENOA_SP5(CHIPS)':
 'VDDCR_SOC_BC48': CDS_PINID='VDDCR_SOC_BC48';
NODE_NAME     U25 BD5
 '@T6G_MB_LIB.T6G(SCH_1):PAGE30_I50@PURE_QUANTA.GENOA_SP5(CHIPS)':
 'VDDCR_SOC_BD5': CDS_PINID='VDDCR_SOC_BD5';
NODE_NAME     U25 BD12
 '@T6G_MB_LIB.T6G(SCH_1):PAGE30_I50@PURE_QUANTA.GENOA_SP5(CHIPS)':
 'VDDCR_SOC_BD12': CDS_PINID='VDDCR_SOC_BD12';
NODE_NAME     U25 BD19
 '@T6G_MB_LIB.T6G(SCH_1):PAGE30_I50@PURE_QUANTA.GENOA_SP5(CHIPS)':
 'VDDCR_SOC_BD19': CDS_PINID='VDDCR_SOC_BD19';
NODE_NAME     U25 BD22
 '@T6G_MB_LIB.T6G(SCH_1):PAGE30_I50@PURE_QUANTA.GENOA_SP5(CHIPS)':
 'VDDCR_SOC_BD22': CDS_PINID='VDDCR_SOC_BD22';
NODE_NAME     U25 BD24
 '@T6G_MB_LIB.T6G(SCH_1):PAGE30_I50@PURE_QUANTA.GENOA_SP5(CHIPS)':
 'VDDCR_SOC_BD24': CDS_PINID='VDDCR_SOC_BD24';
NODE_NAME     U25 BD26
 '@T6G_MB_LIB.T6G(SCH_1):PAGE30_I50@PURE_QUANTA.GENOA_SP5(CHIPS)':
 'VDDCR_SOC_BD26': CDS_PINID='VDDCR_SOC_BD26';
NODE_NAME     U25 BD28
 '@T6G_MB_LIB.T6G(SCH_1):PAGE30_I50@PURE_QUANTA.GENOA_SP5(CHIPS)':
 'VDDCR_SOC_BD28': CDS_PINID='VDDCR_SOC_BD28';
NODE_NAME     U25 BD48
 '@T6G_MB_LIB.T6G(SCH_1):PAGE30_I50@PURE_QUANTA.GENOA_SP5(CHIPS)':
 'VDDCR_SOC_BD48': CDS_PINID='VDDCR_SOC_BD48';
NODE_NAME     U25 BF23
 '@T6G_MB_LIB.T6G(SCH_1):PAGE30_I50@PURE_QUANTA.GENOA_SP5(CHIPS)':
 'VDDCR_SOC_BF23': CDS_PINID='VDDCR_SOC_BF23';
NODE_NAME     U25 BF25
 '@T6G_MB_LIB.T6G(SCH_1):PAGE30_I50@PURE_QUANTA.GENOA_SP5(CHIPS)':
 'VDDCR_SOC_BF25': CDS_PINID='VDDCR_SOC_BF25';
NODE_NAME     U25 BF27
 '@T6G_MB_LIB.T6G(SCH_1):PAGE30_I50@PURE_QUANTA.GENOA_SP5(CHIPS)':
 'VDDCR_SOC_BF27': CDS_PINID='VDDCR_SOC_BF27';
NODE_NAME     U25 BF48
 '@T6G_MB_LIB.T6G(SCH_1):PAGE30_I50@PURE_QUANTA.GENOA_SP5(CHIPS)':
 'VDDCR_SOC_BF48': CDS_PINID='VDDCR_SOC_BF48';
NODE_NAME     U25 BG22
 '@T6G_MB_LIB.T6G(SCH_1):PAGE30_I50@PURE_QUANTA.GENOA_SP5(CHIPS)':
 'VDDCR_SOC_BG22': CDS_PINID='VDDCR_SOC_BG22';
NODE_NAME     U25 BG24
 '@T6G_MB_LIB.T6G(SCH_1):PAGE30_I50@PURE_QUANTA.GENOA_SP5(CHIPS)':
 'VDDCR_SOC_BG24': CDS_PINID='VDDCR_SOC_BG24';
NODE_NAME     U25 BG26
 '@T6G_MB_LIB.T6G(SCH_1):PAGE30_I50@PURE_QUANTA.GENOA_SP5(CHIPS)':
 'VDDCR_SOC_BG26': CDS_PINID='VDDCR_SOC_BG26';
NODE_NAME     U25 BG28
 '@T6G_MB_LIB.T6G(SCH_1):PAGE30_I50@PURE_QUANTA.GENOA_SP5(CHIPS)':
 'VDDCR_SOC_BG28': CDS_PINID='VDDCR_SOC_BG28';
NODE_NAME     U25 BG48
 '@T6G_MB_LIB.T6G(SCH_1):PAGE30_I50@PURE_QUANTA.GENOA_SP5(CHIPS)':
 'VDDCR_SOC_BG48': CDS_PINID='VDDCR_SOC_BG48';
NODE_NAME     U25 BH23
 '@T6G_MB_LIB.T6G(SCH_1):PAGE30_I50@PURE_QUANTA.GENOA_SP5(CHIPS)':
 'VDDCR_SOC_BH23': CDS_PINID='VDDCR_SOC_BH23';
NODE_NAME     U25 BH25
 '@T6G_MB_LIB.T6G(SCH_1):PAGE30_I50@PURE_QUANTA.GENOA_SP5(CHIPS)':
 'VDDCR_SOC_BH25': CDS_PINID='VDDCR_SOC_BH25';
NODE_NAME     U25 BH48
 '@T6G_MB_LIB.T6G(SCH_1):PAGE30_I50@PURE_QUANTA.GENOA_SP5(CHIPS)':
 'VDDCR_SOC_BH48': CDS_PINID='VDDCR_SOC_BH48';
NODE_NAME     U25 BJ4
 '@T6G_MB_LIB.T6G(SCH_1):PAGE30_I50@PURE_QUANTA.GENOA_SP5(CHIPS)':
 'VDDCR_SOC_BJ4': CDS_PINID='VDDCR_SOC_BJ4';
NODE_NAME     U25 BJ11
 '@T6G_MB_LIB.T6G(SCH_1):PAGE30_I50@PURE_QUANTA.GENOA_SP5(CHIPS)':
 'VDDCR_SOC_BJ11': CDS_PINID='VDDCR_SOC_BJ11';
NODE_NAME     U25 BJ48
 '@T6G_MB_LIB.T6G(SCH_1):PAGE30_I50@PURE_QUANTA.GENOA_SP5(CHIPS)':
 'VDDCR_SOC_BJ48': CDS_PINID='VDDCR_SOC_BJ48';
NODE_NAME     U25 BM5
 '@T6G_MB_LIB.T6G(SCH_1):PAGE30_I50@PURE_QUANTA.GENOA_SP5(CHIPS)':
 'VDDCR_SOC_BM5': CDS_PINID='VDDCR_SOC_BM5';
NODE_NAME     U25 C4
 '@T6G_MB_LIB.T6G(SCH_1):PAGE30_I50@PURE_QUANTA.GENOA_SP5(CHIPS)':
 'VDDCR_SOC_C4': CDS_PINID='VDDCR_SOC_C4';
NODE_NAME     U25 E4
 '@T6G_MB_LIB.T6G(SCH_1):PAGE30_I50@PURE_QUANTA.GENOA_SP5(CHIPS)':
 'VDDCR_SOC_E4': CDS_PINID='VDDCR_SOC_E4';
NODE_NAME     U25 E11
 '@T6G_MB_LIB.T6G(SCH_1):PAGE30_I50@PURE_QUANTA.GENOA_SP5(CHIPS)':
 'VDDCR_SOC_E11': CDS_PINID='VDDCR_SOC_E11';
NODE_NAME     U25 H5
 '@T6G_MB_LIB.T6G(SCH_1):PAGE30_I50@PURE_QUANTA.GENOA_SP5(CHIPS)':
 'VDDCR_SOC_H5': CDS_PINID='VDDCR_SOC_H5';
NODE_NAME     U25 H12
 '@T6G_MB_LIB.T6G(SCH_1):PAGE30_I50@PURE_QUANTA.GENOA_SP5(CHIPS)':
 'VDDCR_SOC_H12': CDS_PINID='VDDCR_SOC_H12';
NODE_NAME     U25 H19
 '@T6G_MB_LIB.T6G(SCH_1):PAGE30_I50@PURE_QUANTA.GENOA_SP5(CHIPS)':
 'VDDCR_SOC_H19': CDS_PINID='VDDCR_SOC_H19';
NODE_NAME     U25 K22
 '@T6G_MB_LIB.T6G(SCH_1):PAGE30_I50@PURE_QUANTA.GENOA_SP5(CHIPS)':
 'VDDCR_SOC_K22': CDS_PINID='VDDCR_SOC_K22';
NODE_NAME     U25 L4
 '@T6G_MB_LIB.T6G(SCH_1):PAGE30_I50@PURE_QUANTA.GENOA_SP5(CHIPS)':
 'VDDCR_SOC_L4': CDS_PINID='VDDCR_SOC_L4';
NODE_NAME     U25 L11
 '@T6G_MB_LIB.T6G(SCH_1):PAGE30_I50@PURE_QUANTA.GENOA_SP5(CHIPS)':
 'VDDCR_SOC_L11': CDS_PINID='VDDCR_SOC_L11';
NODE_NAME     U25 L18
 '@T6G_MB_LIB.T6G(SCH_1):PAGE30_I50@PURE_QUANTA.GENOA_SP5(CHIPS)':
 'VDDCR_SOC_L18': CDS_PINID='VDDCR_SOC_L18';
NODE_NAME     U25 P5
 '@T6G_MB_LIB.T6G(SCH_1):PAGE30_I50@PURE_QUANTA.GENOA_SP5(CHIPS)':
 'VDDCR_SOC_P5': CDS_PINID='VDDCR_SOC_P5';
NODE_NAME     U25 P12
 '@T6G_MB_LIB.T6G(SCH_1):PAGE30_I50@PURE_QUANTA.GENOA_SP5(CHIPS)':
 'VDDCR_SOC_P12': CDS_PINID='VDDCR_SOC_P12';
NODE_NAME     U25 P19
 '@T6G_MB_LIB.T6G(SCH_1):PAGE30_I50@PURE_QUANTA.GENOA_SP5(CHIPS)':
 'VDDCR_SOC_P19': CDS_PINID='VDDCR_SOC_P19';
NODE_NAME     U25 P22
 '@T6G_MB_LIB.T6G(SCH_1):PAGE30_I50@PURE_QUANTA.GENOA_SP5(CHIPS)':
 'VDDCR_SOC_P22': CDS_PINID='VDDCR_SOC_P22';
NODE_NAME     U25 U4
 '@T6G_MB_LIB.T6G(SCH_1):PAGE30_I50@PURE_QUANTA.GENOA_SP5(CHIPS)':
 'VDDCR_SOC_U4': CDS_PINID='VDDCR_SOC_U4';
NODE_NAME     U25 U11
 '@T6G_MB_LIB.T6G(SCH_1):PAGE30_I50@PURE_QUANTA.GENOA_SP5(CHIPS)':
 'VDDCR_SOC_U11': CDS_PINID='VDDCR_SOC_U11';
NODE_NAME     U25 U18
 '@T6G_MB_LIB.T6G(SCH_1):PAGE30_I50@PURE_QUANTA.GENOA_SP5(CHIPS)':
 'VDDCR_SOC_U18': CDS_PINID='VDDCR_SOC_U18';
NODE_NAME     U25 V22
 '@T6G_MB_LIB.T6G(SCH_1):PAGE30_I50@PURE_QUANTA.GENOA_SP5(CHIPS)':
 'VDDCR_SOC_V22': CDS_PINID='VDDCR_SOC_V22';
NODE_NAME     U25 Y5
 '@T6G_MB_LIB.T6G(SCH_1):PAGE30_I50@PURE_QUANTA.GENOA_SP5(CHIPS)':
 'VDDCR_SOC_Y5': CDS_PINID='VDDCR_SOC_Y5';
NODE_NAME     U25 Y12
 '@T6G_MB_LIB.T6G(SCH_1):PAGE30_I50@PURE_QUANTA.GENOA_SP5(CHIPS)':
 'VDDCR_SOC_Y12': CDS_PINID='VDDCR_SOC_Y12';
NODE_NAME     U25 Y19
 '@T6G_MB_LIB.T6G(SCH_1):PAGE30_I50@PURE_QUANTA.GENOA_SP5(CHIPS)':
 'VDDCR_SOC_Y19': CDS_PINID='VDDCR_SOC_Y19';
NODE_NAME     C3888 1
 '@T6G_MB_LIB.T6G(SCH_1):PAGE67_I83@PURE_QUANTA.Q_CAP(CHIPS)':
 'A': CDS_PINID='A';
NODE_NAME     C2130 1
 '@T6G_MB_LIB.T6G(SCH_1):PAGE67_I85@PURE_QUANTA.Q_CAP(CHIPS)':
 'A': CDS_PINID='A';
NODE_NAME     C3889 1
 '@T6G_MB_LIB.T6G(SCH_1):PAGE67_I86@PURE_QUANTA.Q_CAP(CHIPS)':
 'A': CDS_PINID='A';
NODE_NAME     C2135 1
 '@T6G_MB_LIB.T6G(SCH_1):PAGE67_I87@PURE_QUANTA.Q_CAP(CHIPS)':
 'A': CDS_PINID='A';
NODE_NAME     C2129 1
 '@T6G_MB_LIB.T6G(SCH_1):PAGE67_I89@PURE_QUANTA.Q_CAP(CHIPS)':
 'A': CDS_PINID='A';
NODE_NAME     C2134 1
 '@T6G_MB_LIB.T6G(SCH_1):PAGE67_I90@PURE_QUANTA.Q_CAP(CHIPS)':
 'A': CDS_PINID='A';
NODE_NAME     C2140 1
 '@T6G_MB_LIB.T6G(SCH_1):PAGE67_I92@PURE_QUANTA.Q_CAP(CHIPS)':
 'A': CDS_PINID='A';
NODE_NAME     C2144 1
 '@T6G_MB_LIB.T6G(SCH_1):PAGE67_I93@PURE_QUANTA.Q_CAP(CHIPS)':
 'A': CDS_PINID='A';
NODE_NAME     C2148 1
 '@T6G_MB_LIB.T6G(SCH_1):PAGE67_I94@PURE_QUANTA.Q_CAP(CHIPS)':
 'A': CDS_PINID='A';
NODE_NAME     C2139 1
 '@T6G_MB_LIB.T6G(SCH_1):PAGE67_I95@PURE_QUANTA.Q_CAP(CHIPS)':
 'A': CDS_PINID='A';
NODE_NAME     C2143 1
 '@T6G_MB_LIB.T6G(SCH_1):PAGE67_I96@PURE_QUANTA.Q_CAP(CHIPS)':
 'A': CDS_PINID='A';
NODE_NAME     C2152 1
 '@T6G_MB_LIB.T6G(SCH_1):PAGE67_I97@PURE_QUANTA.Q_CAP(CHIPS)':
 'A': CDS_PINID='A';
NODE_NAME     C2155 1
 '@T6G_MB_LIB.T6G(SCH_1):PAGE67_I98@PURE_QUANTA.Q_CAP(CHIPS)':
 'A': CDS_PINID='A';
NODE_NAME     C2151 1
 '@T6G_MB_LIB.T6G(SCH_1):PAGE67_I99@PURE_QUANTA.Q_CAP(CHIPS)':
 'A': CDS_PINID='A';
NODE_NAME     C2154 1
 '@T6G_MB_LIB.T6G(SCH_1):PAGE67_I100@PURE_QUANTA.Q_CAP(CHIPS)':
 'A': CDS_PINID='A';
NODE_NAME     C3894 1
 '@T6G_MB_LIB.T6G(SCH_1):PAGE67_I101@PURE_QUANTA.Q_CAP(CHIPS)':
 'A': CDS_PINID='A';
NODE_NAME     C3895 1
 '@T6G_MB_LIB.T6G(SCH_1):PAGE67_I102@PURE_QUANTA.Q_CAP(CHIPS)':
 'A': CDS_PINID='A';
NODE_NAME     C2157 1
 '@T6G_MB_LIB.T6G(SCH_1):PAGE67_I103@PURE_QUANTA.Q_CAP(CHIPS)':
 'A': CDS_PINID='A';
NODE_NAME     C2159 1
 '@T6G_MB_LIB.T6G(SCH_1):PAGE67_I104@PURE_QUANTA.Q_CAP(CHIPS)':
 'A': CDS_PINID='A';
NODE_NAME     C3896 1
 '@T6G_MB_LIB.T6G(SCH_1):PAGE67_I106@PURE_QUANTA.Q_CAP(CHIPS)':
 'A': CDS_PINID='A';
NODE_NAME     C2161 1
 '@T6G_MB_LIB.T6G(SCH_1):PAGE67_I108@PURE_QUANTA.Q_CAP(CHIPS)':
 'A': CDS_PINID='A';
NODE_NAME     C2147 1
 '@T6G_MB_LIB.T6G(SCH_1):PAGE67_I109@PURE_QUANTA.Q_CAP(CHIPS)':
 'A': CDS_PINID='A';
NODE_NAME     C3925 1
 '@T6G_MB_LIB.T6G(SCH_1):PAGE69_I1@PURE_QUANTA.Q_CAP(CHIPS)':
 'A': CDS_PINID='A';
NODE_NAME     C3926 1
 '@T6G_MB_LIB.T6G(SCH_1):PAGE69_I3@PURE_QUANTA.Q_CAP(CHIPS)':
 'A': CDS_PINID='A';
NODE_NAME     C2533 1
 '@T6G_MB_LIB.T6G(SCH_1):PAGE69_I4@PURE_QUANTA.Q_CAP(CHIPS)':
 'A': CDS_PINID='A';
NODE_NAME     C2540 1
 '@T6G_MB_LIB.T6G(SCH_1):PAGE69_I6@PURE_QUANTA.Q_CAP(CHIPS)':
 'A': CDS_PINID='A';
NODE_NAME     C2532 1
 '@T6G_MB_LIB.T6G(SCH_1):PAGE69_I7@PURE_QUANTA.Q_CAP(CHIPS)':
 'A': CDS_PINID='A';
NODE_NAME     C2531 1
 '@T6G_MB_LIB.T6G(SCH_1):PAGE69_I9@PURE_QUANTA.Q_CAP(CHIPS)':
 'A': CDS_PINID='A';
NODE_NAME     C2539 1
 '@T6G_MB_LIB.T6G(SCH_1):PAGE69_I10@PURE_QUANTA.Q_CAP(CHIPS)':
 'A': CDS_PINID='A';
NODE_NAME     C2538 1
 '@T6G_MB_LIB.T6G(SCH_1):PAGE69_I11@PURE_QUANTA.Q_CAP(CHIPS)':
 'A': CDS_PINID='A';
NODE_NAME     C2530 1
 '@T6G_MB_LIB.T6G(SCH_1):PAGE69_I13@PURE_QUANTA.Q_CAP(CHIPS)':
 'A': CDS_PINID='A';
NODE_NAME     C2537 1
 '@T6G_MB_LIB.T6G(SCH_1):PAGE69_I15@PURE_QUANTA.Q_CAP(CHIPS)':
 'A': CDS_PINID='A';
NODE_NAME     C2529 1
 '@T6G_MB_LIB.T6G(SCH_1):PAGE69_I16@PURE_QUANTA.Q_CAP(CHIPS)':
 'A': CDS_PINID='A';
NODE_NAME     C2528 1
 '@T6G_MB_LIB.T6G(SCH_1):PAGE69_I18@PURE_QUANTA.Q_CAP(CHIPS)':
 'A': CDS_PINID='A';
NODE_NAME     C2536 1
 '@T6G_MB_LIB.T6G(SCH_1):PAGE69_I19@PURE_QUANTA.Q_CAP(CHIPS)':
 'A': CDS_PINID='A';
NODE_NAME     C2535 1
 '@T6G_MB_LIB.T6G(SCH_1):PAGE69_I20@PURE_QUANTA.Q_CAP(CHIPS)':
 'A': CDS_PINID='A';
NODE_NAME     C2527 1
 '@T6G_MB_LIB.T6G(SCH_1):PAGE69_I22@PURE_QUANTA.Q_CAP(CHIPS)':
 'A': CDS_PINID='A';
NODE_NAME     C2534 1
 '@T6G_MB_LIB.T6G(SCH_1):PAGE69_I24@PURE_QUANTA.Q_CAP(CHIPS)':
 'A': CDS_PINID='A';
NODE_NAME     C3927 1
 '@T6G_MB_LIB.T6G(SCH_1):PAGE69_I25@PURE_QUANTA.Q_CAP(CHIPS)':
 'A': CDS_PINID='A';
NODE_NAME     C3928 1
 '@T6G_MB_LIB.T6G(SCH_1):PAGE69_I26@PURE_QUANTA.Q_CAP(CHIPS)':
 'A': CDS_PINID='A';
NODE_NAME     C3929 1
 '@T6G_MB_LIB.T6G(SCH_1):PAGE69_I27@PURE_QUANTA.Q_CAP(CHIPS)':
 'A': CDS_PINID='A';
NODE_NAME     C2547 1
 '@T6G_MB_LIB.T6G(SCH_1):PAGE69_I28@PURE_QUANTA.Q_CAP(CHIPS)':
 'A': CDS_PINID='A';
NODE_NAME     C2554 1
 '@T6G_MB_LIB.T6G(SCH_1):PAGE69_I29@PURE_QUANTA.Q_CAP(CHIPS)':
 'A': CDS_PINID='A';
NODE_NAME     C2561 1
 '@T6G_MB_LIB.T6G(SCH_1):PAGE69_I30@PURE_QUANTA.Q_CAP(CHIPS)':
 'A': CDS_PINID='A';
NODE_NAME     C3930 1
 '@T6G_MB_LIB.T6G(SCH_1):PAGE69_I31@PURE_QUANTA.Q_CAP(CHIPS)':
 'A': CDS_PINID='A';
NODE_NAME     C3931 1
 '@T6G_MB_LIB.T6G(SCH_1):PAGE69_I33@PURE_QUANTA.Q_CAP(CHIPS)':
 'A': CDS_PINID='A';
NODE_NAME     C2568 1
 '@T6G_MB_LIB.T6G(SCH_1):PAGE69_I34@PURE_QUANTA.Q_CAP(CHIPS)':
 'A': CDS_PINID='A';
NODE_NAME     C2575 1
 '@T6G_MB_LIB.T6G(SCH_1):PAGE69_I35@PURE_QUANTA.Q_CAP(CHIPS)':
 'A': CDS_PINID='A';
NODE_NAME     C2546 1
 '@T6G_MB_LIB.T6G(SCH_1):PAGE69_I36@PURE_QUANTA.Q_CAP(CHIPS)':
 'A': CDS_PINID='A';
NODE_NAME     C2545 1
 '@T6G_MB_LIB.T6G(SCH_1):PAGE69_I37@PURE_QUANTA.Q_CAP(CHIPS)':
 'A': CDS_PINID='A';
NODE_NAME     C2553 1
 '@T6G_MB_LIB.T6G(SCH_1):PAGE69_I38@PURE_QUANTA.Q_CAP(CHIPS)':
 'A': CDS_PINID='A';
NODE_NAME     C2560 1
 '@T6G_MB_LIB.T6G(SCH_1):PAGE69_I39@PURE_QUANTA.Q_CAP(CHIPS)':
 'A': CDS_PINID='A';
NODE_NAME     C2552 1
 '@T6G_MB_LIB.T6G(SCH_1):PAGE69_I40@PURE_QUANTA.Q_CAP(CHIPS)':
 'A': CDS_PINID='A';
NODE_NAME     C2559 1
 '@T6G_MB_LIB.T6G(SCH_1):PAGE69_I41@PURE_QUANTA.Q_CAP(CHIPS)':
 'A': CDS_PINID='A';
NODE_NAME     C2544 1
 '@T6G_MB_LIB.T6G(SCH_1):PAGE69_I42@PURE_QUANTA.Q_CAP(CHIPS)':
 'A': CDS_PINID='A';
NODE_NAME     C2551 1
 '@T6G_MB_LIB.T6G(SCH_1):PAGE69_I43@PURE_QUANTA.Q_CAP(CHIPS)':
 'A': CDS_PINID='A';
NODE_NAME     C2558 1
 '@T6G_MB_LIB.T6G(SCH_1):PAGE69_I44@PURE_QUANTA.Q_CAP(CHIPS)':
 'A': CDS_PINID='A';
NODE_NAME     C2567 1
 '@T6G_MB_LIB.T6G(SCH_1):PAGE69_I45@PURE_QUANTA.Q_CAP(CHIPS)':
 'A': CDS_PINID='A';
NODE_NAME     C2566 1
 '@T6G_MB_LIB.T6G(SCH_1):PAGE69_I46@PURE_QUANTA.Q_CAP(CHIPS)':
 'A': CDS_PINID='A';
NODE_NAME     C2574 1
 '@T6G_MB_LIB.T6G(SCH_1):PAGE69_I47@PURE_QUANTA.Q_CAP(CHIPS)':
 'A': CDS_PINID='A';
NODE_NAME     C2573 1
 '@T6G_MB_LIB.T6G(SCH_1):PAGE69_I48@PURE_QUANTA.Q_CAP(CHIPS)':
 'A': CDS_PINID='A';
NODE_NAME     C2565 1
 '@T6G_MB_LIB.T6G(SCH_1):PAGE69_I49@PURE_QUANTA.Q_CAP(CHIPS)':
 'A': CDS_PINID='A';
NODE_NAME     C2572 1
 '@T6G_MB_LIB.T6G(SCH_1):PAGE69_I50@PURE_QUANTA.Q_CAP(CHIPS)':
 'A': CDS_PINID='A';
NODE_NAME     C2582 1
 '@T6G_MB_LIB.T6G(SCH_1):PAGE69_I51@PURE_QUANTA.Q_CAP(CHIPS)':
 'A': CDS_PINID='A';
NODE_NAME     C2589 1
 '@T6G_MB_LIB.T6G(SCH_1):PAGE69_I52@PURE_QUANTA.Q_CAP(CHIPS)':
 'A': CDS_PINID='A';
NODE_NAME     C2596 1
 '@T6G_MB_LIB.T6G(SCH_1):PAGE69_I56@PURE_QUANTA.Q_CAP(CHIPS)':
 'A': CDS_PINID='A';
NODE_NAME     C2581 1
 '@T6G_MB_LIB.T6G(SCH_1):PAGE69_I61@PURE_QUANTA.Q_CAP(CHIPS)':
 'A': CDS_PINID='A';
NODE_NAME     C2580 1
 '@T6G_MB_LIB.T6G(SCH_1):PAGE69_I62@PURE_QUANTA.Q_CAP(CHIPS)':
 'A': CDS_PINID='A';
NODE_NAME     C2588 1
 '@T6G_MB_LIB.T6G(SCH_1):PAGE69_I63@PURE_QUANTA.Q_CAP(CHIPS)':
 'A': CDS_PINID='A';
NODE_NAME     C2587 1
 '@T6G_MB_LIB.T6G(SCH_1):PAGE69_I64@PURE_QUANTA.Q_CAP(CHIPS)':
 'A': CDS_PINID='A';
NODE_NAME     C2579 1
 '@T6G_MB_LIB.T6G(SCH_1):PAGE69_I65@PURE_QUANTA.Q_CAP(CHIPS)':
 'A': CDS_PINID='A';
NODE_NAME     C2586 1
 '@T6G_MB_LIB.T6G(SCH_1):PAGE69_I66@PURE_QUANTA.Q_CAP(CHIPS)':
 'A': CDS_PINID='A';
NODE_NAME     C2595 1
 '@T6G_MB_LIB.T6G(SCH_1):PAGE69_I67@PURE_QUANTA.Q_CAP(CHIPS)':
 'A': CDS_PINID='A';
NODE_NAME     C2594 1
 '@T6G_MB_LIB.T6G(SCH_1):PAGE69_I69@PURE_QUANTA.Q_CAP(CHIPS)':
 'A': CDS_PINID='A';
NODE_NAME     C2593 1
 '@T6G_MB_LIB.T6G(SCH_1):PAGE69_I74@PURE_QUANTA.Q_CAP(CHIPS)':
 'A': CDS_PINID='A';
NODE_NAME     C2543 1
 '@T6G_MB_LIB.T6G(SCH_1):PAGE69_I78@PURE_QUANTA.Q_CAP(CHIPS)':
 'A': CDS_PINID='A';
NODE_NAME     C2542 1
 '@T6G_MB_LIB.T6G(SCH_1):PAGE69_I79@PURE_QUANTA.Q_CAP(CHIPS)':
 'A': CDS_PINID='A';
NODE_NAME     C2550 1
 '@T6G_MB_LIB.T6G(SCH_1):PAGE69_I80@PURE_QUANTA.Q_CAP(CHIPS)':
 'A': CDS_PINID='A';
NODE_NAME     C2549 1
 '@T6G_MB_LIB.T6G(SCH_1):PAGE69_I81@PURE_QUANTA.Q_CAP(CHIPS)':
 'A': CDS_PINID='A';
NODE_NAME     C2557 1
 '@T6G_MB_LIB.T6G(SCH_1):PAGE69_I82@PURE_QUANTA.Q_CAP(CHIPS)':
 'A': CDS_PINID='A';
NODE_NAME     C2556 1
 '@T6G_MB_LIB.T6G(SCH_1):PAGE69_I83@PURE_QUANTA.Q_CAP(CHIPS)':
 'A': CDS_PINID='A';
NODE_NAME     C2541 1
 '@T6G_MB_LIB.T6G(SCH_1):PAGE69_I84@PURE_QUANTA.Q_CAP(CHIPS)':
 'A': CDS_PINID='A';
NODE_NAME     C2548 1
 '@T6G_MB_LIB.T6G(SCH_1):PAGE69_I85@PURE_QUANTA.Q_CAP(CHIPS)':
 'A': CDS_PINID='A';
NODE_NAME     C2555 1
 '@T6G_MB_LIB.T6G(SCH_1):PAGE69_I86@PURE_QUANTA.Q_CAP(CHIPS)':
 'A': CDS_PINID='A';
NODE_NAME     C2564 1
 '@T6G_MB_LIB.T6G(SCH_1):PAGE69_I87@PURE_QUANTA.Q_CAP(CHIPS)':
 'A': CDS_PINID='A';
NODE_NAME     C2563 1
 '@T6G_MB_LIB.T6G(SCH_1):PAGE69_I88@PURE_QUANTA.Q_CAP(CHIPS)':
 'A': CDS_PINID='A';
NODE_NAME     C2571 1
 '@T6G_MB_LIB.T6G(SCH_1):PAGE69_I89@PURE_QUANTA.Q_CAP(CHIPS)':
 'A': CDS_PINID='A';
NODE_NAME     C2570 1
 '@T6G_MB_LIB.T6G(SCH_1):PAGE69_I90@PURE_QUANTA.Q_CAP(CHIPS)':
 'A': CDS_PINID='A';
NODE_NAME     C2562 1
 '@T6G_MB_LIB.T6G(SCH_1):PAGE69_I91@PURE_QUANTA.Q_CAP(CHIPS)':
 'A': CDS_PINID='A';
NODE_NAME     C2569 1
 '@T6G_MB_LIB.T6G(SCH_1):PAGE69_I92@PURE_QUANTA.Q_CAP(CHIPS)':
 'A': CDS_PINID='A';
NODE_NAME     C2578 1
 '@T6G_MB_LIB.T6G(SCH_1):PAGE69_I93@PURE_QUANTA.Q_CAP(CHIPS)':
 'A': CDS_PINID='A';
NODE_NAME     C2577 1
 '@T6G_MB_LIB.T6G(SCH_1):PAGE69_I94@PURE_QUANTA.Q_CAP(CHIPS)':
 'A': CDS_PINID='A';
NODE_NAME     C2585 1
 '@T6G_MB_LIB.T6G(SCH_1):PAGE69_I95@PURE_QUANTA.Q_CAP(CHIPS)':
 'A': CDS_PINID='A';
NODE_NAME     C2584 1
 '@T6G_MB_LIB.T6G(SCH_1):PAGE69_I96@PURE_QUANTA.Q_CAP(CHIPS)':
 'A': CDS_PINID='A';
NODE_NAME     C2576 1
 '@T6G_MB_LIB.T6G(SCH_1):PAGE69_I97@PURE_QUANTA.Q_CAP(CHIPS)':
 'A': CDS_PINID='A';
NODE_NAME     C2583 1
 '@T6G_MB_LIB.T6G(SCH_1):PAGE69_I98@PURE_QUANTA.Q_CAP(CHIPS)':
 'A': CDS_PINID='A';
NODE_NAME     C2592 1
 '@T6G_MB_LIB.T6G(SCH_1):PAGE69_I99@PURE_QUANTA.Q_CAP(CHIPS)':
 'A': CDS_PINID='A';
NODE_NAME     C2591 1
 '@T6G_MB_LIB.T6G(SCH_1):PAGE69_I101@PURE_QUANTA.Q_CAP(CHIPS)':
 'A': CDS_PINID='A';
NODE_NAME     C2590 1
 '@T6G_MB_LIB.T6G(SCH_1):PAGE69_I106@PURE_QUANTA.Q_CAP(CHIPS)':
 'A': CDS_PINID='A';
NODE_NAME     PC597 1
 '@T6G_MB_LIB.T6G(SCH_1):PAGE173_I63@PURE_QUANTA.Q_CAPP(CHIPS)':
 'A': CDS_PINID='A';
NODE_NAME     PC601 1
 '@T6G_MB_LIB.T6G(SCH_1):PAGE173_I66@PURE_QUANTA.Q_CAPP(CHIPS)':
 'A': CDS_PINID='A';
NODE_NAME     PL63 4
 '@T6G_MB_LIB.T6G(SCH_1):PAGE173_I69@PURE_QUANTA.Q_INDUCTOR4P_14(CHIPS)':
 '4': CDS_PINID='\4\';
NODE_NAME     PC599 1
 '@T6G_MB_LIB.T6G(SCH_1):PAGE173_I79@PURE_QUANTA.Q_CAP(CHIPS)':
 'A': CDS_PINID='A';
NODE_NAME     PC604_1 1
 '@T6G_MB_LIB.T6G(SCH_1):PAGE173_I83@PURE_QUANTA.Q_CAP(CHIPS)':
 'A': CDS_PINID='A';
NODE_NAME     PL66 4
 '@T6G_MB_LIB.T6G(SCH_1):PAGE174_I25@PURE_QUANTA.Q_INDUCTOR4P_14(CHIPS)':
 '4': CDS_PINID='\4\';
NODE_NAME     PC615_3 1
 '@T6G_MB_LIB.T6G(SCH_1):PAGE174_I29@PURE_QUANTA.Q_CAP(CHIPS)':
 'A': CDS_PINID='A';
NODE_NAME     PR296 1
 '@T6G_MB_LIB.T6G(SCH_1):PAGE168_I40@PURE_QUANTA.Q_RES(CHIPS)':
 'A': CDS_PINID='A';
NODE_NAME     PR363 2
 '@T6G_MB_LIB.T6G(SCH_1):PAGE173_I18@PURE_QUANTA.Q_RES(CHIPS)':
 'B': CDS_PINID='B';
NODE_NAME     PR362 2
 '@T6G_MB_LIB.T6G(SCH_1):PAGE173_I27@PURE_QUANTA.Q_RES(CHIPS)':
 'B': CDS_PINID='B';
NODE_NAME     PL64 4
 '@T6G_MB_LIB.T6G(SCH_1):PAGE173_I53@PURE_QUANTA.Q_INDUCTOR4P_14(CHIPS)':
 '4': CDS_PINID='\4\';
NODE_NAME     PC600_2 1
 '@T6G_MB_LIB.T6G(SCH_1):PAGE173_I59@PURE_QUANTA.Q_CAP(CHIPS)':
 'A': CDS_PINID='A';
NODE_NAME     PC603_2 1
 '@T6G_MB_LIB.T6G(SCH_1):PAGE173_I61@PURE_QUANTA.Q_CAP(CHIPS)':
 'A': CDS_PINID='A';
NODE_NAME     PC598 1
 '@T6G_MB_LIB.T6G(SCH_1):PAGE173_I64@PURE_QUANTA.Q_CAPP(CHIPS)':
 'A': CDS_PINID='A';
NODE_NAME     PC602_1 1
 '@T6G_MB_LIB.T6G(SCH_1):PAGE173_I80@PURE_QUANTA.Q_CAP(CHIPS)':
 'A': CDS_PINID='A';
NODE_NAME     PR334 1
 '@T6G_MB_LIB.T6G(SCH_1):PAGE173_I82@PURE_QUANTA.Q_RES(CHIPS)':
 'A': CDS_PINID='A';
NODE_NAME     PR367 2
 '@T6G_MB_LIB.T6G(SCH_1):PAGE174_I11@PURE_QUANTA.Q_RES(CHIPS)':
 'B': CDS_PINID='B';
NODE_NAME     PC614_3 1
 '@T6G_MB_LIB.T6G(SCH_1):PAGE174_I27@PURE_QUANTA.Q_CAP(CHIPS)':
 'A': CDS_PINID='A';
NET_NAME
'PVDDCR_SOC_P0_EN'
 '@T6G_MB_LIB.T6G(SCH_1):PVDDCR_SOC_P0_EN':
 C_SIGNAL='@t6g_mb_lib.t6g(sch_1):pvddcr_soc_p0_en';
NODE_NAME     U18 W3
 '@T6G_MB_LIB.T6G(SCH_1):PAGE81_I143@PURE_QUANTA.LCMXO3LF9400C5BG484C(CHIPS)':
 'PL29C': CDS_PINID='PL29C';
NODE_NAME     R8282 1
 '@T6G_MB_LIB.T6G(SCH_1):PAGE168_I2@PURE_QUANTA.Q_RES(CHIPS)':
 'A': CDS_PINID='A';
NET_NAME
'PVDDCR_SOC_P0_EN//ADDR_CFG'
 '@T6G_MB_LIB.T6G(SCH_1):PVDDCR_SOC_P0_EN//ADDR_CFG':
 C_SIGNAL='@t6g_mb_lib.t6g(sch_1):\pvddcr_soc_p0_en//addr_cfg\';
NODE_NAME     PQ13 D
 '@T6G_MB_LIB.T6G(SCH_1):PAGE168_I19@PURE_QUANTA.MOSFET_PCH_GDS_ESD_PROTECTED(CHIPS)':
 'D': CDS_PINID='D';
NODE_NAME     PR292 1
 '@T6G_MB_LIB.T6G(SCH_1):PAGE168_I27@PURE_QUANTA.Q_RES(CHIPS)':
 'A': CDS_PINID='A';
NODE_NAME     PU42 42
 '@T6G_MB_LIB.T6G(SCH_1):PAGE168_I135@PURE_QUANTA.RAA229620GNPHA0(CHIPS)':
 'EN1||ADDR_CFG': CDS_PINID='\en1||addr_cfg\';
NET_NAME
'PVDDCR_SOC_P0_EN_GD'
 '@T6G_MB_LIB.T6G(SCH_1):PVDDCR_SOC_P0_EN_GD':
 C_SIGNAL='@t6g_mb_lib.t6g(sch_1):pvddcr_soc_p0_en_gd';
NODE_NAME     PQ17 D
 '@T6G_MB_LIB.T6G(SCH_1):PAGE168_I17@PURE_QUANTA.MOSFET_N(CHIPS)':
 'DRAIN': CDS_PINID='DRAIN';
NODE_NAME     PR285 2
 '@T6G_MB_LIB.T6G(SCH_1):PAGE168_I18@PURE_QUANTA.Q_RES(CHIPS)':
 'B': CDS_PINID='B';
NODE_NAME     PQ13 G
 '@T6G_MB_LIB.T6G(SCH_1):PAGE168_I19@PURE_QUANTA.MOSFET_PCH_GDS_ESD_PROTECTED(CHIPS)':
 'G': CDS_PINID='G';
NET_NAME
'PVDDCR_SOC_P0_EN_RC'
 '@T6G_MB_LIB.T6G(SCH_1):PVDDCR_SOC_P0_EN_RC':
 C_SIGNAL='@t6g_mb_lib.t6g(sch_1):pvddcr_soc_p0_en_rc';
NODE_NAME     C461 1
 '@T6G_MB_LIB.T6G(SCH_1):PAGE168_I13@PURE_QUANTA.Q_CAP(CHIPS)':
 'A': CDS_PINID='A';
NODE_NAME     R8282 2
 '@T6G_MB_LIB.T6G(SCH_1):PAGE168_I2@PURE_QUANTA.Q_RES(CHIPS)':
 'B': CDS_PINID='B';
NODE_NAME     PQ17 G
 '@T6G_MB_LIB.T6G(SCH_1):PAGE168_I17@PURE_QUANTA.MOSFET_N(CHIPS)':
 'GATE': CDS_PINID='GATE';
NODE_NAME     R6089 1
 '@T6G_MB_LIB.T6G(SCH_1):PAGE168_I136@PURE_QUANTA.Q_RES(CHIPS)':
 'A': CDS_PINID='A';
NET_NAME
'PVDDCR_SOC_P0_IMON1'
 '@T6G_MB_LIB.T6G(SCH_1):PVDDCR_SOC_P0_IMON1':
 C_SIGNAL='@t6g_mb_lib.t6g(sch_1):pvddcr_soc_p0_imon1';
NODE_NAME     PU42 38
 '@T6G_MB_LIB.T6G(SCH_1):PAGE168_I135@PURE_QUANTA.RAA229620GNPHA0(CHIPS)':
 'CS0': CDS_PINID='CS0';
NODE_NAME     PU49 38
 '@T6G_MB_LIB.T6G(SCH_1):PAGE173_I41@PURE_QUANTA.ISL99390FRZTR5935(CHIPS)':
 'IOUT': CDS_PINID='IOUT';
NET_NAME
'PVDDCR_SOC_P0_IMON2'
 '@T6G_MB_LIB.T6G(SCH_1):PVDDCR_SOC_P0_IMON2':
 C_SIGNAL='@t6g_mb_lib.t6g(sch_1):pvddcr_soc_p0_imon2';
NODE_NAME     PU42 37
 '@T6G_MB_LIB.T6G(SCH_1):PAGE168_I135@PURE_QUANTA.RAA229620GNPHA0(CHIPS)':
 'CS1': CDS_PINID='CS1';
NODE_NAME     PU50 38
 '@T6G_MB_LIB.T6G(SCH_1):PAGE173_I86@PURE_QUANTA.ISL99390FRZTR5935(CHIPS)':
 'IOUT': CDS_PINID='IOUT';
NET_NAME
'PVDDCR_SOC_P0_IMON3'
 '@T6G_MB_LIB.T6G(SCH_1):PVDDCR_SOC_P0_IMON3':
 C_SIGNAL='@t6g_mb_lib.t6g(sch_1):pvddcr_soc_p0_imon3';
NODE_NAME     PU51 38
 '@T6G_MB_LIB.T6G(SCH_1):PAGE174_I38@PURE_QUANTA.ISL99390FRZTR5935(CHIPS)':
 'IOUT': CDS_PINID='IOUT';
NODE_NAME     PU42 36
 '@T6G_MB_LIB.T6G(SCH_1):PAGE168_I135@PURE_QUANTA.RAA229620GNPHA0(CHIPS)':
 'CS2': CDS_PINID='CS2';
NET_NAME
'PVDDCR_SOC_P0_LSET1'
 '@T6G_MB_LIB.T6G(SCH_1):PVDDCR_SOC_P0_LSET1':
 C_SIGNAL='@t6g_mb_lib.t6g(sch_1):pvddcr_soc_p0_lset1';
NODE_NAME     PR358 2
 '@T6G_MB_LIB.T6G(SCH_1):PAGE173_I32@PURE_QUANTA.Q_RES(CHIPS)':
 'B': CDS_PINID='B';
NODE_NAME     PU49 37
 '@T6G_MB_LIB.T6G(SCH_1):PAGE173_I41@PURE_QUANTA.ISL99390FRZTR5935(CHIPS)':
 'LSET': CDS_PINID='LSET';
NET_NAME
'PVDDCR_SOC_P0_LSET2'
 '@T6G_MB_LIB.T6G(SCH_1):PVDDCR_SOC_P0_LSET2':
 C_SIGNAL='@t6g_mb_lib.t6g(sch_1):pvddcr_soc_p0_lset2';
NODE_NAME     PR359 2
 '@T6G_MB_LIB.T6G(SCH_1):PAGE173_I8@PURE_QUANTA.Q_RES(CHIPS)':
 'B': CDS_PINID='B';
NODE_NAME     PU50 37
 '@T6G_MB_LIB.T6G(SCH_1):PAGE173_I86@PURE_QUANTA.ISL99390FRZTR5935(CHIPS)':
 'LSET': CDS_PINID='LSET';
NET_NAME
'PVDDCR_SOC_P0_LSET3'
 '@T6G_MB_LIB.T6G(SCH_1):PVDDCR_SOC_P0_LSET3':
 C_SIGNAL='@t6g_mb_lib.t6g(sch_1):pvddcr_soc_p0_lset3';
NODE_NAME     PR365 2
 '@T6G_MB_LIB.T6G(SCH_1):PAGE174_I7@PURE_QUANTA.Q_RES(CHIPS)':
 'B': CDS_PINID='B';
NODE_NAME     PU51 37
 '@T6G_MB_LIB.T6G(SCH_1):PAGE174_I38@PURE_QUANTA.ISL99390FRZTR5935(CHIPS)':
 'LSET': CDS_PINID='LSET';
NET_NAME
'PVDDCR_SOC_P0_PWM1'
 '@T6G_MB_LIB.T6G(SCH_1):PVDDCR_SOC_P0_PWM1':
 C_SIGNAL='@t6g_mb_lib.t6g(sch_1):pvddcr_soc_p0_pwm1';
NODE_NAME     PU42 1
 '@T6G_MB_LIB.T6G(SCH_1):PAGE168_I135@PURE_QUANTA.RAA229620GNPHA0(CHIPS)':
 'PWM0': CDS_PINID='PWM0';
NODE_NAME     PU49 34
 '@T6G_MB_LIB.T6G(SCH_1):PAGE173_I41@PURE_QUANTA.ISL99390FRZTR5935(CHIPS)':
 'PWM': CDS_PINID='PWM';
NET_NAME
'PVDDCR_SOC_P0_PWM2'
 '@T6G_MB_LIB.T6G(SCH_1):PVDDCR_SOC_P0_PWM2':
 C_SIGNAL='@t6g_mb_lib.t6g(sch_1):pvddcr_soc_p0_pwm2';
NODE_NAME     PU42 2
 '@T6G_MB_LIB.T6G(SCH_1):PAGE168_I135@PURE_QUANTA.RAA229620GNPHA0(CHIPS)':
 'PWM1': CDS_PINID='PWM1';
NODE_NAME     PU50 34
 '@T6G_MB_LIB.T6G(SCH_1):PAGE173_I86@PURE_QUANTA.ISL99390FRZTR5935(CHIPS)':
 'PWM': CDS_PINID='PWM';
NET_NAME
'PVDDCR_SOC_P0_PWM3'
 '@T6G_MB_LIB.T6G(SCH_1):PVDDCR_SOC_P0_PWM3':
 C_SIGNAL='@t6g_mb_lib.t6g(sch_1):pvddcr_soc_p0_pwm3';
NODE_NAME     PU51 34
 '@T6G_MB_LIB.T6G(SCH_1):PAGE174_I38@PURE_QUANTA.ISL99390FRZTR5935(CHIPS)':
 'PWM': CDS_PINID='PWM';
NODE_NAME     PU42 3
 '@T6G_MB_LIB.T6G(SCH_1):PAGE168_I135@PURE_QUANTA.RAA229620GNPHA0(CHIPS)':
 'PWM2': CDS_PINID='PWM2';
NET_NAME
'PVDDCR_SOC_P0_TEMP1'
 '@T6G_MB_LIB.T6G(SCH_1):PVDDCR_SOC_P0_TEMP1':
 C_SIGNAL='@t6g_mb_lib.t6g(sch_1):pvddcr_soc_p0_temp1';
NODE_NAME     PU51 36
 '@T6G_MB_LIB.T6G(SCH_1):PAGE174_I38@PURE_QUANTA.ISL99390FRZTR5935(CHIPS)':
 'TOUT_FLT': CDS_PINID='TOUT_FLT';
NODE_NAME     PC472 1
 '@T6G_MB_LIB.T6G(SCH_1):PAGE168_I98@PURE_QUANTA.Q_CAP(CHIPS)':
 'A': CDS_PINID='A';
NODE_NAME     PU42 43
 '@T6G_MB_LIB.T6G(SCH_1):PAGE168_I135@PURE_QUANTA.RAA229620GNPHA0(CHIPS)':
 'TEMP1': CDS_PINID='TEMP1';
NODE_NAME     PU49 36
 '@T6G_MB_LIB.T6G(SCH_1):PAGE173_I41@PURE_QUANTA.ISL99390FRZTR5935(CHIPS)':
 'TOUT_FLT': CDS_PINID='TOUT_FLT';
NODE_NAME     PU50 36
 '@T6G_MB_LIB.T6G(SCH_1):PAGE173_I86@PURE_QUANTA.ISL99390FRZTR5935(CHIPS)':
 'TOUT_FLT': CDS_PINID='TOUT_FLT';
NET_NAME
'PVDDCR_SOC_P0_VCC1'
 '@T6G_MB_LIB.T6G(SCH_1):PVDDCR_SOC_P0_VCC1':
 C_SIGNAL='@t6g_mb_lib.t6g(sch_1):pvddcr_soc_p0_vcc1';
NODE_NAME     PC579 1
 '@T6G_MB_LIB.T6G(SCH_1):PAGE173_I36@PURE_QUANTA.Q_CAP(CHIPS)':
 'A': CDS_PINID='A';
NODE_NAME     PR356 2
 '@T6G_MB_LIB.T6G(SCH_1):PAGE173_I38@PURE_QUANTA.Q_RES(CHIPS)':
 'B': CDS_PINID='B';
NODE_NAME     PU49 35
 '@T6G_MB_LIB.T6G(SCH_1):PAGE173_I41@PURE_QUANTA.ISL99390FRZTR5935(CHIPS)':
 'EN': CDS_PINID='EN';
NODE_NAME     PU49 3
 '@T6G_MB_LIB.T6G(SCH_1):PAGE173_I41@PURE_QUANTA.ISL99390FRZTR5935(CHIPS)':
 'VCC': CDS_PINID='VCC';
NET_NAME
'PVDDCR_SOC_P0_VCC2'
 '@T6G_MB_LIB.T6G(SCH_1):PVDDCR_SOC_P0_VCC2':
 C_SIGNAL='@t6g_mb_lib.t6g(sch_1):pvddcr_soc_p0_vcc2';
NODE_NAME     PC580 1
 '@T6G_MB_LIB.T6G(SCH_1):PAGE173_I11@PURE_QUANTA.Q_CAP(CHIPS)':
 'A': CDS_PINID='A';
NODE_NAME     PR357 2
 '@T6G_MB_LIB.T6G(SCH_1):PAGE173_I12@PURE_QUANTA.Q_RES(CHIPS)':
 'B': CDS_PINID='B';
NODE_NAME     PU50 35
 '@T6G_MB_LIB.T6G(SCH_1):PAGE173_I86@PURE_QUANTA.ISL99390FRZTR5935(CHIPS)':
 'EN': CDS_PINID='EN';
NODE_NAME     PU50 3
 '@T6G_MB_LIB.T6G(SCH_1):PAGE173_I86@PURE_QUANTA.ISL99390FRZTR5935(CHIPS)':
 'VCC': CDS_PINID='VCC';
NET_NAME
'PVDDCR_SOC_P0_VCC3'
 '@T6G_MB_LIB.T6G(SCH_1):PVDDCR_SOC_P0_VCC3':
 C_SIGNAL='@t6g_mb_lib.t6g(sch_1):pvddcr_soc_p0_vcc3';
NODE_NAME     PU51 35
 '@T6G_MB_LIB.T6G(SCH_1):PAGE174_I38@PURE_QUANTA.ISL99390FRZTR5935(CHIPS)':
 'EN': CDS_PINID='EN';
NODE_NAME     PU51 3
 '@T6G_MB_LIB.T6G(SCH_1):PAGE174_I38@PURE_QUANTA.ISL99390FRZTR5935(CHIPS)':
 'VCC': CDS_PINID='VCC';
NODE_NAME     PC606 1
 '@T6G_MB_LIB.T6G(SCH_1):PAGE174_I14@PURE_QUANTA.Q_CAP(CHIPS)':
 'A': CDS_PINID='A';
NODE_NAME     PR364 2
 '@T6G_MB_LIB.T6G(SCH_1):PAGE174_I15@PURE_QUANTA.Q_RES(CHIPS)':
 'B': CDS_PINID='B';
NET_NAME
'PVDDCR_SOC_P0_VOS1'
 '@T6G_MB_LIB.T6G(SCH_1):PVDDCR_SOC_P0_VOS1':
 C_SIGNAL='@t6g_mb_lib.t6g(sch_1):pvddcr_soc_p0_vos1';
NODE_NAME     PR362 1
 '@T6G_MB_LIB.T6G(SCH_1):PAGE173_I27@PURE_QUANTA.Q_RES(CHIPS)':
 'A': CDS_PINID='A';
NODE_NAME     PU49 1
 '@T6G_MB_LIB.T6G(SCH_1):PAGE173_I41@PURE_QUANTA.ISL99390FRZTR5935(CHIPS)':
 'VOS': CDS_PINID='VOS';
NET_NAME
'PVDDCR_SOC_P0_VOS2'
 '@T6G_MB_LIB.T6G(SCH_1):PVDDCR_SOC_P0_VOS2':
 C_SIGNAL='@t6g_mb_lib.t6g(sch_1):pvddcr_soc_p0_vos2';
NODE_NAME     PR363 1
 '@T6G_MB_LIB.T6G(SCH_1):PAGE173_I18@PURE_QUANTA.Q_RES(CHIPS)':
 'A': CDS_PINID='A';
NODE_NAME     PU50 1
 '@T6G_MB_LIB.T6G(SCH_1):PAGE173_I86@PURE_QUANTA.ISL99390FRZTR5935(CHIPS)':
 'VOS': CDS_PINID='VOS';
NET_NAME
'PVDDCR_SOC_P0_VOS3'
 '@T6G_MB_LIB.T6G(SCH_1):PVDDCR_SOC_P0_VOS3':
 C_SIGNAL='@t6g_mb_lib.t6g(sch_1):pvddcr_soc_p0_vos3';
NODE_NAME     PU51 1
 '@T6G_MB_LIB.T6G(SCH_1):PAGE174_I38@PURE_QUANTA.ISL99390FRZTR5935(CHIPS)':
 'VOS': CDS_PINID='VOS';
NODE_NAME     PR367 1
 '@T6G_MB_LIB.T6G(SCH_1):PAGE174_I11@PURE_QUANTA.Q_RES(CHIPS)':
 'A': CDS_PINID='A';
NET_NAME
'PVDDCR_SOC_P1'
 '@T6G_MB_LIB.T6G(SCH_1):PVDDCR_SOC_P1':
 C_SIGNAL='@t6g_mb_lib.t6g(sch_1):pvddcr_soc_p1',
 CDS_GLOBAL_NET='TRUE';
NODE_NAME     U26 AA22
 '@T6G_MB_LIB.T6G(SCH_1):PAGE57_I49@PURE_QUANTA.GENOA_SP5(CHIPS)':
 'VDDCR_SOC_AA22': CDS_PINID='VDDCR_SOC_AA22';
NODE_NAME     U26 AC4
 '@T6G_MB_LIB.T6G(SCH_1):PAGE57_I49@PURE_QUANTA.GENOA_SP5(CHIPS)':
 'VDDCR_SOC_AC4': CDS_PINID='VDDCR_SOC_AC4';
NODE_NAME     U26 AC11
 '@T6G_MB_LIB.T6G(SCH_1):PAGE57_I49@PURE_QUANTA.GENOA_SP5(CHIPS)':
 'VDDCR_SOC_AC11': CDS_PINID='VDDCR_SOC_AC11';
NODE_NAME     U26 AC18
 '@T6G_MB_LIB.T6G(SCH_1):PAGE57_I49@PURE_QUANTA.GENOA_SP5(CHIPS)':
 'VDDCR_SOC_AC18': CDS_PINID='VDDCR_SOC_AC18';
NODE_NAME     U26 AD22
 '@T6G_MB_LIB.T6G(SCH_1):PAGE57_I49@PURE_QUANTA.GENOA_SP5(CHIPS)':
 'VDDCR_SOC_AD22': CDS_PINID='VDDCR_SOC_AD22';
NODE_NAME     U26 AF5
 '@T6G_MB_LIB.T6G(SCH_1):PAGE57_I49@PURE_QUANTA.GENOA_SP5(CHIPS)':
 'VDDCR_SOC_AF5': CDS_PINID='VDDCR_SOC_AF5';
NODE_NAME     U26 AF12
 '@T6G_MB_LIB.T6G(SCH_1):PAGE57_I49@PURE_QUANTA.GENOA_SP5(CHIPS)':
 'VDDCR_SOC_AF12': CDS_PINID='VDDCR_SOC_AF12';
NODE_NAME     U26 AF19
 '@T6G_MB_LIB.T6G(SCH_1):PAGE57_I49@PURE_QUANTA.GENOA_SP5(CHIPS)':
 'VDDCR_SOC_AF19': CDS_PINID='VDDCR_SOC_AF19';
NODE_NAME     U26 AH22
 '@T6G_MB_LIB.T6G(SCH_1):PAGE57_I49@PURE_QUANTA.GENOA_SP5(CHIPS)':
 'VDDCR_SOC_AH22': CDS_PINID='VDDCR_SOC_AH22';
NODE_NAME     U26 AJ4
 '@T6G_MB_LIB.T6G(SCH_1):PAGE57_I49@PURE_QUANTA.GENOA_SP5(CHIPS)':
 'VDDCR_SOC_AJ4': CDS_PINID='VDDCR_SOC_AJ4';
NODE_NAME     U26 AJ11
 '@T6G_MB_LIB.T6G(SCH_1):PAGE57_I49@PURE_QUANTA.GENOA_SP5(CHIPS)':
 'VDDCR_SOC_AJ11': CDS_PINID='VDDCR_SOC_AJ11';
NODE_NAME     U26 AJ18
 '@T6G_MB_LIB.T6G(SCH_1):PAGE57_I49@PURE_QUANTA.GENOA_SP5(CHIPS)':
 'VDDCR_SOC_AJ18': CDS_PINID='VDDCR_SOC_AJ18';
NODE_NAME     U26 AM5
 '@T6G_MB_LIB.T6G(SCH_1):PAGE57_I49@PURE_QUANTA.GENOA_SP5(CHIPS)':
 'VDDCR_SOC_AM5': CDS_PINID='VDDCR_SOC_AM5';
NODE_NAME     U26 AM12
 '@T6G_MB_LIB.T6G(SCH_1):PAGE57_I49@PURE_QUANTA.GENOA_SP5(CHIPS)':
 'VDDCR_SOC_AM12': CDS_PINID='VDDCR_SOC_AM12';
NODE_NAME     U26 AM19
 '@T6G_MB_LIB.T6G(SCH_1):PAGE57_I49@PURE_QUANTA.GENOA_SP5(CHIPS)':
 'VDDCR_SOC_AM19': CDS_PINID='VDDCR_SOC_AM19';
NODE_NAME     U26 AM22
 '@T6G_MB_LIB.T6G(SCH_1):PAGE57_I49@PURE_QUANTA.GENOA_SP5(CHIPS)':
 'VDDCR_SOC_AM22': CDS_PINID='VDDCR_SOC_AM22';
NODE_NAME     U26 AR4
 '@T6G_MB_LIB.T6G(SCH_1):PAGE57_I49@PURE_QUANTA.GENOA_SP5(CHIPS)':
 'VDDCR_SOC_AR4': CDS_PINID='VDDCR_SOC_AR4';
NODE_NAME     U26 AR11
 '@T6G_MB_LIB.T6G(SCH_1):PAGE57_I49@PURE_QUANTA.GENOA_SP5(CHIPS)':
 'VDDCR_SOC_AR11': CDS_PINID='VDDCR_SOC_AR11';
NODE_NAME     U26 AR18
 '@T6G_MB_LIB.T6G(SCH_1):PAGE57_I49@PURE_QUANTA.GENOA_SP5(CHIPS)':
 'VDDCR_SOC_AR18': CDS_PINID='VDDCR_SOC_AR18';
NODE_NAME     U26 AT22
 '@T6G_MB_LIB.T6G(SCH_1):PAGE57_I49@PURE_QUANTA.GENOA_SP5(CHIPS)':
 'VDDCR_SOC_AT22': CDS_PINID='VDDCR_SOC_AT22';
NODE_NAME     U26 AU23
 '@T6G_MB_LIB.T6G(SCH_1):PAGE57_I49@PURE_QUANTA.GENOA_SP5(CHIPS)':
 'VDDCR_SOC_AU23': CDS_PINID='VDDCR_SOC_AU23';
NODE_NAME     U26 AU27
 '@T6G_MB_LIB.T6G(SCH_1):PAGE57_I49@PURE_QUANTA.GENOA_SP5(CHIPS)':
 'VDDCR_SOC_AU27': CDS_PINID='VDDCR_SOC_AU27';
NODE_NAME     U26 AU31
 '@T6G_MB_LIB.T6G(SCH_1):PAGE57_I49@PURE_QUANTA.GENOA_SP5(CHIPS)':
 'VDDCR_SOC_AU31': CDS_PINID='VDDCR_SOC_AU31';
NODE_NAME     U26 AU35
 '@T6G_MB_LIB.T6G(SCH_1):PAGE57_I49@PURE_QUANTA.GENOA_SP5(CHIPS)':
 'VDDCR_SOC_AU35': CDS_PINID='VDDCR_SOC_AU35';
NODE_NAME     U26 AU40
 '@T6G_MB_LIB.T6G(SCH_1):PAGE57_I49@PURE_QUANTA.GENOA_SP5(CHIPS)':
 'VDDCR_SOC_AU40': CDS_PINID='VDDCR_SOC_AU40';
NODE_NAME     U26 AV5
 '@T6G_MB_LIB.T6G(SCH_1):PAGE57_I49@PURE_QUANTA.GENOA_SP5(CHIPS)':
 'VDDCR_SOC_AV5': CDS_PINID='VDDCR_SOC_AV5';
NODE_NAME     U26 AV12
 '@T6G_MB_LIB.T6G(SCH_1):PAGE57_I49@PURE_QUANTA.GENOA_SP5(CHIPS)':
 'VDDCR_SOC_AV12': CDS_PINID='VDDCR_SOC_AV12';
NODE_NAME     U26 AV19
 '@T6G_MB_LIB.T6G(SCH_1):PAGE57_I49@PURE_QUANTA.GENOA_SP5(CHIPS)':
 'VDDCR_SOC_AV19': CDS_PINID='VDDCR_SOC_AV19';
NODE_NAME     U26 AV22
 '@T6G_MB_LIB.T6G(SCH_1):PAGE57_I49@PURE_QUANTA.GENOA_SP5(CHIPS)':
 'VDDCR_SOC_AV22': CDS_PINID='VDDCR_SOC_AV22';
NODE_NAME     U26 AV24
 '@T6G_MB_LIB.T6G(SCH_1):PAGE57_I49@PURE_QUANTA.GENOA_SP5(CHIPS)':
 'VDDCR_SOC_AV24': CDS_PINID='VDDCR_SOC_AV24';
NODE_NAME     U26 AV26
 '@T6G_MB_LIB.T6G(SCH_1):PAGE57_I49@PURE_QUANTA.GENOA_SP5(CHIPS)':
 'VDDCR_SOC_AV26': CDS_PINID='VDDCR_SOC_AV26';
NODE_NAME     U26 AV28
 '@T6G_MB_LIB.T6G(SCH_1):PAGE57_I49@PURE_QUANTA.GENOA_SP5(CHIPS)':
 'VDDCR_SOC_AV28': CDS_PINID='VDDCR_SOC_AV28';
NODE_NAME     U26 AV30
 '@T6G_MB_LIB.T6G(SCH_1):PAGE57_I49@PURE_QUANTA.GENOA_SP5(CHIPS)':
 'VDDCR_SOC_AV30': CDS_PINID='VDDCR_SOC_AV30';
NODE_NAME     U26 AV32
 '@T6G_MB_LIB.T6G(SCH_1):PAGE57_I49@PURE_QUANTA.GENOA_SP5(CHIPS)':
 'VDDCR_SOC_AV32': CDS_PINID='VDDCR_SOC_AV32';
NODE_NAME     U26 AV34
 '@T6G_MB_LIB.T6G(SCH_1):PAGE57_I49@PURE_QUANTA.GENOA_SP5(CHIPS)':
 'VDDCR_SOC_AV34': CDS_PINID='VDDCR_SOC_AV34';
NODE_NAME     U26 AV36
 '@T6G_MB_LIB.T6G(SCH_1):PAGE57_I49@PURE_QUANTA.GENOA_SP5(CHIPS)':
 'VDDCR_SOC_AV36': CDS_PINID='VDDCR_SOC_AV36';
NODE_NAME     U26 AV39
 '@T6G_MB_LIB.T6G(SCH_1):PAGE57_I49@PURE_QUANTA.GENOA_SP5(CHIPS)':
 'VDDCR_SOC_AV39': CDS_PINID='VDDCR_SOC_AV39';
NODE_NAME     U26 AV41
 '@T6G_MB_LIB.T6G(SCH_1):PAGE57_I49@PURE_QUANTA.GENOA_SP5(CHIPS)':
 'VDDCR_SOC_AV41': CDS_PINID='VDDCR_SOC_AV41';
NODE_NAME     U26 AV43
 '@T6G_MB_LIB.T6G(SCH_1):PAGE57_I49@PURE_QUANTA.GENOA_SP5(CHIPS)':
 'VDDCR_SOC_AV43': CDS_PINID='VDDCR_SOC_AV43';
NODE_NAME     U26 AV45
 '@T6G_MB_LIB.T6G(SCH_1):PAGE57_I49@PURE_QUANTA.GENOA_SP5(CHIPS)':
 'VDDCR_SOC_AV45': CDS_PINID='VDDCR_SOC_AV45';
NODE_NAME     U26 AV47
 '@T6G_MB_LIB.T6G(SCH_1):PAGE57_I49@PURE_QUANTA.GENOA_SP5(CHIPS)':
 'VDDCR_SOC_AV47': CDS_PINID='VDDCR_SOC_AV47';
NODE_NAME     U26 AW23
 '@T6G_MB_LIB.T6G(SCH_1):PAGE57_I49@PURE_QUANTA.GENOA_SP5(CHIPS)':
 'VDDCR_SOC_AW23': CDS_PINID='VDDCR_SOC_AW23';
NODE_NAME     U26 AW25
 '@T6G_MB_LIB.T6G(SCH_1):PAGE57_I49@PURE_QUANTA.GENOA_SP5(CHIPS)':
 'VDDCR_SOC_AW25': CDS_PINID='VDDCR_SOC_AW25';
NODE_NAME     U26 AW27
 '@T6G_MB_LIB.T6G(SCH_1):PAGE57_I49@PURE_QUANTA.GENOA_SP5(CHIPS)':
 'VDDCR_SOC_AW27': CDS_PINID='VDDCR_SOC_AW27';
NODE_NAME     U26 AW48
 '@T6G_MB_LIB.T6G(SCH_1):PAGE57_I49@PURE_QUANTA.GENOA_SP5(CHIPS)':
 'VDDCR_SOC_AW48': CDS_PINID='VDDCR_SOC_AW48';
NODE_NAME     U26 AY22
 '@T6G_MB_LIB.T6G(SCH_1):PAGE57_I49@PURE_QUANTA.GENOA_SP5(CHIPS)':
 'VDDCR_SOC_AY22': CDS_PINID='VDDCR_SOC_AY22';
NODE_NAME     U26 AY24
 '@T6G_MB_LIB.T6G(SCH_1):PAGE57_I49@PURE_QUANTA.GENOA_SP5(CHIPS)':
 'VDDCR_SOC_AY24': CDS_PINID='VDDCR_SOC_AY24';
NODE_NAME     U26 AY26
 '@T6G_MB_LIB.T6G(SCH_1):PAGE57_I49@PURE_QUANTA.GENOA_SP5(CHIPS)':
 'VDDCR_SOC_AY26': CDS_PINID='VDDCR_SOC_AY26';
NODE_NAME     U26 AY28
 '@T6G_MB_LIB.T6G(SCH_1):PAGE57_I49@PURE_QUANTA.GENOA_SP5(CHIPS)':
 'VDDCR_SOC_AY28': CDS_PINID='VDDCR_SOC_AY28';
NODE_NAME     U26 AY49
 '@T6G_MB_LIB.T6G(SCH_1):PAGE57_I49@PURE_QUANTA.GENOA_SP5(CHIPS)':
 'VDDCR_SOC_AY49': CDS_PINID='VDDCR_SOC_AY49';
NODE_NAME     U26 B5
 '@T6G_MB_LIB.T6G(SCH_1):PAGE57_I49@PURE_QUANTA.GENOA_SP5(CHIPS)':
 'VDDCR_SOC_B5': CDS_PINID='VDDCR_SOC_B5';
NODE_NAME     U26 BA4
 '@T6G_MB_LIB.T6G(SCH_1):PAGE57_I49@PURE_QUANTA.GENOA_SP5(CHIPS)':
 'VDDCR_SOC_BA4': CDS_PINID='VDDCR_SOC_BA4';
NODE_NAME     U26 BA11
 '@T6G_MB_LIB.T6G(SCH_1):PAGE57_I49@PURE_QUANTA.GENOA_SP5(CHIPS)':
 'VDDCR_SOC_BA11': CDS_PINID='VDDCR_SOC_BA11';
NODE_NAME     U26 BA18
 '@T6G_MB_LIB.T6G(SCH_1):PAGE57_I49@PURE_QUANTA.GENOA_SP5(CHIPS)':
 'VDDCR_SOC_BA18': CDS_PINID='VDDCR_SOC_BA18';
NODE_NAME     U26 BA23
 '@T6G_MB_LIB.T6G(SCH_1):PAGE57_I49@PURE_QUANTA.GENOA_SP5(CHIPS)':
 'VDDCR_SOC_BA23': CDS_PINID='VDDCR_SOC_BA23';
NODE_NAME     U26 BA25
 '@T6G_MB_LIB.T6G(SCH_1):PAGE57_I49@PURE_QUANTA.GENOA_SP5(CHIPS)':
 'VDDCR_SOC_BA25': CDS_PINID='VDDCR_SOC_BA25';
NODE_NAME     U26 BA27
 '@T6G_MB_LIB.T6G(SCH_1):PAGE57_I49@PURE_QUANTA.GENOA_SP5(CHIPS)':
 'VDDCR_SOC_BA27': CDS_PINID='VDDCR_SOC_BA27';
NODE_NAME     U26 BA48
 '@T6G_MB_LIB.T6G(SCH_1):PAGE57_I49@PURE_QUANTA.GENOA_SP5(CHIPS)':
 'VDDCR_SOC_BA48': CDS_PINID='VDDCR_SOC_BA48';
NODE_NAME     U26 BB22
 '@T6G_MB_LIB.T6G(SCH_1):PAGE57_I49@PURE_QUANTA.GENOA_SP5(CHIPS)':
 'VDDCR_SOC_BB22': CDS_PINID='VDDCR_SOC_BB22';
NODE_NAME     U26 BB24
 '@T6G_MB_LIB.T6G(SCH_1):PAGE57_I49@PURE_QUANTA.GENOA_SP5(CHIPS)':
 'VDDCR_SOC_BB24': CDS_PINID='VDDCR_SOC_BB24';
NODE_NAME     U26 BB26
 '@T6G_MB_LIB.T6G(SCH_1):PAGE57_I49@PURE_QUANTA.GENOA_SP5(CHIPS)':
 'VDDCR_SOC_BB26': CDS_PINID='VDDCR_SOC_BB26';
NODE_NAME     U26 BB28
 '@T6G_MB_LIB.T6G(SCH_1):PAGE57_I49@PURE_QUANTA.GENOA_SP5(CHIPS)':
 'VDDCR_SOC_BB28': CDS_PINID='VDDCR_SOC_BB28';
NODE_NAME     U26 BB49
 '@T6G_MB_LIB.T6G(SCH_1):PAGE57_I49@PURE_QUANTA.GENOA_SP5(CHIPS)':
 'VDDCR_SOC_BB49': CDS_PINID='VDDCR_SOC_BB49';
NODE_NAME     U26 BC23
 '@T6G_MB_LIB.T6G(SCH_1):PAGE57_I49@PURE_QUANTA.GENOA_SP5(CHIPS)':
 'VDDCR_SOC_BC23': CDS_PINID='VDDCR_SOC_BC23';
NODE_NAME     U26 BC25
 '@T6G_MB_LIB.T6G(SCH_1):PAGE57_I49@PURE_QUANTA.GENOA_SP5(CHIPS)':
 'VDDCR_SOC_BC25': CDS_PINID='VDDCR_SOC_BC25';
NODE_NAME     U26 BC27
 '@T6G_MB_LIB.T6G(SCH_1):PAGE57_I49@PURE_QUANTA.GENOA_SP5(CHIPS)':
 'VDDCR_SOC_BC27': CDS_PINID='VDDCR_SOC_BC27';
NODE_NAME     U26 BC48
 '@T6G_MB_LIB.T6G(SCH_1):PAGE57_I49@PURE_QUANTA.GENOA_SP5(CHIPS)':
 'VDDCR_SOC_BC48': CDS_PINID='VDDCR_SOC_BC48';
NODE_NAME     U26 BD5
 '@T6G_MB_LIB.T6G(SCH_1):PAGE57_I49@PURE_QUANTA.GENOA_SP5(CHIPS)':
 'VDDCR_SOC_BD5': CDS_PINID='VDDCR_SOC_BD5';
NODE_NAME     U26 BD12
 '@T6G_MB_LIB.T6G(SCH_1):PAGE57_I49@PURE_QUANTA.GENOA_SP5(CHIPS)':
 'VDDCR_SOC_BD12': CDS_PINID='VDDCR_SOC_BD12';
NODE_NAME     U26 BD19
 '@T6G_MB_LIB.T6G(SCH_1):PAGE57_I49@PURE_QUANTA.GENOA_SP5(CHIPS)':
 'VDDCR_SOC_BD19': CDS_PINID='VDDCR_SOC_BD19';
NODE_NAME     U26 BD22
 '@T6G_MB_LIB.T6G(SCH_1):PAGE57_I49@PURE_QUANTA.GENOA_SP5(CHIPS)':
 'VDDCR_SOC_BD22': CDS_PINID='VDDCR_SOC_BD22';
NODE_NAME     U26 BD24
 '@T6G_MB_LIB.T6G(SCH_1):PAGE57_I49@PURE_QUANTA.GENOA_SP5(CHIPS)':
 'VDDCR_SOC_BD24': CDS_PINID='VDDCR_SOC_BD24';
NODE_NAME     U26 BD26
 '@T6G_MB_LIB.T6G(SCH_1):PAGE57_I49@PURE_QUANTA.GENOA_SP5(CHIPS)':
 'VDDCR_SOC_BD26': CDS_PINID='VDDCR_SOC_BD26';
NODE_NAME     U26 BD28
 '@T6G_MB_LIB.T6G(SCH_1):PAGE57_I49@PURE_QUANTA.GENOA_SP5(CHIPS)':
 'VDDCR_SOC_BD28': CDS_PINID='VDDCR_SOC_BD28';
NODE_NAME     U26 BD48
 '@T6G_MB_LIB.T6G(SCH_1):PAGE57_I49@PURE_QUANTA.GENOA_SP5(CHIPS)':
 'VDDCR_SOC_BD48': CDS_PINID='VDDCR_SOC_BD48';
NODE_NAME     U26 BF23
 '@T6G_MB_LIB.T6G(SCH_1):PAGE57_I49@PURE_QUANTA.GENOA_SP5(CHIPS)':
 'VDDCR_SOC_BF23': CDS_PINID='VDDCR_SOC_BF23';
NODE_NAME     U26 BF25
 '@T6G_MB_LIB.T6G(SCH_1):PAGE57_I49@PURE_QUANTA.GENOA_SP5(CHIPS)':
 'VDDCR_SOC_BF25': CDS_PINID='VDDCR_SOC_BF25';
NODE_NAME     U26 BF27
 '@T6G_MB_LIB.T6G(SCH_1):PAGE57_I49@PURE_QUANTA.GENOA_SP5(CHIPS)':
 'VDDCR_SOC_BF27': CDS_PINID='VDDCR_SOC_BF27';
NODE_NAME     U26 BF48
 '@T6G_MB_LIB.T6G(SCH_1):PAGE57_I49@PURE_QUANTA.GENOA_SP5(CHIPS)':
 'VDDCR_SOC_BF48': CDS_PINID='VDDCR_SOC_BF48';
NODE_NAME     U26 BG22
 '@T6G_MB_LIB.T6G(SCH_1):PAGE57_I49@PURE_QUANTA.GENOA_SP5(CHIPS)':
 'VDDCR_SOC_BG22': CDS_PINID='VDDCR_SOC_BG22';
NODE_NAME     U26 BG24
 '@T6G_MB_LIB.T6G(SCH_1):PAGE57_I49@PURE_QUANTA.GENOA_SP5(CHIPS)':
 'VDDCR_SOC_BG24': CDS_PINID='VDDCR_SOC_BG24';
NODE_NAME     U26 BG26
 '@T6G_MB_LIB.T6G(SCH_1):PAGE57_I49@PURE_QUANTA.GENOA_SP5(CHIPS)':
 'VDDCR_SOC_BG26': CDS_PINID='VDDCR_SOC_BG26';
NODE_NAME     U26 BG28
 '@T6G_MB_LIB.T6G(SCH_1):PAGE57_I49@PURE_QUANTA.GENOA_SP5(CHIPS)':
 'VDDCR_SOC_BG28': CDS_PINID='VDDCR_SOC_BG28';
NODE_NAME     U26 BG48
 '@T6G_MB_LIB.T6G(SCH_1):PAGE57_I49@PURE_QUANTA.GENOA_SP5(CHIPS)':
 'VDDCR_SOC_BG48': CDS_PINID='VDDCR_SOC_BG48';
NODE_NAME     U26 BH23
 '@T6G_MB_LIB.T6G(SCH_1):PAGE57_I49@PURE_QUANTA.GENOA_SP5(CHIPS)':
 'VDDCR_SOC_BH23': CDS_PINID='VDDCR_SOC_BH23';
NODE_NAME     U26 BH25
 '@T6G_MB_LIB.T6G(SCH_1):PAGE57_I49@PURE_QUANTA.GENOA_SP5(CHIPS)':
 'VDDCR_SOC_BH25': CDS_PINID='VDDCR_SOC_BH25';
NODE_NAME     U26 BH48
 '@T6G_MB_LIB.T6G(SCH_1):PAGE57_I49@PURE_QUANTA.GENOA_SP5(CHIPS)':
 'VDDCR_SOC_BH48': CDS_PINID='VDDCR_SOC_BH48';
NODE_NAME     U26 BJ4
 '@T6G_MB_LIB.T6G(SCH_1):PAGE57_I49@PURE_QUANTA.GENOA_SP5(CHIPS)':
 'VDDCR_SOC_BJ4': CDS_PINID='VDDCR_SOC_BJ4';
NODE_NAME     U26 BJ11
 '@T6G_MB_LIB.T6G(SCH_1):PAGE57_I49@PURE_QUANTA.GENOA_SP5(CHIPS)':
 'VDDCR_SOC_BJ11': CDS_PINID='VDDCR_SOC_BJ11';
NODE_NAME     U26 BJ48
 '@T6G_MB_LIB.T6G(SCH_1):PAGE57_I49@PURE_QUANTA.GENOA_SP5(CHIPS)':
 'VDDCR_SOC_BJ48': CDS_PINID='VDDCR_SOC_BJ48';
NODE_NAME     U26 BM5
 '@T6G_MB_LIB.T6G(SCH_1):PAGE57_I49@PURE_QUANTA.GENOA_SP5(CHIPS)':
 'VDDCR_SOC_BM5': CDS_PINID='VDDCR_SOC_BM5';
NODE_NAME     U26 C4
 '@T6G_MB_LIB.T6G(SCH_1):PAGE57_I49@PURE_QUANTA.GENOA_SP5(CHIPS)':
 'VDDCR_SOC_C4': CDS_PINID='VDDCR_SOC_C4';
NODE_NAME     U26 E4
 '@T6G_MB_LIB.T6G(SCH_1):PAGE57_I49@PURE_QUANTA.GENOA_SP5(CHIPS)':
 'VDDCR_SOC_E4': CDS_PINID='VDDCR_SOC_E4';
NODE_NAME     U26 E11
 '@T6G_MB_LIB.T6G(SCH_1):PAGE57_I49@PURE_QUANTA.GENOA_SP5(CHIPS)':
 'VDDCR_SOC_E11': CDS_PINID='VDDCR_SOC_E11';
NODE_NAME     U26 H5
 '@T6G_MB_LIB.T6G(SCH_1):PAGE57_I49@PURE_QUANTA.GENOA_SP5(CHIPS)':
 'VDDCR_SOC_H5': CDS_PINID='VDDCR_SOC_H5';
NODE_NAME     U26 H12
 '@T6G_MB_LIB.T6G(SCH_1):PAGE57_I49@PURE_QUANTA.GENOA_SP5(CHIPS)':
 'VDDCR_SOC_H12': CDS_PINID='VDDCR_SOC_H12';
NODE_NAME     U26 H19
 '@T6G_MB_LIB.T6G(SCH_1):PAGE57_I49@PURE_QUANTA.GENOA_SP5(CHIPS)':
 'VDDCR_SOC_H19': CDS_PINID='VDDCR_SOC_H19';
NODE_NAME     U26 K22
 '@T6G_MB_LIB.T6G(SCH_1):PAGE57_I49@PURE_QUANTA.GENOA_SP5(CHIPS)':
 'VDDCR_SOC_K22': CDS_PINID='VDDCR_SOC_K22';
NODE_NAME     U26 L4
 '@T6G_MB_LIB.T6G(SCH_1):PAGE57_I49@PURE_QUANTA.GENOA_SP5(CHIPS)':
 'VDDCR_SOC_L4': CDS_PINID='VDDCR_SOC_L4';
NODE_NAME     U26 L11
 '@T6G_MB_LIB.T6G(SCH_1):PAGE57_I49@PURE_QUANTA.GENOA_SP5(CHIPS)':
 'VDDCR_SOC_L11': CDS_PINID='VDDCR_SOC_L11';
NODE_NAME     U26 L18
 '@T6G_MB_LIB.T6G(SCH_1):PAGE57_I49@PURE_QUANTA.GENOA_SP5(CHIPS)':
 'VDDCR_SOC_L18': CDS_PINID='VDDCR_SOC_L18';
NODE_NAME     U26 P5
 '@T6G_MB_LIB.T6G(SCH_1):PAGE57_I49@PURE_QUANTA.GENOA_SP5(CHIPS)':
 'VDDCR_SOC_P5': CDS_PINID='VDDCR_SOC_P5';
NODE_NAME     U26 P12
 '@T6G_MB_LIB.T6G(SCH_1):PAGE57_I49@PURE_QUANTA.GENOA_SP5(CHIPS)':
 'VDDCR_SOC_P12': CDS_PINID='VDDCR_SOC_P12';
NODE_NAME     U26 P19
 '@T6G_MB_LIB.T6G(SCH_1):PAGE57_I49@PURE_QUANTA.GENOA_SP5(CHIPS)':
 'VDDCR_SOC_P19': CDS_PINID='VDDCR_SOC_P19';
NODE_NAME     U26 P22
 '@T6G_MB_LIB.T6G(SCH_1):PAGE57_I49@PURE_QUANTA.GENOA_SP5(CHIPS)':
 'VDDCR_SOC_P22': CDS_PINID='VDDCR_SOC_P22';
NODE_NAME     U26 U4
 '@T6G_MB_LIB.T6G(SCH_1):PAGE57_I49@PURE_QUANTA.GENOA_SP5(CHIPS)':
 'VDDCR_SOC_U4': CDS_PINID='VDDCR_SOC_U4';
NODE_NAME     U26 U11
 '@T6G_MB_LIB.T6G(SCH_1):PAGE57_I49@PURE_QUANTA.GENOA_SP5(CHIPS)':
 'VDDCR_SOC_U11': CDS_PINID='VDDCR_SOC_U11';
NODE_NAME     U26 U18
 '@T6G_MB_LIB.T6G(SCH_1):PAGE57_I49@PURE_QUANTA.GENOA_SP5(CHIPS)':
 'VDDCR_SOC_U18': CDS_PINID='VDDCR_SOC_U18';
NODE_NAME     U26 V22
 '@T6G_MB_LIB.T6G(SCH_1):PAGE57_I49@PURE_QUANTA.GENOA_SP5(CHIPS)':
 'VDDCR_SOC_V22': CDS_PINID='VDDCR_SOC_V22';
NODE_NAME     U26 Y5
 '@T6G_MB_LIB.T6G(SCH_1):PAGE57_I49@PURE_QUANTA.GENOA_SP5(CHIPS)':
 'VDDCR_SOC_Y5': CDS_PINID='VDDCR_SOC_Y5';
NODE_NAME     U26 Y12
 '@T6G_MB_LIB.T6G(SCH_1):PAGE57_I49@PURE_QUANTA.GENOA_SP5(CHIPS)':
 'VDDCR_SOC_Y12': CDS_PINID='VDDCR_SOC_Y12';
NODE_NAME     U26 Y19
 '@T6G_MB_LIB.T6G(SCH_1):PAGE57_I49@PURE_QUANTA.GENOA_SP5(CHIPS)':
 'VDDCR_SOC_Y19': CDS_PINID='VDDCR_SOC_Y19';
NODE_NAME     C3900 1
 '@T6G_MB_LIB.T6G(SCH_1):PAGE71_I5@PURE_QUANTA.Q_CAP(CHIPS)':
 'A': CDS_PINID='A';
NODE_NAME     C2259 1
 '@T6G_MB_LIB.T6G(SCH_1):PAGE71_I7@PURE_QUANTA.Q_CAP(CHIPS)':
 'A': CDS_PINID='A';
NODE_NAME     C2258 1
 '@T6G_MB_LIB.T6G(SCH_1):PAGE71_I9@PURE_QUANTA.Q_CAP(CHIPS)':
 'A': CDS_PINID='A';
NODE_NAME     C3901 1
 '@T6G_MB_LIB.T6G(SCH_1):PAGE71_I23@PURE_QUANTA.Q_CAP(CHIPS)':
 'A': CDS_PINID='A';
NODE_NAME     C2264 1
 '@T6G_MB_LIB.T6G(SCH_1):PAGE71_I30@PURE_QUANTA.Q_CAP(CHIPS)':
 'A': CDS_PINID='A';
NODE_NAME     C2263 1
 '@T6G_MB_LIB.T6G(SCH_1):PAGE71_I31@PURE_QUANTA.Q_CAP(CHIPS)':
 'A': CDS_PINID='A';
NODE_NAME     C2269 1
 '@T6G_MB_LIB.T6G(SCH_1):PAGE71_I32@PURE_QUANTA.Q_CAP(CHIPS)':
 'A': CDS_PINID='A';
NODE_NAME     C2268 1
 '@T6G_MB_LIB.T6G(SCH_1):PAGE71_I33@PURE_QUANTA.Q_CAP(CHIPS)':
 'A': CDS_PINID='A';
NODE_NAME     C2272 1
 '@T6G_MB_LIB.T6G(SCH_1):PAGE71_I34@PURE_QUANTA.Q_CAP(CHIPS)':
 'A': CDS_PINID='A';
NODE_NAME     C2273 1
 '@T6G_MB_LIB.T6G(SCH_1):PAGE71_I35@PURE_QUANTA.Q_CAP(CHIPS)':
 'A': CDS_PINID='A';
NODE_NAME     C2277 1
 '@T6G_MB_LIB.T6G(SCH_1):PAGE71_I36@PURE_QUANTA.Q_CAP(CHIPS)':
 'A': CDS_PINID='A';
NODE_NAME     C2281 1
 '@T6G_MB_LIB.T6G(SCH_1):PAGE71_I37@PURE_QUANTA.Q_CAP(CHIPS)':
 'A': CDS_PINID='A';
NODE_NAME     C2280 1
 '@T6G_MB_LIB.T6G(SCH_1):PAGE71_I38@PURE_QUANTA.Q_CAP(CHIPS)':
 'A': CDS_PINID='A';
NODE_NAME     C2284 1
 '@T6G_MB_LIB.T6G(SCH_1):PAGE71_I39@PURE_QUANTA.Q_CAP(CHIPS)':
 'A': CDS_PINID='A';
NODE_NAME     C2283 1
 '@T6G_MB_LIB.T6G(SCH_1):PAGE71_I40@PURE_QUANTA.Q_CAP(CHIPS)':
 'A': CDS_PINID='A';
NODE_NAME     C3906 1
 '@T6G_MB_LIB.T6G(SCH_1):PAGE71_I41@PURE_QUANTA.Q_CAP(CHIPS)':
 'A': CDS_PINID='A';
NODE_NAME     C2286 1
 '@T6G_MB_LIB.T6G(SCH_1):PAGE71_I42@PURE_QUANTA.Q_CAP(CHIPS)':
 'A': CDS_PINID='A';
NODE_NAME     C3907 1
 '@T6G_MB_LIB.T6G(SCH_1):PAGE71_I43@PURE_QUANTA.Q_CAP(CHIPS)':
 'A': CDS_PINID='A';
NODE_NAME     C2288 1
 '@T6G_MB_LIB.T6G(SCH_1):PAGE71_I44@PURE_QUANTA.Q_CAP(CHIPS)':
 'A': CDS_PINID='A';
NODE_NAME     C3908 1
 '@T6G_MB_LIB.T6G(SCH_1):PAGE71_I45@PURE_QUANTA.Q_CAP(CHIPS)':
 'A': CDS_PINID='A';
NODE_NAME     C2290 1
 '@T6G_MB_LIB.T6G(SCH_1):PAGE71_I47@PURE_QUANTA.Q_CAP(CHIPS)':
 'A': CDS_PINID='A';
NODE_NAME     C2276 1
 '@T6G_MB_LIB.T6G(SCH_1):PAGE71_I62@PURE_QUANTA.Q_CAP(CHIPS)':
 'A': CDS_PINID='A';
NODE_NAME     C3912 1
 '@T6G_MB_LIB.T6G(SCH_1):PAGE73_I1@PURE_QUANTA.Q_CAP(CHIPS)':
 'A': CDS_PINID='A';
NODE_NAME     C2413 1
 '@T6G_MB_LIB.T6G(SCH_1):PAGE73_I3@PURE_QUANTA.Q_CAP(CHIPS)':
 'A': CDS_PINID='A';
NODE_NAME     C3913 1
 '@T6G_MB_LIB.T6G(SCH_1):PAGE73_I4@PURE_QUANTA.Q_CAP(CHIPS)':
 'A': CDS_PINID='A';
NODE_NAME     C2420 1
 '@T6G_MB_LIB.T6G(SCH_1):PAGE73_I5@PURE_QUANTA.Q_CAP(CHIPS)':
 'A': CDS_PINID='A';
NODE_NAME     C3914 1
 '@T6G_MB_LIB.T6G(SCH_1):PAGE73_I6@PURE_QUANTA.Q_CAP(CHIPS)':
 'A': CDS_PINID='A';
NODE_NAME     C2427 1
 '@T6G_MB_LIB.T6G(SCH_1):PAGE73_I7@PURE_QUANTA.Q_CAP(CHIPS)':
 'A': CDS_PINID='A';
NODE_NAME     C3915 1
 '@T6G_MB_LIB.T6G(SCH_1):PAGE73_I8@PURE_QUANTA.Q_CAP(CHIPS)':
 'A': CDS_PINID='A';
NODE_NAME     C2434 1
 '@T6G_MB_LIB.T6G(SCH_1):PAGE73_I9@PURE_QUANTA.Q_CAP(CHIPS)':
 'A': CDS_PINID='A';
NODE_NAME     C2412 1
 '@T6G_MB_LIB.T6G(SCH_1):PAGE73_I11@PURE_QUANTA.Q_CAP(CHIPS)':
 'A': CDS_PINID='A';
NODE_NAME     C2419 1
 '@T6G_MB_LIB.T6G(SCH_1):PAGE73_I13@PURE_QUANTA.Q_CAP(CHIPS)':
 'A': CDS_PINID='A';
NODE_NAME     C2411 1
 '@T6G_MB_LIB.T6G(SCH_1):PAGE73_I14@PURE_QUANTA.Q_CAP(CHIPS)':
 'A': CDS_PINID='A';
NODE_NAME     C2410 1
 '@T6G_MB_LIB.T6G(SCH_1):PAGE73_I16@PURE_QUANTA.Q_CAP(CHIPS)':
 'A': CDS_PINID='A';
NODE_NAME     C2418 1
 '@T6G_MB_LIB.T6G(SCH_1):PAGE73_I17@PURE_QUANTA.Q_CAP(CHIPS)':
 'A': CDS_PINID='A';
NODE_NAME     C2417 1
 '@T6G_MB_LIB.T6G(SCH_1):PAGE73_I18@PURE_QUANTA.Q_CAP(CHIPS)':
 'A': CDS_PINID='A';
NODE_NAME     C2426 1
 '@T6G_MB_LIB.T6G(SCH_1):PAGE73_I19@PURE_QUANTA.Q_CAP(CHIPS)':
 'A': CDS_PINID='A';
NODE_NAME     C2433 1
 '@T6G_MB_LIB.T6G(SCH_1):PAGE73_I20@PURE_QUANTA.Q_CAP(CHIPS)':
 'A': CDS_PINID='A';
NODE_NAME     C2425 1
 '@T6G_MB_LIB.T6G(SCH_1):PAGE73_I21@PURE_QUANTA.Q_CAP(CHIPS)':
 'A': CDS_PINID='A';
NODE_NAME     C2424 1
 '@T6G_MB_LIB.T6G(SCH_1):PAGE73_I22@PURE_QUANTA.Q_CAP(CHIPS)':
 'A': CDS_PINID='A';
NODE_NAME     C2432 1
 '@T6G_MB_LIB.T6G(SCH_1):PAGE73_I23@PURE_QUANTA.Q_CAP(CHIPS)':
 'A': CDS_PINID='A';
NODE_NAME     C2431 1
 '@T6G_MB_LIB.T6G(SCH_1):PAGE73_I24@PURE_QUANTA.Q_CAP(CHIPS)':
 'A': CDS_PINID='A';
NODE_NAME     C3916 1
 '@T6G_MB_LIB.T6G(SCH_1):PAGE73_I25@PURE_QUANTA.Q_CAP(CHIPS)':
 'A': CDS_PINID='A';
NODE_NAME     C2441 1
 '@T6G_MB_LIB.T6G(SCH_1):PAGE73_I26@PURE_QUANTA.Q_CAP(CHIPS)':
 'A': CDS_PINID='A';
NODE_NAME     C3917 1
 '@T6G_MB_LIB.T6G(SCH_1):PAGE73_I27@PURE_QUANTA.Q_CAP(CHIPS)':
 'A': CDS_PINID='A';
NODE_NAME     C2448 1
 '@T6G_MB_LIB.T6G(SCH_1):PAGE73_I28@PURE_QUANTA.Q_CAP(CHIPS)':
 'A': CDS_PINID='A';
NODE_NAME     C2455 1
 '@T6G_MB_LIB.T6G(SCH_1):PAGE73_I29@PURE_QUANTA.Q_CAP(CHIPS)':
 'A': CDS_PINID='A';
NODE_NAME     C3918 1
 '@T6G_MB_LIB.T6G(SCH_1):PAGE73_I30@PURE_QUANTA.Q_CAP(CHIPS)':
 'A': CDS_PINID='A';
NODE_NAME     C2462 1
 '@T6G_MB_LIB.T6G(SCH_1):PAGE73_I32@PURE_QUANTA.Q_CAP(CHIPS)':
 'A': CDS_PINID='A';
NODE_NAME     C2469 1
 '@T6G_MB_LIB.T6G(SCH_1):PAGE73_I33@PURE_QUANTA.Q_CAP(CHIPS)':
 'A': CDS_PINID='A';
NODE_NAME     C2440 1
 '@T6G_MB_LIB.T6G(SCH_1):PAGE73_I34@PURE_QUANTA.Q_CAP(CHIPS)':
 'A': CDS_PINID='A';
NODE_NAME     C2447 1
 '@T6G_MB_LIB.T6G(SCH_1):PAGE73_I35@PURE_QUANTA.Q_CAP(CHIPS)':
 'A': CDS_PINID='A';
NODE_NAME     C2439 1
 '@T6G_MB_LIB.T6G(SCH_1):PAGE73_I36@PURE_QUANTA.Q_CAP(CHIPS)':
 'A': CDS_PINID='A';
NODE_NAME     C2438 1
 '@T6G_MB_LIB.T6G(SCH_1):PAGE73_I37@PURE_QUANTA.Q_CAP(CHIPS)':
 'A': CDS_PINID='A';
NODE_NAME     C2446 1
 '@T6G_MB_LIB.T6G(SCH_1):PAGE73_I38@PURE_QUANTA.Q_CAP(CHIPS)':
 'A': CDS_PINID='A';
NODE_NAME     C2445 1
 '@T6G_MB_LIB.T6G(SCH_1):PAGE73_I39@PURE_QUANTA.Q_CAP(CHIPS)':
 'A': CDS_PINID='A';
NODE_NAME     C2452 1
 '@T6G_MB_LIB.T6G(SCH_1):PAGE73_I40@PURE_QUANTA.Q_CAP(CHIPS)':
 'A': CDS_PINID='A';
NODE_NAME     C2453 1
 '@T6G_MB_LIB.T6G(SCH_1):PAGE73_I41@PURE_QUANTA.Q_CAP(CHIPS)':
 'A': CDS_PINID='A';
NODE_NAME     C2454 1
 '@T6G_MB_LIB.T6G(SCH_1):PAGE73_I42@PURE_QUANTA.Q_CAP(CHIPS)':
 'A': CDS_PINID='A';
NODE_NAME     C2461 1
 '@T6G_MB_LIB.T6G(SCH_1):PAGE73_I43@PURE_QUANTA.Q_CAP(CHIPS)':
 'A': CDS_PINID='A';
NODE_NAME     C2468 1
 '@T6G_MB_LIB.T6G(SCH_1):PAGE73_I44@PURE_QUANTA.Q_CAP(CHIPS)':
 'A': CDS_PINID='A';
NODE_NAME     C2460 1
 '@T6G_MB_LIB.T6G(SCH_1):PAGE73_I45@PURE_QUANTA.Q_CAP(CHIPS)':
 'A': CDS_PINID='A';
NODE_NAME     C2459 1
 '@T6G_MB_LIB.T6G(SCH_1):PAGE73_I46@PURE_QUANTA.Q_CAP(CHIPS)':
 'A': CDS_PINID='A';
NODE_NAME     C2467 1
 '@T6G_MB_LIB.T6G(SCH_1):PAGE73_I47@PURE_QUANTA.Q_CAP(CHIPS)':
 'A': CDS_PINID='A';
NODE_NAME     C2466 1
 '@T6G_MB_LIB.T6G(SCH_1):PAGE73_I48@PURE_QUANTA.Q_CAP(CHIPS)':
 'A': CDS_PINID='A';
NODE_NAME     C2409 1
 '@T6G_MB_LIB.T6G(SCH_1):PAGE73_I50@PURE_QUANTA.Q_CAP(CHIPS)':
 'A': CDS_PINID='A';
NODE_NAME     C2416 1
 '@T6G_MB_LIB.T6G(SCH_1):PAGE73_I52@PURE_QUANTA.Q_CAP(CHIPS)':
 'A': CDS_PINID='A';
NODE_NAME     C2408 1
 '@T6G_MB_LIB.T6G(SCH_1):PAGE73_I53@PURE_QUANTA.Q_CAP(CHIPS)':
 'A': CDS_PINID='A';
NODE_NAME     C2407 1
 '@T6G_MB_LIB.T6G(SCH_1):PAGE73_I55@PURE_QUANTA.Q_CAP(CHIPS)':
 'A': CDS_PINID='A';
NODE_NAME     C2415 1
 '@T6G_MB_LIB.T6G(SCH_1):PAGE73_I56@PURE_QUANTA.Q_CAP(CHIPS)':
 'A': CDS_PINID='A';
NODE_NAME     C2414 1
 '@T6G_MB_LIB.T6G(SCH_1):PAGE73_I57@PURE_QUANTA.Q_CAP(CHIPS)':
 'A': CDS_PINID='A';
NODE_NAME     C2423 1
 '@T6G_MB_LIB.T6G(SCH_1):PAGE73_I58@PURE_QUANTA.Q_CAP(CHIPS)':
 'A': CDS_PINID='A';
NODE_NAME     C2430 1
 '@T6G_MB_LIB.T6G(SCH_1):PAGE73_I59@PURE_QUANTA.Q_CAP(CHIPS)':
 'A': CDS_PINID='A';
NODE_NAME     C2422 1
 '@T6G_MB_LIB.T6G(SCH_1):PAGE73_I60@PURE_QUANTA.Q_CAP(CHIPS)':
 'A': CDS_PINID='A';
NODE_NAME     C2421 1
 '@T6G_MB_LIB.T6G(SCH_1):PAGE73_I61@PURE_QUANTA.Q_CAP(CHIPS)':
 'A': CDS_PINID='A';
NODE_NAME     C2429 1
 '@T6G_MB_LIB.T6G(SCH_1):PAGE73_I62@PURE_QUANTA.Q_CAP(CHIPS)':
 'A': CDS_PINID='A';
NODE_NAME     C2437 1
 '@T6G_MB_LIB.T6G(SCH_1):PAGE73_I64@PURE_QUANTA.Q_CAP(CHIPS)':
 'A': CDS_PINID='A';
NODE_NAME     C2444 1
 '@T6G_MB_LIB.T6G(SCH_1):PAGE73_I65@PURE_QUANTA.Q_CAP(CHIPS)':
 'A': CDS_PINID='A';
NODE_NAME     C2436 1
 '@T6G_MB_LIB.T6G(SCH_1):PAGE73_I66@PURE_QUANTA.Q_CAP(CHIPS)':
 'A': CDS_PINID='A';
NODE_NAME     C2443 1
 '@T6G_MB_LIB.T6G(SCH_1):PAGE73_I67@PURE_QUANTA.Q_CAP(CHIPS)':
 'A': CDS_PINID='A';
NODE_NAME     C2449 1
 '@T6G_MB_LIB.T6G(SCH_1):PAGE73_I68@PURE_QUANTA.Q_CAP(CHIPS)':
 'A': CDS_PINID='A';
NODE_NAME     C2450 1
 '@T6G_MB_LIB.T6G(SCH_1):PAGE73_I69@PURE_QUANTA.Q_CAP(CHIPS)':
 'A': CDS_PINID='A';
NODE_NAME     C2451 1
 '@T6G_MB_LIB.T6G(SCH_1):PAGE73_I70@PURE_QUANTA.Q_CAP(CHIPS)':
 'A': CDS_PINID='A';
NODE_NAME     C2458 1
 '@T6G_MB_LIB.T6G(SCH_1):PAGE73_I71@PURE_QUANTA.Q_CAP(CHIPS)':
 'A': CDS_PINID='A';
NODE_NAME     C2465 1
 '@T6G_MB_LIB.T6G(SCH_1):PAGE73_I72@PURE_QUANTA.Q_CAP(CHIPS)':
 'A': CDS_PINID='A';
NODE_NAME     C2457 1
 '@T6G_MB_LIB.T6G(SCH_1):PAGE73_I73@PURE_QUANTA.Q_CAP(CHIPS)':
 'A': CDS_PINID='A';
NODE_NAME     C2456 1
 '@T6G_MB_LIB.T6G(SCH_1):PAGE73_I74@PURE_QUANTA.Q_CAP(CHIPS)':
 'A': CDS_PINID='A';
NODE_NAME     C2464 1
 '@T6G_MB_LIB.T6G(SCH_1):PAGE73_I75@PURE_QUANTA.Q_CAP(CHIPS)':
 'A': CDS_PINID='A';
NODE_NAME     C2463 1
 '@T6G_MB_LIB.T6G(SCH_1):PAGE73_I76@PURE_QUANTA.Q_CAP(CHIPS)':
 'A': CDS_PINID='A';
NODE_NAME     C2476 1
 '@T6G_MB_LIB.T6G(SCH_1):PAGE73_I79@PURE_QUANTA.Q_CAP(CHIPS)':
 'A': CDS_PINID='A';
NODE_NAME     C2475 1
 '@T6G_MB_LIB.T6G(SCH_1):PAGE73_I88@PURE_QUANTA.Q_CAP(CHIPS)':
 'A': CDS_PINID='A';
NODE_NAME     C2474 1
 '@T6G_MB_LIB.T6G(SCH_1):PAGE73_I94@PURE_QUANTA.Q_CAP(CHIPS)':
 'A': CDS_PINID='A';
NODE_NAME     C2473 1
 '@T6G_MB_LIB.T6G(SCH_1):PAGE73_I96@PURE_QUANTA.Q_CAP(CHIPS)':
 'A': CDS_PINID='A';
NODE_NAME     C2472 1
 '@T6G_MB_LIB.T6G(SCH_1):PAGE73_I127@PURE_QUANTA.Q_CAP(CHIPS)':
 'A': CDS_PINID='A';
NODE_NAME     C2471 1
 '@T6G_MB_LIB.T6G(SCH_1):PAGE73_I131@PURE_QUANTA.Q_CAP(CHIPS)':
 'A': CDS_PINID='A';
NODE_NAME     C2470 1
 '@T6G_MB_LIB.T6G(SCH_1):PAGE73_I133@PURE_QUANTA.Q_CAP(CHIPS)':
 'A': CDS_PINID='A';
NODE_NAME     C2442 1
 '@T6G_MB_LIB.T6G(SCH_1):PAGE73_I173@PURE_QUANTA.Q_CAP(CHIPS)':
 'A': CDS_PINID='A';
NODE_NAME     C2435 1
 '@T6G_MB_LIB.T6G(SCH_1):PAGE73_I174@PURE_QUANTA.Q_CAP(CHIPS)':
 'A': CDS_PINID='A';
NODE_NAME     C2428 1
 '@T6G_MB_LIB.T6G(SCH_1):PAGE73_I175@PURE_QUANTA.Q_CAP(CHIPS)':
 'A': CDS_PINID='A';
NODE_NAME     PL36 4
 '@T6G_MB_LIB.T6G(SCH_1):PAGE190_I52@PURE_QUANTA.Q_INDUCTOR4P_14(CHIPS)':
 '4': CDS_PINID='\4\';
NODE_NAME     PC340 1
 '@T6G_MB_LIB.T6G(SCH_1):PAGE190_I63@PURE_QUANTA.Q_CAPP(CHIPS)':
 'A': CDS_PINID='A';
NODE_NAME     PC343 1
 '@T6G_MB_LIB.T6G(SCH_1):PAGE190_I66@PURE_QUANTA.Q_CAPP(CHIPS)':
 'A': CDS_PINID='A';
NODE_NAME     PL35 4
 '@T6G_MB_LIB.T6G(SCH_1):PAGE190_I69@PURE_QUANTA.Q_INDUCTOR4P_14(CHIPS)':
 '4': CDS_PINID='\4\';
NODE_NAME     PC338 1
 '@T6G_MB_LIB.T6G(SCH_1):PAGE190_I79@PURE_QUANTA.Q_CAP(CHIPS)':
 'A': CDS_PINID='A';
NODE_NAME     PC344_1 1
 '@T6G_MB_LIB.T6G(SCH_1):PAGE190_I81@PURE_QUANTA.Q_CAP(CHIPS)':
 'A': CDS_PINID='A';
NODE_NAME     PR339 1
 '@T6G_MB_LIB.T6G(SCH_1):PAGE190_I83@PURE_QUANTA.Q_RES(CHIPS)':
 'A': CDS_PINID='A';
NODE_NAME     PL38 4
 '@T6G_MB_LIB.T6G(SCH_1):PAGE191_I26@PURE_QUANTA.Q_INDUCTOR4P_14(CHIPS)':
 '4': CDS_PINID='\4\';
NODE_NAME     PR163 1
 '@T6G_MB_LIB.T6G(SCH_1):PAGE185_I39@PURE_QUANTA.Q_RES(CHIPS)':
 'A': CDS_PINID='A';
NODE_NAME     PR216 2
 '@T6G_MB_LIB.T6G(SCH_1):PAGE191_I23@PURE_QUANTA.Q_RES(CHIPS)':
 'B': CDS_PINID='B';
NODE_NAME     PC354_3 1
 '@T6G_MB_LIB.T6G(SCH_1):PAGE191_I28@PURE_QUANTA.Q_CAP(CHIPS)':
 'A': CDS_PINID='A';
NODE_NAME     PC355_3 1
 '@T6G_MB_LIB.T6G(SCH_1):PAGE191_I30@PURE_QUANTA.Q_CAP(CHIPS)':
 'A': CDS_PINID='A';
NODE_NAME     PR211 2
 '@T6G_MB_LIB.T6G(SCH_1):PAGE190_I30@PURE_QUANTA.Q_RES(CHIPS)':
 'B': CDS_PINID='B';
NODE_NAME     PC337 1
 '@T6G_MB_LIB.T6G(SCH_1):PAGE190_I59@PURE_QUANTA.Q_CAPP(CHIPS)':
 'A': CDS_PINID='A';
NODE_NAME     PC339_2 1
 '@T6G_MB_LIB.T6G(SCH_1):PAGE190_I60@PURE_QUANTA.Q_CAP(CHIPS)':
 'A': CDS_PINID='A';
NODE_NAME     PC342_2 1
 '@T6G_MB_LIB.T6G(SCH_1):PAGE190_I62@PURE_QUANTA.Q_CAP(CHIPS)':
 'A': CDS_PINID='A';
NODE_NAME     PC341_1 1
 '@T6G_MB_LIB.T6G(SCH_1):PAGE190_I80@PURE_QUANTA.Q_CAP(CHIPS)':
 'A': CDS_PINID='A';
NODE_NAME     PR212 2
 '@T6G_MB_LIB.T6G(SCH_1):PAGE190_I85@PURE_QUANTA.Q_RES(CHIPS)':
 'B': CDS_PINID='B';
NET_NAME
'PVDDCR_SOC_P1_EN'
 '@T6G_MB_LIB.T6G(SCH_1):PVDDCR_SOC_P1_EN':
 C_SIGNAL='@t6g_mb_lib.t6g(sch_1):pvddcr_soc_p1_en';
NODE_NAME     R149 1
 '@T6G_MB_LIB.T6G(SCH_1):PAGE185_I2@PURE_QUANTA.Q_RES(CHIPS)':
 'A': CDS_PINID='A';
NODE_NAME     U18 C15
 '@T6G_MB_LIB.T6G(SCH_1):PAGE79_I94@PURE_QUANTA.LCMXO3LF9400C5BG484C(CHIPS)':
 'PT38C': CDS_PINID='PT38C';
NET_NAME
'PVDDCR_SOC_P1_EN//ADDR_CFG'
 '@T6G_MB_LIB.T6G(SCH_1):PVDDCR_SOC_P1_EN//ADDR_CFG':
 C_SIGNAL='@t6g_mb_lib.t6g(sch_1):\pvddcr_soc_p1_en//addr_cfg\';
NODE_NAME     PQ11 D
 '@T6G_MB_LIB.T6G(SCH_1):PAGE185_I18@PURE_QUANTA.MOSFET_PCH_GDS_ESD_PROTECTED(CHIPS)':
 'D': CDS_PINID='D';
NODE_NAME     PU25 42
 '@T6G_MB_LIB.T6G(SCH_1):PAGE185_I133@PURE_QUANTA.RAA229620GNPHA0(CHIPS)':
 'EN1||ADDR_CFG': CDS_PINID='\en1||addr_cfg\';
NODE_NAME     PR159 1
 '@T6G_MB_LIB.T6G(SCH_1):PAGE185_I142@PURE_QUANTA.Q_RES(CHIPS)':
 'A': CDS_PINID='A';
NET_NAME
'PVDDCR_SOC_P1_EN_GD'
 '@T6G_MB_LIB.T6G(SCH_1):PVDDCR_SOC_P1_EN_GD':
 C_SIGNAL='@t6g_mb_lib.t6g(sch_1):pvddcr_soc_p1_en_gd';
NODE_NAME     PQ15 D
 '@T6G_MB_LIB.T6G(SCH_1):PAGE185_I16@PURE_QUANTA.MOSFET_N(CHIPS)':
 'DRAIN': CDS_PINID='DRAIN';
NODE_NAME     PR152 2
 '@T6G_MB_LIB.T6G(SCH_1):PAGE185_I17@PURE_QUANTA.Q_RES(CHIPS)':
 'B': CDS_PINID='B';
NODE_NAME     PQ11 G
 '@T6G_MB_LIB.T6G(SCH_1):PAGE185_I18@PURE_QUANTA.MOSFET_PCH_GDS_ESD_PROTECTED(CHIPS)':
 'G': CDS_PINID='G';
NET_NAME
'PVDDCR_SOC_P1_EN_RC'
 '@T6G_MB_LIB.T6G(SCH_1):PVDDCR_SOC_P1_EN_RC':
 C_SIGNAL='@t6g_mb_lib.t6g(sch_1):pvddcr_soc_p1_en_rc';
NODE_NAME     C242 1
 '@T6G_MB_LIB.T6G(SCH_1):PAGE185_I13@PURE_QUANTA.Q_CAP(CHIPS)':
 'A': CDS_PINID='A';
NODE_NAME     R149 2
 '@T6G_MB_LIB.T6G(SCH_1):PAGE185_I2@PURE_QUANTA.Q_RES(CHIPS)':
 'B': CDS_PINID='B';
NODE_NAME     PQ15 G
 '@T6G_MB_LIB.T6G(SCH_1):PAGE185_I16@PURE_QUANTA.MOSFET_N(CHIPS)':
 'GATE': CDS_PINID='GATE';
NODE_NAME     R6087 1
 '@T6G_MB_LIB.T6G(SCH_1):PAGE185_I135@PURE_QUANTA.Q_RES(CHIPS)':
 'A': CDS_PINID='A';
NET_NAME
'PVDDCR_SOC_P1_IMON1'
 '@T6G_MB_LIB.T6G(SCH_1):PVDDCR_SOC_P1_IMON1':
 C_SIGNAL='@t6g_mb_lib.t6g(sch_1):pvddcr_soc_p1_imon1';
NODE_NAME     PU25 38
 '@T6G_MB_LIB.T6G(SCH_1):PAGE185_I133@PURE_QUANTA.RAA229620GNPHA0(CHIPS)':
 'CS0': CDS_PINID='CS0';
NODE_NAME     PU30 38
 '@T6G_MB_LIB.T6G(SCH_1):PAGE190_I17@PURE_QUANTA.ISL99390FRZTR5935(CHIPS)':
 'IOUT': CDS_PINID='IOUT';
NET_NAME
'PVDDCR_SOC_P1_IMON2'
 '@T6G_MB_LIB.T6G(SCH_1):PVDDCR_SOC_P1_IMON2':
 C_SIGNAL='@t6g_mb_lib.t6g(sch_1):pvddcr_soc_p1_imon2';
NODE_NAME     PU25 37
 '@T6G_MB_LIB.T6G(SCH_1):PAGE185_I133@PURE_QUANTA.RAA229620GNPHA0(CHIPS)':
 'CS1': CDS_PINID='CS1';
NODE_NAME     PU31 38
 '@T6G_MB_LIB.T6G(SCH_1):PAGE190_I86@PURE_QUANTA.ISL99390FRZTR5935(CHIPS)':
 'IOUT': CDS_PINID='IOUT';
NET_NAME
'PVDDCR_SOC_P1_IMON3'
 '@T6G_MB_LIB.T6G(SCH_1):PVDDCR_SOC_P1_IMON3':
 C_SIGNAL='@t6g_mb_lib.t6g(sch_1):pvddcr_soc_p1_imon3';
NODE_NAME     PU32 38
 '@T6G_MB_LIB.T6G(SCH_1):PAGE191_I38@PURE_QUANTA.ISL99390FRZTR5935(CHIPS)':
 'IOUT': CDS_PINID='IOUT';
NODE_NAME     PU25 36
 '@T6G_MB_LIB.T6G(SCH_1):PAGE185_I133@PURE_QUANTA.RAA229620GNPHA0(CHIPS)':
 'CS2': CDS_PINID='CS2';
NET_NAME
'PVDDCR_SOC_P1_LSET1'
 '@T6G_MB_LIB.T6G(SCH_1):PVDDCR_SOC_P1_LSET1':
 C_SIGNAL='@t6g_mb_lib.t6g(sch_1):pvddcr_soc_p1_lset1';
NODE_NAME     PU30 37
 '@T6G_MB_LIB.T6G(SCH_1):PAGE190_I17@PURE_QUANTA.ISL99390FRZTR5935(CHIPS)':
 'LSET': CDS_PINID='LSET';
NODE_NAME     PR207 2
 '@T6G_MB_LIB.T6G(SCH_1):PAGE190_I35@PURE_QUANTA.Q_RES(CHIPS)':
 'B': CDS_PINID='B';
NET_NAME
'PVDDCR_SOC_P1_LSET2'
 '@T6G_MB_LIB.T6G(SCH_1):PVDDCR_SOC_P1_LSET2':
 C_SIGNAL='@t6g_mb_lib.t6g(sch_1):pvddcr_soc_p1_lset2';
NODE_NAME     PR208 2
 '@T6G_MB_LIB.T6G(SCH_1):PAGE190_I8@PURE_QUANTA.Q_RES(CHIPS)':
 'B': CDS_PINID='B';
NODE_NAME     PU31 37
 '@T6G_MB_LIB.T6G(SCH_1):PAGE190_I86@PURE_QUANTA.ISL99390FRZTR5935(CHIPS)':
 'LSET': CDS_PINID='LSET';
NET_NAME
'PVDDCR_SOC_P1_LSET3'
 '@T6G_MB_LIB.T6G(SCH_1):PVDDCR_SOC_P1_LSET3':
 C_SIGNAL='@t6g_mb_lib.t6g(sch_1):pvddcr_soc_p1_lset3';
NODE_NAME     PR214 2
 '@T6G_MB_LIB.T6G(SCH_1):PAGE191_I7@PURE_QUANTA.Q_RES(CHIPS)':
 'B': CDS_PINID='B';
NODE_NAME     PU32 37
 '@T6G_MB_LIB.T6G(SCH_1):PAGE191_I38@PURE_QUANTA.ISL99390FRZTR5935(CHIPS)':
 'LSET': CDS_PINID='LSET';
NET_NAME
'PVDDCR_SOC_P1_PWM1'
 '@T6G_MB_LIB.T6G(SCH_1):PVDDCR_SOC_P1_PWM1':
 C_SIGNAL='@t6g_mb_lib.t6g(sch_1):pvddcr_soc_p1_pwm1';
NODE_NAME     PU25 1
 '@T6G_MB_LIB.T6G(SCH_1):PAGE185_I133@PURE_QUANTA.RAA229620GNPHA0(CHIPS)':
 'PWM0': CDS_PINID='PWM0';
NODE_NAME     PU30 34
 '@T6G_MB_LIB.T6G(SCH_1):PAGE190_I17@PURE_QUANTA.ISL99390FRZTR5935(CHIPS)':
 'PWM': CDS_PINID='PWM';
NET_NAME
'PVDDCR_SOC_P1_PWM2'
 '@T6G_MB_LIB.T6G(SCH_1):PVDDCR_SOC_P1_PWM2':
 C_SIGNAL='@t6g_mb_lib.t6g(sch_1):pvddcr_soc_p1_pwm2';
NODE_NAME     PU25 2
 '@T6G_MB_LIB.T6G(SCH_1):PAGE185_I133@PURE_QUANTA.RAA229620GNPHA0(CHIPS)':
 'PWM1': CDS_PINID='PWM1';
NODE_NAME     PU31 34
 '@T6G_MB_LIB.T6G(SCH_1):PAGE190_I86@PURE_QUANTA.ISL99390FRZTR5935(CHIPS)':
 'PWM': CDS_PINID='PWM';
NET_NAME
'PVDDCR_SOC_P1_PWM3'
 '@T6G_MB_LIB.T6G(SCH_1):PVDDCR_SOC_P1_PWM3':
 C_SIGNAL='@t6g_mb_lib.t6g(sch_1):pvddcr_soc_p1_pwm3';
NODE_NAME     PU32 34
 '@T6G_MB_LIB.T6G(SCH_1):PAGE191_I38@PURE_QUANTA.ISL99390FRZTR5935(CHIPS)':
 'PWM': CDS_PINID='PWM';
NODE_NAME     PU25 3
 '@T6G_MB_LIB.T6G(SCH_1):PAGE185_I133@PURE_QUANTA.RAA229620GNPHA0(CHIPS)':
 'PWM2': CDS_PINID='PWM2';
NET_NAME
'PVDDCR_SOC_P1_TEMP1'
 '@T6G_MB_LIB.T6G(SCH_1):PVDDCR_SOC_P1_TEMP1':
 C_SIGNAL='@t6g_mb_lib.t6g(sch_1):pvddcr_soc_p1_temp1';
NODE_NAME     PU32 36
 '@T6G_MB_LIB.T6G(SCH_1):PAGE191_I38@PURE_QUANTA.ISL99390FRZTR5935(CHIPS)':
 'TOUT_FLT': CDS_PINID='TOUT_FLT';
NODE_NAME     PC253 1
 '@T6G_MB_LIB.T6G(SCH_1):PAGE185_I94@PURE_QUANTA.Q_CAP(CHIPS)':
 'A': CDS_PINID='A';
NODE_NAME     PU25 43
 '@T6G_MB_LIB.T6G(SCH_1):PAGE185_I133@PURE_QUANTA.RAA229620GNPHA0(CHIPS)':
 'TEMP1': CDS_PINID='TEMP1';
NODE_NAME     PU30 36
 '@T6G_MB_LIB.T6G(SCH_1):PAGE190_I17@PURE_QUANTA.ISL99390FRZTR5935(CHIPS)':
 'TOUT_FLT': CDS_PINID='TOUT_FLT';
NODE_NAME     PU31 36
 '@T6G_MB_LIB.T6G(SCH_1):PAGE190_I86@PURE_QUANTA.ISL99390FRZTR5935(CHIPS)':
 'TOUT_FLT': CDS_PINID='TOUT_FLT';
NET_NAME
'PVDDCR_SOC_P1_VCC1'
 '@T6G_MB_LIB.T6G(SCH_1):PVDDCR_SOC_P1_VCC1':
 C_SIGNAL='@t6g_mb_lib.t6g(sch_1):pvddcr_soc_p1_vcc1';
NODE_NAME     PR205 2
 '@T6G_MB_LIB.T6G(SCH_1):PAGE190_I39@PURE_QUANTA.Q_RES(CHIPS)':
 'B': CDS_PINID='B';
NODE_NAME     PU30 35
 '@T6G_MB_LIB.T6G(SCH_1):PAGE190_I17@PURE_QUANTA.ISL99390FRZTR5935(CHIPS)':
 'EN': CDS_PINID='EN';
NODE_NAME     PU30 3
 '@T6G_MB_LIB.T6G(SCH_1):PAGE190_I17@PURE_QUANTA.ISL99390FRZTR5935(CHIPS)':
 'VCC': CDS_PINID='VCC';
NODE_NAME     PC319 1
 '@T6G_MB_LIB.T6G(SCH_1):PAGE190_I36@PURE_QUANTA.Q_CAP(CHIPS)':
 'A': CDS_PINID='A';
NET_NAME
'PVDDCR_SOC_P1_VCC2'
 '@T6G_MB_LIB.T6G(SCH_1):PVDDCR_SOC_P1_VCC2':
 C_SIGNAL='@t6g_mb_lib.t6g(sch_1):pvddcr_soc_p1_vcc2';
NODE_NAME     PC320 1
 '@T6G_MB_LIB.T6G(SCH_1):PAGE190_I11@PURE_QUANTA.Q_CAP(CHIPS)':
 'A': CDS_PINID='A';
NODE_NAME     PR206 2
 '@T6G_MB_LIB.T6G(SCH_1):PAGE190_I12@PURE_QUANTA.Q_RES(CHIPS)':
 'B': CDS_PINID='B';
NODE_NAME     PU31 35
 '@T6G_MB_LIB.T6G(SCH_1):PAGE190_I86@PURE_QUANTA.ISL99390FRZTR5935(CHIPS)':
 'EN': CDS_PINID='EN';
NODE_NAME     PU31 3
 '@T6G_MB_LIB.T6G(SCH_1):PAGE190_I86@PURE_QUANTA.ISL99390FRZTR5935(CHIPS)':
 'VCC': CDS_PINID='VCC';
NET_NAME
'PVDDCR_SOC_P1_VCC3'
 '@T6G_MB_LIB.T6G(SCH_1):PVDDCR_SOC_P1_VCC3':
 C_SIGNAL='@t6g_mb_lib.t6g(sch_1):pvddcr_soc_p1_vcc3';
NODE_NAME     PU32 35
 '@T6G_MB_LIB.T6G(SCH_1):PAGE191_I38@PURE_QUANTA.ISL99390FRZTR5935(CHIPS)':
 'EN': CDS_PINID='EN';
NODE_NAME     PU32 3
 '@T6G_MB_LIB.T6G(SCH_1):PAGE191_I38@PURE_QUANTA.ISL99390FRZTR5935(CHIPS)':
 'VCC': CDS_PINID='VCC';
NODE_NAME     PC346 1
 '@T6G_MB_LIB.T6G(SCH_1):PAGE191_I13@PURE_QUANTA.Q_CAP(CHIPS)':
 'A': CDS_PINID='A';
NODE_NAME     PR213 2
 '@T6G_MB_LIB.T6G(SCH_1):PAGE191_I14@PURE_QUANTA.Q_RES(CHIPS)':
 'B': CDS_PINID='B';
NET_NAME
'PVDDCR_SOC_P1_VOS1'
 '@T6G_MB_LIB.T6G(SCH_1):PVDDCR_SOC_P1_VOS1':
 C_SIGNAL='@t6g_mb_lib.t6g(sch_1):pvddcr_soc_p1_vos1';
NODE_NAME     PU30 1
 '@T6G_MB_LIB.T6G(SCH_1):PAGE190_I17@PURE_QUANTA.ISL99390FRZTR5935(CHIPS)':
 'VOS': CDS_PINID='VOS';
NODE_NAME     PR211 1
 '@T6G_MB_LIB.T6G(SCH_1):PAGE190_I30@PURE_QUANTA.Q_RES(CHIPS)':
 'A': CDS_PINID='A';
NET_NAME
'PVDDCR_SOC_P1_VOS2'
 '@T6G_MB_LIB.T6G(SCH_1):PVDDCR_SOC_P1_VOS2':
 C_SIGNAL='@t6g_mb_lib.t6g(sch_1):pvddcr_soc_p1_vos2';
NODE_NAME     PR212 1
 '@T6G_MB_LIB.T6G(SCH_1):PAGE190_I85@PURE_QUANTA.Q_RES(CHIPS)':
 'A': CDS_PINID='A';
NODE_NAME     PU31 1
 '@T6G_MB_LIB.T6G(SCH_1):PAGE190_I86@PURE_QUANTA.ISL99390FRZTR5935(CHIPS)':
 'VOS': CDS_PINID='VOS';
NET_NAME
'PVDDCR_SOC_P1_VOS3'
 '@T6G_MB_LIB.T6G(SCH_1):PVDDCR_SOC_P1_VOS3':
 C_SIGNAL='@t6g_mb_lib.t6g(sch_1):pvddcr_soc_p1_vos3';
NODE_NAME     PU32 1
 '@T6G_MB_LIB.T6G(SCH_1):PAGE191_I38@PURE_QUANTA.ISL99390FRZTR5935(CHIPS)':
 'VOS': CDS_PINID='VOS';
NODE_NAME     PR216 1
 '@T6G_MB_LIB.T6G(SCH_1):PAGE191_I23@PURE_QUANTA.Q_RES(CHIPS)':
 'A': CDS_PINID='A';
NET_NAME
'PVDDIO_P0'
 '@T6G_MB_LIB.T6G(SCH_1):PVDDIO_P0':
 C_SIGNAL='@t6g_mb_lib.t6g(sch_1):pvddio_p0',
 CDS_GLOBAL_NET='TRUE';
NODE_NAME     U25 AA54
 '@T6G_MB_LIB.T6G(SCH_1):PAGE30_I28@PURE_QUANTA.GENOA_SP5(CHIPS)':
 'VDDIO_AA54': CDS_PINID='VDDIO_AA54';
NODE_NAME     U25 AC58
 '@T6G_MB_LIB.T6G(SCH_1):PAGE30_I28@PURE_QUANTA.GENOA_SP5(CHIPS)':
 'VDDIO_AC58': CDS_PINID='VDDIO_AC58';
NODE_NAME     U25 AC65
 '@T6G_MB_LIB.T6G(SCH_1):PAGE30_I28@PURE_QUANTA.GENOA_SP5(CHIPS)':
 'VDDIO_AC65': CDS_PINID='VDDIO_AC65';
NODE_NAME     U25 AC72
 '@T6G_MB_LIB.T6G(SCH_1):PAGE30_I28@PURE_QUANTA.GENOA_SP5(CHIPS)':
 'VDDIO_AC72': CDS_PINID='VDDIO_AC72';
NODE_NAME     U25 AD54
 '@T6G_MB_LIB.T6G(SCH_1):PAGE30_I28@PURE_QUANTA.GENOA_SP5(CHIPS)':
 'VDDIO_AD54': CDS_PINID='VDDIO_AD54';
NODE_NAME     U25 AF57
 '@T6G_MB_LIB.T6G(SCH_1):PAGE30_I28@PURE_QUANTA.GENOA_SP5(CHIPS)':
 'VDDIO_AF57': CDS_PINID='VDDIO_AF57';
NODE_NAME     U25 AF64
 '@T6G_MB_LIB.T6G(SCH_1):PAGE30_I28@PURE_QUANTA.GENOA_SP5(CHIPS)':
 'VDDIO_AF64': CDS_PINID='VDDIO_AF64';
NODE_NAME     U25 AF71
 '@T6G_MB_LIB.T6G(SCH_1):PAGE30_I28@PURE_QUANTA.GENOA_SP5(CHIPS)':
 'VDDIO_AF71': CDS_PINID='VDDIO_AF71';
NODE_NAME     U25 AH54
 '@T6G_MB_LIB.T6G(SCH_1):PAGE30_I28@PURE_QUANTA.GENOA_SP5(CHIPS)':
 'VDDIO_AH54': CDS_PINID='VDDIO_AH54';
NODE_NAME     U25 AJ58
 '@T6G_MB_LIB.T6G(SCH_1):PAGE30_I28@PURE_QUANTA.GENOA_SP5(CHIPS)':
 'VDDIO_AJ58': CDS_PINID='VDDIO_AJ58';
NODE_NAME     U25 AJ65
 '@T6G_MB_LIB.T6G(SCH_1):PAGE30_I28@PURE_QUANTA.GENOA_SP5(CHIPS)':
 'VDDIO_AJ65': CDS_PINID='VDDIO_AJ65';
NODE_NAME     U25 AJ72
 '@T6G_MB_LIB.T6G(SCH_1):PAGE30_I28@PURE_QUANTA.GENOA_SP5(CHIPS)':
 'VDDIO_AJ72': CDS_PINID='VDDIO_AJ72';
NODE_NAME     U25 AM54
 '@T6G_MB_LIB.T6G(SCH_1):PAGE30_I28@PURE_QUANTA.GENOA_SP5(CHIPS)':
 'VDDIO_AM54': CDS_PINID='VDDIO_AM54';
NODE_NAME     U25 AM57
 '@T6G_MB_LIB.T6G(SCH_1):PAGE30_I28@PURE_QUANTA.GENOA_SP5(CHIPS)':
 'VDDIO_AM57': CDS_PINID='VDDIO_AM57';
NODE_NAME     U25 AM64
 '@T6G_MB_LIB.T6G(SCH_1):PAGE30_I28@PURE_QUANTA.GENOA_SP5(CHIPS)':
 'VDDIO_AM64': CDS_PINID='VDDIO_AM64';
NODE_NAME     U25 AM71
 '@T6G_MB_LIB.T6G(SCH_1):PAGE30_I28@PURE_QUANTA.GENOA_SP5(CHIPS)':
 'VDDIO_AM71': CDS_PINID='VDDIO_AM71';
NODE_NAME     U25 AR58
 '@T6G_MB_LIB.T6G(SCH_1):PAGE30_I28@PURE_QUANTA.GENOA_SP5(CHIPS)':
 'VDDIO_AR58': CDS_PINID='VDDIO_AR58';
NODE_NAME     U25 AR65
 '@T6G_MB_LIB.T6G(SCH_1):PAGE30_I28@PURE_QUANTA.GENOA_SP5(CHIPS)':
 'VDDIO_AR65': CDS_PINID='VDDIO_AR65';
NODE_NAME     U25 AR72
 '@T6G_MB_LIB.T6G(SCH_1):PAGE30_I28@PURE_QUANTA.GENOA_SP5(CHIPS)':
 'VDDIO_AR72': CDS_PINID='VDDIO_AR72';
NODE_NAME     U25 AV57
 '@T6G_MB_LIB.T6G(SCH_1):PAGE30_I28@PURE_QUANTA.GENOA_SP5(CHIPS)':
 'VDDIO_AV57': CDS_PINID='VDDIO_AV57';
NODE_NAME     U25 AV64
 '@T6G_MB_LIB.T6G(SCH_1):PAGE30_I28@PURE_QUANTA.GENOA_SP5(CHIPS)':
 'VDDIO_AV64': CDS_PINID='VDDIO_AV64';
NODE_NAME     U25 AV71
 '@T6G_MB_LIB.T6G(SCH_1):PAGE30_I28@PURE_QUANTA.GENOA_SP5(CHIPS)':
 'VDDIO_AV71': CDS_PINID='VDDIO_AV71';
NODE_NAME     U25 BA58
 '@T6G_MB_LIB.T6G(SCH_1):PAGE30_I28@PURE_QUANTA.GENOA_SP5(CHIPS)':
 'VDDIO_BA58': CDS_PINID='VDDIO_BA58';
NODE_NAME     U25 BA65
 '@T6G_MB_LIB.T6G(SCH_1):PAGE30_I28@PURE_QUANTA.GENOA_SP5(CHIPS)':
 'VDDIO_BA65': CDS_PINID='VDDIO_BA65';
NODE_NAME     U25 BA72
 '@T6G_MB_LIB.T6G(SCH_1):PAGE30_I28@PURE_QUANTA.GENOA_SP5(CHIPS)':
 'VDDIO_BA72': CDS_PINID='VDDIO_BA72';
NODE_NAME     U25 BD50
 '@T6G_MB_LIB.T6G(SCH_1):PAGE30_I28@PURE_QUANTA.GENOA_SP5(CHIPS)':
 'VDDIO_BD50': CDS_PINID='VDDIO_BD50';
NODE_NAME     U25 BD52
 '@T6G_MB_LIB.T6G(SCH_1):PAGE30_I28@PURE_QUANTA.GENOA_SP5(CHIPS)':
 'VDDIO_BD52': CDS_PINID='VDDIO_BD52';
NODE_NAME     U25 BD54
 '@T6G_MB_LIB.T6G(SCH_1):PAGE30_I28@PURE_QUANTA.GENOA_SP5(CHIPS)':
 'VDDIO_BD54': CDS_PINID='VDDIO_BD54';
NODE_NAME     U25 BF51
 '@T6G_MB_LIB.T6G(SCH_1):PAGE30_I28@PURE_QUANTA.GENOA_SP5(CHIPS)':
 'VDDIO_BF51': CDS_PINID='VDDIO_BF51';
NODE_NAME     U25 BF53
 '@T6G_MB_LIB.T6G(SCH_1):PAGE30_I28@PURE_QUANTA.GENOA_SP5(CHIPS)':
 'VDDIO_BF53': CDS_PINID='VDDIO_BF53';
NODE_NAME     U25 BF57
 '@T6G_MB_LIB.T6G(SCH_1):PAGE30_I28@PURE_QUANTA.GENOA_SP5(CHIPS)':
 'VDDIO_BF57': CDS_PINID='VDDIO_BF57';
NODE_NAME     U25 BF64
 '@T6G_MB_LIB.T6G(SCH_1):PAGE30_I28@PURE_QUANTA.GENOA_SP5(CHIPS)':
 'VDDIO_BF64': CDS_PINID='VDDIO_BF64';
NODE_NAME     U25 BF71
 '@T6G_MB_LIB.T6G(SCH_1):PAGE30_I28@PURE_QUANTA.GENOA_SP5(CHIPS)':
 'VDDIO_BF71': CDS_PINID='VDDIO_BF71';
NODE_NAME     U25 BG50
 '@T6G_MB_LIB.T6G(SCH_1):PAGE30_I28@PURE_QUANTA.GENOA_SP5(CHIPS)':
 'VDDIO_BG50': CDS_PINID='VDDIO_BG50';
NODE_NAME     U25 BG52
 '@T6G_MB_LIB.T6G(SCH_1):PAGE30_I28@PURE_QUANTA.GENOA_SP5(CHIPS)':
 'VDDIO_BG52': CDS_PINID='VDDIO_BG52';
NODE_NAME     U25 BG54
 '@T6G_MB_LIB.T6G(SCH_1):PAGE30_I28@PURE_QUANTA.GENOA_SP5(CHIPS)':
 'VDDIO_BG54': CDS_PINID='VDDIO_BG54';
NODE_NAME     U25 BH51
 '@T6G_MB_LIB.T6G(SCH_1):PAGE30_I28@PURE_QUANTA.GENOA_SP5(CHIPS)':
 'VDDIO_BH51': CDS_PINID='VDDIO_BH51';
NODE_NAME     U25 BH53
 '@T6G_MB_LIB.T6G(SCH_1):PAGE30_I28@PURE_QUANTA.GENOA_SP5(CHIPS)':
 'VDDIO_BH53': CDS_PINID='VDDIO_BH53';
NODE_NAME     U25 BJ50
 '@T6G_MB_LIB.T6G(SCH_1):PAGE30_I28@PURE_QUANTA.GENOA_SP5(CHIPS)':
 'VDDIO_BJ50': CDS_PINID='VDDIO_BJ50';
NODE_NAME     U25 BJ52
 '@T6G_MB_LIB.T6G(SCH_1):PAGE30_I28@PURE_QUANTA.GENOA_SP5(CHIPS)':
 'VDDIO_BJ52': CDS_PINID='VDDIO_BJ52';
NODE_NAME     U25 BJ54
 '@T6G_MB_LIB.T6G(SCH_1):PAGE30_I28@PURE_QUANTA.GENOA_SP5(CHIPS)':
 'VDDIO_BJ54': CDS_PINID='VDDIO_BJ54';
NODE_NAME     U25 BJ58
 '@T6G_MB_LIB.T6G(SCH_1):PAGE30_I28@PURE_QUANTA.GENOA_SP5(CHIPS)':
 'VDDIO_BJ58': CDS_PINID='VDDIO_BJ58';
NODE_NAME     U25 BJ65
 '@T6G_MB_LIB.T6G(SCH_1):PAGE30_I28@PURE_QUANTA.GENOA_SP5(CHIPS)':
 'VDDIO_BJ65': CDS_PINID='VDDIO_BJ65';
NODE_NAME     U25 BJ72
 '@T6G_MB_LIB.T6G(SCH_1):PAGE30_I28@PURE_QUANTA.GENOA_SP5(CHIPS)':
 'VDDIO_BJ72': CDS_PINID='VDDIO_BJ72';
NODE_NAME     U25 BK51
 '@T6G_MB_LIB.T6G(SCH_1):PAGE30_I28@PURE_QUANTA.GENOA_SP5(CHIPS)':
 'VDDIO_BK51': CDS_PINID='VDDIO_BK51';
NODE_NAME     U25 BK53
 '@T6G_MB_LIB.T6G(SCH_1):PAGE30_I28@PURE_QUANTA.GENOA_SP5(CHIPS)':
 'VDDIO_BK53': CDS_PINID='VDDIO_BK53';
NODE_NAME     U25 BL50
 '@T6G_MB_LIB.T6G(SCH_1):PAGE30_I28@PURE_QUANTA.GENOA_SP5(CHIPS)':
 'VDDIO_BL50': CDS_PINID='VDDIO_BL50';
NODE_NAME     U25 BL52
 '@T6G_MB_LIB.T6G(SCH_1):PAGE30_I28@PURE_QUANTA.GENOA_SP5(CHIPS)':
 'VDDIO_BL52': CDS_PINID='VDDIO_BL52';
NODE_NAME     U25 BL54
 '@T6G_MB_LIB.T6G(SCH_1):PAGE30_I28@PURE_QUANTA.GENOA_SP5(CHIPS)':
 'VDDIO_BL54': CDS_PINID='VDDIO_BL54';
NODE_NAME     U25 BM51
 '@T6G_MB_LIB.T6G(SCH_1):PAGE30_I28@PURE_QUANTA.GENOA_SP5(CHIPS)':
 'VDDIO_BM51': CDS_PINID='VDDIO_BM51';
NODE_NAME     U25 BM53
 '@T6G_MB_LIB.T6G(SCH_1):PAGE30_I28@PURE_QUANTA.GENOA_SP5(CHIPS)':
 'VDDIO_BM53': CDS_PINID='VDDIO_BM53';
NODE_NAME     U25 BM57
 '@T6G_MB_LIB.T6G(SCH_1):PAGE30_I28@PURE_QUANTA.GENOA_SP5(CHIPS)':
 'VDDIO_BM57': CDS_PINID='VDDIO_BM57';
NODE_NAME     U25 BM64
 '@T6G_MB_LIB.T6G(SCH_1):PAGE30_I28@PURE_QUANTA.GENOA_SP5(CHIPS)':
 'VDDIO_BM64': CDS_PINID='VDDIO_BM64';
NODE_NAME     U25 BM71
 '@T6G_MB_LIB.T6G(SCH_1):PAGE30_I28@PURE_QUANTA.GENOA_SP5(CHIPS)':
 'VDDIO_BM71': CDS_PINID='VDDIO_BM71';
NODE_NAME     U25 BN54
 '@T6G_MB_LIB.T6G(SCH_1):PAGE30_I28@PURE_QUANTA.GENOA_SP5(CHIPS)':
 'VDDIO_BN54': CDS_PINID='VDDIO_BN54';
NODE_NAME     U25 BR58
 '@T6G_MB_LIB.T6G(SCH_1):PAGE30_I28@PURE_QUANTA.GENOA_SP5(CHIPS)':
 'VDDIO_BR58': CDS_PINID='VDDIO_BR58';
NODE_NAME     U25 BR65
 '@T6G_MB_LIB.T6G(SCH_1):PAGE30_I28@PURE_QUANTA.GENOA_SP5(CHIPS)':
 'VDDIO_BR65': CDS_PINID='VDDIO_BR65';
NODE_NAME     U25 BR72
 '@T6G_MB_LIB.T6G(SCH_1):PAGE30_I28@PURE_QUANTA.GENOA_SP5(CHIPS)':
 'VDDIO_BR72': CDS_PINID='VDDIO_BR72';
NODE_NAME     U25 BV54
 '@T6G_MB_LIB.T6G(SCH_1):PAGE30_I28@PURE_QUANTA.GENOA_SP5(CHIPS)':
 'VDDIO_BV54': CDS_PINID='VDDIO_BV54';
NODE_NAME     U25 BV57
 '@T6G_MB_LIB.T6G(SCH_1):PAGE30_I28@PURE_QUANTA.GENOA_SP5(CHIPS)':
 'VDDIO_BV57': CDS_PINID='VDDIO_BV57';
NODE_NAME     U25 BV64
 '@T6G_MB_LIB.T6G(SCH_1):PAGE30_I28@PURE_QUANTA.GENOA_SP5(CHIPS)':
 'VDDIO_BV64': CDS_PINID='VDDIO_BV64';
NODE_NAME     U25 BV71
 '@T6G_MB_LIB.T6G(SCH_1):PAGE30_I28@PURE_QUANTA.GENOA_SP5(CHIPS)':
 'VDDIO_BV71': CDS_PINID='VDDIO_BV71';
NODE_NAME     U25 CA58
 '@T6G_MB_LIB.T6G(SCH_1):PAGE30_I28@PURE_QUANTA.GENOA_SP5(CHIPS)':
 'VDDIO_CA58': CDS_PINID='VDDIO_CA58';
NODE_NAME     U25 CA65
 '@T6G_MB_LIB.T6G(SCH_1):PAGE30_I28@PURE_QUANTA.GENOA_SP5(CHIPS)':
 'VDDIO_CA65': CDS_PINID='VDDIO_CA65';
NODE_NAME     U25 CA72
 '@T6G_MB_LIB.T6G(SCH_1):PAGE30_I28@PURE_QUANTA.GENOA_SP5(CHIPS)':
 'VDDIO_CA72': CDS_PINID='VDDIO_CA72';
NODE_NAME     U25 CB54
 '@T6G_MB_LIB.T6G(SCH_1):PAGE30_I28@PURE_QUANTA.GENOA_SP5(CHIPS)':
 'VDDIO_CB54': CDS_PINID='VDDIO_CB54';
NODE_NAME     U25 CD57
 '@T6G_MB_LIB.T6G(SCH_1):PAGE30_I28@PURE_QUANTA.GENOA_SP5(CHIPS)':
 'VDDIO_CD57': CDS_PINID='VDDIO_CD57';
NODE_NAME     U25 CD64
 '@T6G_MB_LIB.T6G(SCH_1):PAGE30_I28@PURE_QUANTA.GENOA_SP5(CHIPS)':
 'VDDIO_CD64': CDS_PINID='VDDIO_CD64';
NODE_NAME     U25 CD71
 '@T6G_MB_LIB.T6G(SCH_1):PAGE30_I28@PURE_QUANTA.GENOA_SP5(CHIPS)':
 'VDDIO_CD71': CDS_PINID='VDDIO_CD71';
NODE_NAME     U25 CF54
 '@T6G_MB_LIB.T6G(SCH_1):PAGE30_I28@PURE_QUANTA.GENOA_SP5(CHIPS)':
 'VDDIO_CF54': CDS_PINID='VDDIO_CF54';
NODE_NAME     U25 CG58
 '@T6G_MB_LIB.T6G(SCH_1):PAGE30_I28@PURE_QUANTA.GENOA_SP5(CHIPS)':
 'VDDIO_CG58': CDS_PINID='VDDIO_CG58';
NODE_NAME     U25 CG65
 '@T6G_MB_LIB.T6G(SCH_1):PAGE30_I28@PURE_QUANTA.GENOA_SP5(CHIPS)':
 'VDDIO_CG65': CDS_PINID='VDDIO_CG65';
NODE_NAME     U25 CG72
 '@T6G_MB_LIB.T6G(SCH_1):PAGE30_I28@PURE_QUANTA.GENOA_SP5(CHIPS)':
 'VDDIO_CG72': CDS_PINID='VDDIO_CG72';
NODE_NAME     U25 CJ54
 '@T6G_MB_LIB.T6G(SCH_1):PAGE30_I28@PURE_QUANTA.GENOA_SP5(CHIPS)':
 'VDDIO_CJ54': CDS_PINID='VDDIO_CJ54';
NODE_NAME     U25 CK57
 '@T6G_MB_LIB.T6G(SCH_1):PAGE30_I28@PURE_QUANTA.GENOA_SP5(CHIPS)':
 'VDDIO_CK57': CDS_PINID='VDDIO_CK57';
NODE_NAME     U25 CK64
 '@T6G_MB_LIB.T6G(SCH_1):PAGE30_I28@PURE_QUANTA.GENOA_SP5(CHIPS)':
 'VDDIO_CK64': CDS_PINID='VDDIO_CK64';
NODE_NAME     U25 CK71
 '@T6G_MB_LIB.T6G(SCH_1):PAGE30_I28@PURE_QUANTA.GENOA_SP5(CHIPS)':
 'VDDIO_CK71': CDS_PINID='VDDIO_CK71';
NODE_NAME     U25 CM54
 '@T6G_MB_LIB.T6G(SCH_1):PAGE30_I28@PURE_QUANTA.GENOA_SP5(CHIPS)':
 'VDDIO_CM54': CDS_PINID='VDDIO_CM54';
NODE_NAME     U25 CN58
 '@T6G_MB_LIB.T6G(SCH_1):PAGE30_I28@PURE_QUANTA.GENOA_SP5(CHIPS)':
 'VDDIO_CN58': CDS_PINID='VDDIO_CN58';
NODE_NAME     U25 CN65
 '@T6G_MB_LIB.T6G(SCH_1):PAGE30_I28@PURE_QUANTA.GENOA_SP5(CHIPS)':
 'VDDIO_CN65': CDS_PINID='VDDIO_CN65';
NODE_NAME     U25 CN72
 '@T6G_MB_LIB.T6G(SCH_1):PAGE30_I28@PURE_QUANTA.GENOA_SP5(CHIPS)':
 'VDDIO_CN72': CDS_PINID='VDDIO_CN72';
NODE_NAME     U25 CT54
 '@T6G_MB_LIB.T6G(SCH_1):PAGE30_I28@PURE_QUANTA.GENOA_SP5(CHIPS)':
 'VDDIO_CT54': CDS_PINID='VDDIO_CT54';
NODE_NAME     U25 CT57
 '@T6G_MB_LIB.T6G(SCH_1):PAGE30_I28@PURE_QUANTA.GENOA_SP5(CHIPS)':
 'VDDIO_CT57': CDS_PINID='VDDIO_CT57';
NODE_NAME     U25 CT64
 '@T6G_MB_LIB.T6G(SCH_1):PAGE30_I28@PURE_QUANTA.GENOA_SP5(CHIPS)':
 'VDDIO_CT64': CDS_PINID='VDDIO_CT64';
NODE_NAME     U25 CT71
 '@T6G_MB_LIB.T6G(SCH_1):PAGE30_I28@PURE_QUANTA.GENOA_SP5(CHIPS)':
 'VDDIO_CT71': CDS_PINID='VDDIO_CT71';
NODE_NAME     U25 CW58
 '@T6G_MB_LIB.T6G(SCH_1):PAGE30_I28@PURE_QUANTA.GENOA_SP5(CHIPS)':
 'VDDIO_CW58': CDS_PINID='VDDIO_CW58';
NODE_NAME     U25 CW65
 '@T6G_MB_LIB.T6G(SCH_1):PAGE30_I28@PURE_QUANTA.GENOA_SP5(CHIPS)':
 'VDDIO_CW65': CDS_PINID='VDDIO_CW65';
NODE_NAME     U25 CW72
 '@T6G_MB_LIB.T6G(SCH_1):PAGE30_I28@PURE_QUANTA.GENOA_SP5(CHIPS)':
 'VDDIO_CW72': CDS_PINID='VDDIO_CW72';
NODE_NAME     U25 CY54
 '@T6G_MB_LIB.T6G(SCH_1):PAGE30_I28@PURE_QUANTA.GENOA_SP5(CHIPS)':
 'VDDIO_CY54': CDS_PINID='VDDIO_CY54';
NODE_NAME     U25 DB57
 '@T6G_MB_LIB.T6G(SCH_1):PAGE30_I28@PURE_QUANTA.GENOA_SP5(CHIPS)':
 'VDDIO_DB57': CDS_PINID='VDDIO_DB57';
NODE_NAME     U25 DB64
 '@T6G_MB_LIB.T6G(SCH_1):PAGE30_I28@PURE_QUANTA.GENOA_SP5(CHIPS)':
 'VDDIO_DB64': CDS_PINID='VDDIO_DB64';
NODE_NAME     U25 DB71
 '@T6G_MB_LIB.T6G(SCH_1):PAGE30_I28@PURE_QUANTA.GENOA_SP5(CHIPS)':
 'VDDIO_DB71': CDS_PINID='VDDIO_DB71';
NODE_NAME     U25 DE58
 '@T6G_MB_LIB.T6G(SCH_1):PAGE30_I28@PURE_QUANTA.GENOA_SP5(CHIPS)':
 'VDDIO_DE58': CDS_PINID='VDDIO_DE58';
NODE_NAME     U25 DE65
 '@T6G_MB_LIB.T6G(SCH_1):PAGE30_I28@PURE_QUANTA.GENOA_SP5(CHIPS)':
 'VDDIO_DE65': CDS_PINID='VDDIO_DE65';
NODE_NAME     U25 DE72
 '@T6G_MB_LIB.T6G(SCH_1):PAGE30_I28@PURE_QUANTA.GENOA_SP5(CHIPS)':
 'VDDIO_DE72': CDS_PINID='VDDIO_DE72';
NODE_NAME     U25 DG64
 '@T6G_MB_LIB.T6G(SCH_1):PAGE30_I28@PURE_QUANTA.GENOA_SP5(CHIPS)':
 'VDDIO_DG64': CDS_PINID='VDDIO_DG64';
NODE_NAME     U25 DG71
 '@T6G_MB_LIB.T6G(SCH_1):PAGE30_I28@PURE_QUANTA.GENOA_SP5(CHIPS)':
 'VDDIO_DG71': CDS_PINID='VDDIO_DG71';
NODE_NAME     U25 H57
 '@T6G_MB_LIB.T6G(SCH_1):PAGE30_I28@PURE_QUANTA.GENOA_SP5(CHIPS)':
 'VDDIO_H57': CDS_PINID='VDDIO_H57';
NODE_NAME     U25 H64
 '@T6G_MB_LIB.T6G(SCH_1):PAGE30_I28@PURE_QUANTA.GENOA_SP5(CHIPS)':
 'VDDIO_H64': CDS_PINID='VDDIO_H64';
NODE_NAME     U25 H71
 '@T6G_MB_LIB.T6G(SCH_1):PAGE30_I28@PURE_QUANTA.GENOA_SP5(CHIPS)':
 'VDDIO_H71': CDS_PINID='VDDIO_H71';
NODE_NAME     U25 K54
 '@T6G_MB_LIB.T6G(SCH_1):PAGE30_I28@PURE_QUANTA.GENOA_SP5(CHIPS)':
 'VDDIO_K54': CDS_PINID='VDDIO_K54';
NODE_NAME     U25 L58
 '@T6G_MB_LIB.T6G(SCH_1):PAGE30_I28@PURE_QUANTA.GENOA_SP5(CHIPS)':
 'VDDIO_L58': CDS_PINID='VDDIO_L58';
NODE_NAME     U25 L65
 '@T6G_MB_LIB.T6G(SCH_1):PAGE30_I28@PURE_QUANTA.GENOA_SP5(CHIPS)':
 'VDDIO_L65': CDS_PINID='VDDIO_L65';
NODE_NAME     U25 L72
 '@T6G_MB_LIB.T6G(SCH_1):PAGE30_I28@PURE_QUANTA.GENOA_SP5(CHIPS)':
 'VDDIO_L72': CDS_PINID='VDDIO_L72';
NODE_NAME     U25 P54
 '@T6G_MB_LIB.T6G(SCH_1):PAGE30_I28@PURE_QUANTA.GENOA_SP5(CHIPS)':
 'VDDIO_P54': CDS_PINID='VDDIO_P54';
NODE_NAME     U25 P57
 '@T6G_MB_LIB.T6G(SCH_1):PAGE30_I28@PURE_QUANTA.GENOA_SP5(CHIPS)':
 'VDDIO_P57': CDS_PINID='VDDIO_P57';
NODE_NAME     U25 P64
 '@T6G_MB_LIB.T6G(SCH_1):PAGE30_I28@PURE_QUANTA.GENOA_SP5(CHIPS)':
 'VDDIO_P64': CDS_PINID='VDDIO_P64';
NODE_NAME     U25 P71
 '@T6G_MB_LIB.T6G(SCH_1):PAGE30_I28@PURE_QUANTA.GENOA_SP5(CHIPS)':
 'VDDIO_P71': CDS_PINID='VDDIO_P71';
NODE_NAME     U25 U58
 '@T6G_MB_LIB.T6G(SCH_1):PAGE30_I28@PURE_QUANTA.GENOA_SP5(CHIPS)':
 'VDDIO_U58': CDS_PINID='VDDIO_U58';
NODE_NAME     U25 U65
 '@T6G_MB_LIB.T6G(SCH_1):PAGE30_I28@PURE_QUANTA.GENOA_SP5(CHIPS)':
 'VDDIO_U65': CDS_PINID='VDDIO_U65';
NODE_NAME     U25 U72
 '@T6G_MB_LIB.T6G(SCH_1):PAGE30_I28@PURE_QUANTA.GENOA_SP5(CHIPS)':
 'VDDIO_U72': CDS_PINID='VDDIO_U72';
NODE_NAME     U25 V54
 '@T6G_MB_LIB.T6G(SCH_1):PAGE30_I28@PURE_QUANTA.GENOA_SP5(CHIPS)':
 'VDDIO_V54': CDS_PINID='VDDIO_V54';
NODE_NAME     U25 Y57
 '@T6G_MB_LIB.T6G(SCH_1):PAGE30_I28@PURE_QUANTA.GENOA_SP5(CHIPS)':
 'VDDIO_Y57': CDS_PINID='VDDIO_Y57';
NODE_NAME     U25 Y64
 '@T6G_MB_LIB.T6G(SCH_1):PAGE30_I28@PURE_QUANTA.GENOA_SP5(CHIPS)':
 'VDDIO_Y64': CDS_PINID='VDDIO_Y64';
NODE_NAME     U25 Y71
 '@T6G_MB_LIB.T6G(SCH_1):PAGE30_I28@PURE_QUANTA.GENOA_SP5(CHIPS)':
 'VDDIO_Y71': CDS_PINID='VDDIO_Y71';
NODE_NAME     C2131 1
 '@T6G_MB_LIB.T6G(SCH_1):PAGE67_I135@PURE_QUANTA.Q_CAP(CHIPS)':
 'A': CDS_PINID='A';
NODE_NAME     C2136 1
 '@T6G_MB_LIB.T6G(SCH_1):PAGE67_I136@PURE_QUANTA.Q_CAP(CHIPS)':
 'A': CDS_PINID='A';
NODE_NAME     C2141 1
 '@T6G_MB_LIB.T6G(SCH_1):PAGE67_I137@PURE_QUANTA.Q_CAP(CHIPS)':
 'A': CDS_PINID='A';
NODE_NAME     C2145 1
 '@T6G_MB_LIB.T6G(SCH_1):PAGE67_I138@PURE_QUANTA.Q_CAP(CHIPS)':
 'A': CDS_PINID='A';
NODE_NAME     C2149 1
 '@T6G_MB_LIB.T6G(SCH_1):PAGE67_I139@PURE_QUANTA.Q_CAP(CHIPS)':
 'A': CDS_PINID='A';
NODE_NAME     C3898 1
 '@T6G_MB_LIB.T6G(SCH_1):PAGE67_I141@PURE_QUANTA.Q_CAP(CHIPS)':
 'A': CDS_PINID='A';
NODE_NAME     C3899 1
 '@T6G_MB_LIB.T6G(SCH_1):PAGE67_I143@PURE_QUANTA.Q_CAP(CHIPS)':
 'A': CDS_PINID='A';
NODE_NAME     C2599 1
 '@T6G_MB_LIB.T6G(SCH_1):PAGE69_I102@PURE_QUANTA.Q_CAP(CHIPS)':
 'A': CDS_PINID='A';
NODE_NAME     C2598 1
 '@T6G_MB_LIB.T6G(SCH_1):PAGE69_I104@PURE_QUANTA.Q_CAP(CHIPS)':
 'A': CDS_PINID='A';
NODE_NAME     C2597 1
 '@T6G_MB_LIB.T6G(SCH_1):PAGE69_I108@PURE_QUANTA.Q_CAP(CHIPS)':
 'A': CDS_PINID='A';
NODE_NAME     C2606 1
 '@T6G_MB_LIB.T6G(SCH_1):PAGE69_I153@PURE_QUANTA.Q_CAP(CHIPS)':
 'A': CDS_PINID='A';
NODE_NAME     C2605 1
 '@T6G_MB_LIB.T6G(SCH_1):PAGE69_I154@PURE_QUANTA.Q_CAP(CHIPS)':
 'A': CDS_PINID='A';
NODE_NAME     C2613 1
 '@T6G_MB_LIB.T6G(SCH_1):PAGE69_I155@PURE_QUANTA.Q_CAP(CHIPS)':
 'A': CDS_PINID='A';
NODE_NAME     C2612 1
 '@T6G_MB_LIB.T6G(SCH_1):PAGE69_I156@PURE_QUANTA.Q_CAP(CHIPS)':
 'A': CDS_PINID='A';
NODE_NAME     C2619 1
 '@T6G_MB_LIB.T6G(SCH_1):PAGE69_I157@PURE_QUANTA.Q_CAP(CHIPS)':
 'A': CDS_PINID='A';
NODE_NAME     C2604 1
 '@T6G_MB_LIB.T6G(SCH_1):PAGE69_I158@PURE_QUANTA.Q_CAP(CHIPS)':
 'A': CDS_PINID='A';
NODE_NAME     C2611 1
 '@T6G_MB_LIB.T6G(SCH_1):PAGE69_I159@PURE_QUANTA.Q_CAP(CHIPS)':
 'A': CDS_PINID='A';
NODE_NAME     C2618 1
 '@T6G_MB_LIB.T6G(SCH_1):PAGE69_I160@PURE_QUANTA.Q_CAP(CHIPS)':
 'A': CDS_PINID='A';
NODE_NAME     C2620 1
 '@T6G_MB_LIB.T6G(SCH_1):PAGE69_I161@PURE_QUANTA.Q_CAP(CHIPS)':
 'A': CDS_PINID='A';
NODE_NAME     C2626 1
 '@T6G_MB_LIB.T6G(SCH_1):PAGE69_I162@PURE_QUANTA.Q_CAP(CHIPS)':
 'A': CDS_PINID='A';
NODE_NAME     C2632 1
 '@T6G_MB_LIB.T6G(SCH_1):PAGE69_I163@PURE_QUANTA.Q_CAP(CHIPS)':
 'A': CDS_PINID='A';
NODE_NAME     C2625 1
 '@T6G_MB_LIB.T6G(SCH_1):PAGE69_I164@PURE_QUANTA.Q_CAP(CHIPS)':
 'A': CDS_PINID='A';
NODE_NAME     C2631 1
 '@T6G_MB_LIB.T6G(SCH_1):PAGE69_I165@PURE_QUANTA.Q_CAP(CHIPS)':
 'A': CDS_PINID='A';
NODE_NAME     C2638 1
 '@T6G_MB_LIB.T6G(SCH_1):PAGE69_I166@PURE_QUANTA.Q_CAP(CHIPS)':
 'A': CDS_PINID='A';
NODE_NAME     C2644 1
 '@T6G_MB_LIB.T6G(SCH_1):PAGE69_I167@PURE_QUANTA.Q_CAP(CHIPS)':
 'A': CDS_PINID='A';
NODE_NAME     C2637 1
 '@T6G_MB_LIB.T6G(SCH_1):PAGE69_I168@PURE_QUANTA.Q_CAP(CHIPS)':
 'A': CDS_PINID='A';
NODE_NAME     C2643 1
 '@T6G_MB_LIB.T6G(SCH_1):PAGE69_I169@PURE_QUANTA.Q_CAP(CHIPS)':
 'A': CDS_PINID='A';
NODE_NAME     C2650 1
 '@T6G_MB_LIB.T6G(SCH_1):PAGE69_I170@PURE_QUANTA.Q_CAP(CHIPS)':
 'A': CDS_PINID='A';
NODE_NAME     C2655 1
 '@T6G_MB_LIB.T6G(SCH_1):PAGE69_I172@PURE_QUANTA.Q_CAP(CHIPS)':
 'A': CDS_PINID='A';
NODE_NAME     C2649 1
 '@T6G_MB_LIB.T6G(SCH_1):PAGE69_I173@PURE_QUANTA.Q_CAP(CHIPS)':
 'A': CDS_PINID='A';
NODE_NAME     C2654 1
 '@T6G_MB_LIB.T6G(SCH_1):PAGE69_I175@PURE_QUANTA.Q_CAP(CHIPS)':
 'A': CDS_PINID='A';
NODE_NAME     PC191_4 1
 '@T6G_MB_LIB.T6G(SCH_1):PAGE181_I68@PURE_QUANTA.Q_CAP(CHIPS)':
 'A': CDS_PINID='A';
NODE_NAME     PC192_3 1
 '@T6G_MB_LIB.T6G(SCH_1):PAGE181_I71@PURE_QUANTA.Q_CAP(CHIPS)':
 'A': CDS_PINID='A';
NODE_NAME     PR52 2
 '@T6G_MB_LIB.T6G(SCH_1):PAGE175_I22@PURE_QUANTA.Q_RES(CHIPS)':
 'B': CDS_PINID='B';
NODE_NAME     PR104 2
 '@T6G_MB_LIB.T6G(SCH_1):PAGE180_I39@PURE_QUANTA.Q_RES(CHIPS)':
 'B': CDS_PINID='B';
NODE_NAME     PL18 4
 '@T6G_MB_LIB.T6G(SCH_1):PAGE180_I40@PURE_QUANTA.Q_INDUCTOR4P_14(CHIPS)':
 '4': CDS_PINID='\4\';
NODE_NAME     PR103 2
 '@T6G_MB_LIB.T6G(SCH_1):PAGE180_I49@PURE_QUANTA.Q_RES(CHIPS)':
 'B': CDS_PINID='B';
NODE_NAME     PC168_2 1
 '@T6G_MB_LIB.T6G(SCH_1):PAGE180_I51@PURE_QUANTA.Q_CAP(CHIPS)':
 'A': CDS_PINID='A';
NODE_NAME     PC170_2 1
 '@T6G_MB_LIB.T6G(SCH_1):PAGE180_I53@PURE_QUANTA.Q_CAP(CHIPS)':
 'A': CDS_PINID='A';
NODE_NAME     PC160 1
 '@T6G_MB_LIB.T6G(SCH_1):PAGE180_I54@PURE_QUANTA.Q_CAPP(CHIPS)':
 'A': CDS_PINID='A';
NODE_NAME     PC162 1
 '@T6G_MB_LIB.T6G(SCH_1):PAGE180_I57@PURE_QUANTA.Q_CAPP(CHIPS)':
 'A': CDS_PINID='A';
NODE_NAME     PC165 1
 '@T6G_MB_LIB.T6G(SCH_1):PAGE180_I58@PURE_QUANTA.Q_CAPP(CHIPS)':
 'A': CDS_PINID='A';
NODE_NAME     PL17 4
 '@T6G_MB_LIB.T6G(SCH_1):PAGE180_I64@PURE_QUANTA.Q_INDUCTOR4P_14(CHIPS)':
 '4': CDS_PINID='\4\';
NODE_NAME     PC107 1
 '@T6G_MB_LIB.T6G(SCH_1):PAGE180_I73@PURE_QUANTA.Q_CAP(CHIPS)':
 'A': CDS_PINID='A';
NODE_NAME     PC166_1 1
 '@T6G_MB_LIB.T6G(SCH_1):PAGE180_I74@PURE_QUANTA.Q_CAP(CHIPS)':
 'A': CDS_PINID='A';
NODE_NAME     PC169_1 1
 '@T6G_MB_LIB.T6G(SCH_1):PAGE180_I75@PURE_QUANTA.Q_CAP(CHIPS)':
 'A': CDS_PINID='A';
NODE_NAME     PR410 1
 '@T6G_MB_LIB.T6G(SCH_1):PAGE180_I78@PURE_QUANTA.Q_RES(CHIPS)':
 'A': CDS_PINID='A';
NODE_NAME     PR112 2
 '@T6G_MB_LIB.T6G(SCH_1):PAGE181_I41@PURE_QUANTA.Q_RES(CHIPS)':
 'B': CDS_PINID='B';
NODE_NAME     PL20 4
 '@T6G_MB_LIB.T6G(SCH_1):PAGE181_I42@PURE_QUANTA.Q_INDUCTOR4P_14(CHIPS)':
 '4': CDS_PINID='\4\';
NODE_NAME     PR111 2
 '@T6G_MB_LIB.T6G(SCH_1):PAGE181_I50@PURE_QUANTA.Q_RES(CHIPS)':
 'B': CDS_PINID='B';
NODE_NAME     PC189_4 1
 '@T6G_MB_LIB.T6G(SCH_1):PAGE181_I53@PURE_QUANTA.Q_CAP(CHIPS)':
 'A': CDS_PINID='A';
NODE_NAME     PL21 4
 '@T6G_MB_LIB.T6G(SCH_1):PAGE181_I61@PURE_QUANTA.Q_INDUCTOR4P_14(CHIPS)':
 '4': CDS_PINID='\4\';
NODE_NAME     PC190_3 1
 '@T6G_MB_LIB.T6G(SCH_1):PAGE181_I66@PURE_QUANTA.Q_CAP(CHIPS)':
 'A': CDS_PINID='A';
NET_NAME
'PVDDIO_P0_EN'
 '@T6G_MB_LIB.T6G(SCH_1):PVDDIO_P0_EN':
 C_SIGNAL='@t6g_mb_lib.t6g(sch_1):pvddio_p0_en';
NODE_NAME     R8047 1
 '@T6G_MB_LIB.T6G(SCH_1):PAGE175_I2@PURE_QUANTA.Q_RES(CHIPS)':
 'A': CDS_PINID='A';
NODE_NAME     R229 1
 '@T6G_MB_LIB.T6G(SCH_1):PAGE80_I68@PURE_QUANTA.Q_RES(CHIPS)':
 'A': CDS_PINID='A';
NET_NAME
'PVDDIO_P0_EN_G'
 '@T6G_MB_LIB.T6G(SCH_1):PVDDIO_P0_EN_G':
 C_SIGNAL='@t6g_mb_lib.t6g(sch_1):pvddio_p0_en_g';
NODE_NAME     PQ14 D
 '@T6G_MB_LIB.T6G(SCH_1):PAGE175_I6@PURE_QUANTA.MOSFET_N(CHIPS)':
 'DRAIN': CDS_PINID='DRAIN';
NODE_NAME     PQ10 G
 '@T6G_MB_LIB.T6G(SCH_1):PAGE175_I13@PURE_QUANTA.MOSFET_PCH_GDS_ESD_PROTECTED(CHIPS)':
 'G': CDS_PINID='G';
NODE_NAME     PR55 2
 '@T6G_MB_LIB.T6G(SCH_1):PAGE175_I17@PURE_QUANTA.Q_RES(CHIPS)':
 'B': CDS_PINID='B';
NET_NAME
'PVDDIO_P0_EN_R'
 '@T6G_MB_LIB.T6G(SCH_1):PVDDIO_P0_EN_R':
 C_SIGNAL='@t6g_mb_lib.t6g(sch_1):pvddio_p0_en_r';
NODE_NAME     R8047 2
 '@T6G_MB_LIB.T6G(SCH_1):PAGE175_I2@PURE_QUANTA.Q_RES(CHIPS)':
 'B': CDS_PINID='B';
NODE_NAME     C8066 1
 '@T6G_MB_LIB.T6G(SCH_1):PAGE175_I3@PURE_QUANTA.Q_CAP(CHIPS)':
 'A': CDS_PINID='A';
NODE_NAME     PQ14 G
 '@T6G_MB_LIB.T6G(SCH_1):PAGE175_I6@PURE_QUANTA.MOSFET_N(CHIPS)':
 'GATE': CDS_PINID='GATE';
NODE_NAME     R6086 1
 '@T6G_MB_LIB.T6G(SCH_1):PAGE175_I129@PURE_QUANTA.Q_RES(CHIPS)':
 'A': CDS_PINID='A';
NET_NAME
'PVDDIO_P0_IMON1'
 '@T6G_MB_LIB.T6G(SCH_1):PVDDIO_P0_IMON1':
 C_SIGNAL='@t6g_mb_lib.t6g(sch_1):pvddio_p0_imon1';
NODE_NAME     PU12 38
 '@T6G_MB_LIB.T6G(SCH_1):PAGE175_I128@PURE_QUANTA.RAA229620GNPHA0(CHIPS)':
 'CS0': CDS_PINID='CS0';
NODE_NAME     PU17 38
 '@T6G_MB_LIB.T6G(SCH_1):PAGE180_I84@PURE_QUANTA.ISL99390FRZTR5935(CHIPS)':
 'IOUT': CDS_PINID='IOUT';
NET_NAME
'PVDDIO_P0_IMON2'
 '@T6G_MB_LIB.T6G(SCH_1):PVDDIO_P0_IMON2':
 C_SIGNAL='@t6g_mb_lib.t6g(sch_1):pvddio_p0_imon2';
NODE_NAME     PU12 37
 '@T6G_MB_LIB.T6G(SCH_1):PAGE175_I128@PURE_QUANTA.RAA229620GNPHA0(CHIPS)':
 'CS1': CDS_PINID='CS1';
NODE_NAME     PU18 38
 '@T6G_MB_LIB.T6G(SCH_1):PAGE180_I15@PURE_QUANTA.ISL99390FRZTR5935(CHIPS)':
 'IOUT': CDS_PINID='IOUT';
NET_NAME
'PVDDIO_P0_IMON3'
 '@T6G_MB_LIB.T6G(SCH_1):PVDDIO_P0_IMON3':
 C_SIGNAL='@t6g_mb_lib.t6g(sch_1):pvddio_p0_imon3';
NODE_NAME     PU12 36
 '@T6G_MB_LIB.T6G(SCH_1):PAGE175_I128@PURE_QUANTA.RAA229620GNPHA0(CHIPS)':
 'CS2': CDS_PINID='CS2';
NODE_NAME     PU19 38
 '@T6G_MB_LIB.T6G(SCH_1):PAGE181_I32@PURE_QUANTA.ISL99390FRZTR5935(CHIPS)':
 'IOUT': CDS_PINID='IOUT';
NET_NAME
'PVDDIO_P0_IMON4'
 '@T6G_MB_LIB.T6G(SCH_1):PVDDIO_P0_IMON4':
 C_SIGNAL='@t6g_mb_lib.t6g(sch_1):pvddio_p0_imon4';
NODE_NAME     PU12 35
 '@T6G_MB_LIB.T6G(SCH_1):PAGE175_I128@PURE_QUANTA.RAA229620GNPHA0(CHIPS)':
 'CS3': CDS_PINID='CS3';
NODE_NAME     PU20 38
 '@T6G_MB_LIB.T6G(SCH_1):PAGE181_I73@PURE_QUANTA.ISL99390FRZTR5935(CHIPS)':
 'IOUT': CDS_PINID='IOUT';
NET_NAME
'PVDDIO_P0_LSET1'
 '@T6G_MB_LIB.T6G(SCH_1):PVDDIO_P0_LSET1':
 C_SIGNAL='@t6g_mb_lib.t6g(sch_1):pvddio_p0_lset1';
NODE_NAME     PR98 1
 '@T6G_MB_LIB.T6G(SCH_1):PAGE180_I22@PURE_QUANTA.Q_RES(CHIPS)':
 'A': CDS_PINID='A';
NODE_NAME     PU17 37
 '@T6G_MB_LIB.T6G(SCH_1):PAGE180_I84@PURE_QUANTA.ISL99390FRZTR5935(CHIPS)':
 'LSET': CDS_PINID='LSET';
NET_NAME
'PVDDIO_P0_LSET2'
 '@T6G_MB_LIB.T6G(SCH_1):PVDDIO_P0_LSET2':
 C_SIGNAL='@t6g_mb_lib.t6g(sch_1):pvddio_p0_lset2';
NODE_NAME     PR97 1
 '@T6G_MB_LIB.T6G(SCH_1):PAGE180_I4@PURE_QUANTA.Q_RES(CHIPS)':
 'A': CDS_PINID='A';
NODE_NAME     PU18 37
 '@T6G_MB_LIB.T6G(SCH_1):PAGE180_I15@PURE_QUANTA.ISL99390FRZTR5935(CHIPS)':
 'LSET': CDS_PINID='LSET';
NET_NAME
'PVDDIO_P0_LSET3'
 '@T6G_MB_LIB.T6G(SCH_1):PVDDIO_P0_LSET3':
 C_SIGNAL='@t6g_mb_lib.t6g(sch_1):pvddio_p0_lset3';
NODE_NAME     PR106 1
 '@T6G_MB_LIB.T6G(SCH_1):PAGE181_I21@PURE_QUANTA.Q_RES(CHIPS)':
 'A': CDS_PINID='A';
NODE_NAME     PU19 37
 '@T6G_MB_LIB.T6G(SCH_1):PAGE181_I32@PURE_QUANTA.ISL99390FRZTR5935(CHIPS)':
 'LSET': CDS_PINID='LSET';
NET_NAME
'PVDDIO_P0_LSET4'
 '@T6G_MB_LIB.T6G(SCH_1):PVDDIO_P0_LSET4':
 C_SIGNAL='@t6g_mb_lib.t6g(sch_1):pvddio_p0_lset4';
NODE_NAME     PR105 1
 '@T6G_MB_LIB.T6G(SCH_1):PAGE181_I4@PURE_QUANTA.Q_RES(CHIPS)':
 'A': CDS_PINID='A';
NODE_NAME     PU20 37
 '@T6G_MB_LIB.T6G(SCH_1):PAGE181_I73@PURE_QUANTA.ISL99390FRZTR5935(CHIPS)':
 'LSET': CDS_PINID='LSET';
NET_NAME
'PVDDIO_P0_PWM1'
 '@T6G_MB_LIB.T6G(SCH_1):PVDDIO_P0_PWM1':
 C_SIGNAL='@t6g_mb_lib.t6g(sch_1):pvddio_p0_pwm1';
NODE_NAME     PU12 1
 '@T6G_MB_LIB.T6G(SCH_1):PAGE175_I128@PURE_QUANTA.RAA229620GNPHA0(CHIPS)':
 'PWM0': CDS_PINID='PWM0';
NODE_NAME     PU17 34
 '@T6G_MB_LIB.T6G(SCH_1):PAGE180_I84@PURE_QUANTA.ISL99390FRZTR5935(CHIPS)':
 'PWM': CDS_PINID='PWM';
NET_NAME
'PVDDIO_P0_PWM2'
 '@T6G_MB_LIB.T6G(SCH_1):PVDDIO_P0_PWM2':
 C_SIGNAL='@t6g_mb_lib.t6g(sch_1):pvddio_p0_pwm2';
NODE_NAME     PU12 2
 '@T6G_MB_LIB.T6G(SCH_1):PAGE175_I128@PURE_QUANTA.RAA229620GNPHA0(CHIPS)':
 'PWM1': CDS_PINID='PWM1';
NODE_NAME     PU18 34
 '@T6G_MB_LIB.T6G(SCH_1):PAGE180_I15@PURE_QUANTA.ISL99390FRZTR5935(CHIPS)':
 'PWM': CDS_PINID='PWM';
NET_NAME
'PVDDIO_P0_PWM3'
 '@T6G_MB_LIB.T6G(SCH_1):PVDDIO_P0_PWM3':
 C_SIGNAL='@t6g_mb_lib.t6g(sch_1):pvddio_p0_pwm3';
NODE_NAME     PU12 3
 '@T6G_MB_LIB.T6G(SCH_1):PAGE175_I128@PURE_QUANTA.RAA229620GNPHA0(CHIPS)':
 'PWM2': CDS_PINID='PWM2';
NODE_NAME     PU19 34
 '@T6G_MB_LIB.T6G(SCH_1):PAGE181_I32@PURE_QUANTA.ISL99390FRZTR5935(CHIPS)':
 'PWM': CDS_PINID='PWM';
NET_NAME
'PVDDIO_P0_PWM4'
 '@T6G_MB_LIB.T6G(SCH_1):PVDDIO_P0_PWM4':
 C_SIGNAL='@t6g_mb_lib.t6g(sch_1):pvddio_p0_pwm4';
NODE_NAME     PU12 4
 '@T6G_MB_LIB.T6G(SCH_1):PAGE175_I128@PURE_QUANTA.RAA229620GNPHA0(CHIPS)':
 'PWM3': CDS_PINID='PWM3';
NODE_NAME     PU20 34
 '@T6G_MB_LIB.T6G(SCH_1):PAGE181_I73@PURE_QUANTA.ISL99390FRZTR5935(CHIPS)':
 'PWM': CDS_PINID='PWM';
NET_NAME
'PVDDIO_P0_TEMP1'
 '@T6G_MB_LIB.T6G(SCH_1):PVDDIO_P0_TEMP1':
 C_SIGNAL='@t6g_mb_lib.t6g(sch_1):pvddio_p0_temp1';
NODE_NAME     PC77 1
 '@T6G_MB_LIB.T6G(SCH_1):PAGE175_I75@PURE_QUANTA.Q_CAP(CHIPS)':
 'A': CDS_PINID='A';
NODE_NAME     PU12 43
 '@T6G_MB_LIB.T6G(SCH_1):PAGE175_I128@PURE_QUANTA.RAA229620GNPHA0(CHIPS)':
 'TEMP1': CDS_PINID='TEMP1';
NODE_NAME     PU18 36
 '@T6G_MB_LIB.T6G(SCH_1):PAGE180_I15@PURE_QUANTA.ISL99390FRZTR5935(CHIPS)':
 'TOUT_FLT': CDS_PINID='TOUT_FLT';
NODE_NAME     PU17 36
 '@T6G_MB_LIB.T6G(SCH_1):PAGE180_I84@PURE_QUANTA.ISL99390FRZTR5935(CHIPS)':
 'TOUT_FLT': CDS_PINID='TOUT_FLT';
NODE_NAME     PU19 36
 '@T6G_MB_LIB.T6G(SCH_1):PAGE181_I32@PURE_QUANTA.ISL99390FRZTR5935(CHIPS)':
 'TOUT_FLT': CDS_PINID='TOUT_FLT';
NODE_NAME     PU20 36
 '@T6G_MB_LIB.T6G(SCH_1):PAGE181_I73@PURE_QUANTA.ISL99390FRZTR5935(CHIPS)':
 'TOUT_FLT': CDS_PINID='TOUT_FLT';
NET_NAME
'PVDDIO_P0_VCC1'
 '@T6G_MB_LIB.T6G(SCH_1):PVDDIO_P0_VCC1':
 C_SIGNAL='@t6g_mb_lib.t6g(sch_1):pvddio_p0_vcc1';
NODE_NAME     PC143 1
 '@T6G_MB_LIB.T6G(SCH_1):PAGE180_I28@PURE_QUANTA.Q_CAP(CHIPS)':
 'A': CDS_PINID='A';
NODE_NAME     PR100 2
 '@T6G_MB_LIB.T6G(SCH_1):PAGE180_I29@PURE_QUANTA.Q_RES(CHIPS)':
 'B': CDS_PINID='B';
NODE_NAME     PU17 35
 '@T6G_MB_LIB.T6G(SCH_1):PAGE180_I84@PURE_QUANTA.ISL99390FRZTR5935(CHIPS)':
 'EN': CDS_PINID='EN';
NODE_NAME     PU17 3
 '@T6G_MB_LIB.T6G(SCH_1):PAGE180_I84@PURE_QUANTA.ISL99390FRZTR5935(CHIPS)':
 'VCC': CDS_PINID='VCC';
NET_NAME
'PVDDIO_P0_VCC2'
 '@T6G_MB_LIB.T6G(SCH_1):PVDDIO_P0_VCC2':
 C_SIGNAL='@t6g_mb_lib.t6g(sch_1):pvddio_p0_vcc2';
NODE_NAME     PC142 1
 '@T6G_MB_LIB.T6G(SCH_1):PAGE180_I10@PURE_QUANTA.Q_CAP(CHIPS)':
 'A': CDS_PINID='A';
NODE_NAME     PR99 2
 '@T6G_MB_LIB.T6G(SCH_1):PAGE180_I12@PURE_QUANTA.Q_RES(CHIPS)':
 'B': CDS_PINID='B';
NODE_NAME     PU18 35
 '@T6G_MB_LIB.T6G(SCH_1):PAGE180_I15@PURE_QUANTA.ISL99390FRZTR5935(CHIPS)':
 'EN': CDS_PINID='EN';
NODE_NAME     PU18 3
 '@T6G_MB_LIB.T6G(SCH_1):PAGE180_I15@PURE_QUANTA.ISL99390FRZTR5935(CHIPS)':
 'VCC': CDS_PINID='VCC';
NET_NAME
'PVDDIO_P0_VCC3'
 '@T6G_MB_LIB.T6G(SCH_1):PVDDIO_P0_VCC3':
 C_SIGNAL='@t6g_mb_lib.t6g(sch_1):pvddio_p0_vcc3';
NODE_NAME     PR108 2
 '@T6G_MB_LIB.T6G(SCH_1):PAGE181_I28@PURE_QUANTA.Q_RES(CHIPS)':
 'B': CDS_PINID='B';
NODE_NAME     PC172 1
 '@T6G_MB_LIB.T6G(SCH_1):PAGE181_I27@PURE_QUANTA.Q_CAP(CHIPS)':
 'A': CDS_PINID='A';
NODE_NAME     PU19 35
 '@T6G_MB_LIB.T6G(SCH_1):PAGE181_I32@PURE_QUANTA.ISL99390FRZTR5935(CHIPS)':
 'EN': CDS_PINID='EN';
NODE_NAME     PU19 3
 '@T6G_MB_LIB.T6G(SCH_1):PAGE181_I32@PURE_QUANTA.ISL99390FRZTR5935(CHIPS)':
 'VCC': CDS_PINID='VCC';
NET_NAME
'PVDDIO_P0_VCC4'
 '@T6G_MB_LIB.T6G(SCH_1):PVDDIO_P0_VCC4':
 C_SIGNAL='@t6g_mb_lib.t6g(sch_1):pvddio_p0_vcc4';
NODE_NAME     PC171 1
 '@T6G_MB_LIB.T6G(SCH_1):PAGE181_I10@PURE_QUANTA.Q_CAP(CHIPS)':
 'A': CDS_PINID='A';
NODE_NAME     PR107 2
 '@T6G_MB_LIB.T6G(SCH_1):PAGE181_I12@PURE_QUANTA.Q_RES(CHIPS)':
 'B': CDS_PINID='B';
NODE_NAME     PU20 35
 '@T6G_MB_LIB.T6G(SCH_1):PAGE181_I73@PURE_QUANTA.ISL99390FRZTR5935(CHIPS)':
 'EN': CDS_PINID='EN';
NODE_NAME     PU20 3
 '@T6G_MB_LIB.T6G(SCH_1):PAGE181_I73@PURE_QUANTA.ISL99390FRZTR5935(CHIPS)':
 'VCC': CDS_PINID='VCC';
NET_NAME
'PVDDIO_P0_VOS1'
 '@T6G_MB_LIB.T6G(SCH_1):PVDDIO_P0_VOS1':
 C_SIGNAL='@t6g_mb_lib.t6g(sch_1):pvddio_p0_vos1';
NODE_NAME     PR103 1
 '@T6G_MB_LIB.T6G(SCH_1):PAGE180_I49@PURE_QUANTA.Q_RES(CHIPS)':
 'A': CDS_PINID='A';
NODE_NAME     PU17 1
 '@T6G_MB_LIB.T6G(SCH_1):PAGE180_I84@PURE_QUANTA.ISL99390FRZTR5935(CHIPS)':
 'VOS': CDS_PINID='VOS';
NET_NAME
'PVDDIO_P0_VOS2'
 '@T6G_MB_LIB.T6G(SCH_1):PVDDIO_P0_VOS2':
 C_SIGNAL='@t6g_mb_lib.t6g(sch_1):pvddio_p0_vos2';
NODE_NAME     PU18 1
 '@T6G_MB_LIB.T6G(SCH_1):PAGE180_I15@PURE_QUANTA.ISL99390FRZTR5935(CHIPS)':
 'VOS': CDS_PINID='VOS';
NODE_NAME     PR104 1
 '@T6G_MB_LIB.T6G(SCH_1):PAGE180_I39@PURE_QUANTA.Q_RES(CHIPS)':
 'A': CDS_PINID='A';
NET_NAME
'PVDDIO_P0_VOS3'
 '@T6G_MB_LIB.T6G(SCH_1):PVDDIO_P0_VOS3':
 C_SIGNAL='@t6g_mb_lib.t6g(sch_1):pvddio_p0_vos3';
NODE_NAME     PU19 1
 '@T6G_MB_LIB.T6G(SCH_1):PAGE181_I32@PURE_QUANTA.ISL99390FRZTR5935(CHIPS)':
 'VOS': CDS_PINID='VOS';
NODE_NAME     PR111 1
 '@T6G_MB_LIB.T6G(SCH_1):PAGE181_I50@PURE_QUANTA.Q_RES(CHIPS)':
 'A': CDS_PINID='A';
NET_NAME
'PVDDIO_P0_VOS4'
 '@T6G_MB_LIB.T6G(SCH_1):PVDDIO_P0_VOS4':
 C_SIGNAL='@t6g_mb_lib.t6g(sch_1):pvddio_p0_vos4';
NODE_NAME     PR112 1
 '@T6G_MB_LIB.T6G(SCH_1):PAGE181_I41@PURE_QUANTA.Q_RES(CHIPS)':
 'A': CDS_PINID='A';
NODE_NAME     PU20 1
 '@T6G_MB_LIB.T6G(SCH_1):PAGE181_I73@PURE_QUANTA.ISL99390FRZTR5935(CHIPS)':
 'VOS': CDS_PINID='VOS';
NET_NAME
'PVDDIO_P1'
 '@T6G_MB_LIB.T6G(SCH_1):PVDDIO_P1':
 C_SIGNAL='@t6g_mb_lib.t6g(sch_1):pvddio_p1',
 CDS_GLOBAL_NET='TRUE';
NODE_NAME     U26 AA54
 '@T6G_MB_LIB.T6G(SCH_1):PAGE57_I45@PURE_QUANTA.GENOA_SP5(CHIPS)':
 'VDDIO_AA54': CDS_PINID='VDDIO_AA54';
NODE_NAME     U26 AC58
 '@T6G_MB_LIB.T6G(SCH_1):PAGE57_I45@PURE_QUANTA.GENOA_SP5(CHIPS)':
 'VDDIO_AC58': CDS_PINID='VDDIO_AC58';
NODE_NAME     U26 AC65
 '@T6G_MB_LIB.T6G(SCH_1):PAGE57_I45@PURE_QUANTA.GENOA_SP5(CHIPS)':
 'VDDIO_AC65': CDS_PINID='VDDIO_AC65';
NODE_NAME     U26 AC72
 '@T6G_MB_LIB.T6G(SCH_1):PAGE57_I45@PURE_QUANTA.GENOA_SP5(CHIPS)':
 'VDDIO_AC72': CDS_PINID='VDDIO_AC72';
NODE_NAME     U26 AD54
 '@T6G_MB_LIB.T6G(SCH_1):PAGE57_I45@PURE_QUANTA.GENOA_SP5(CHIPS)':
 'VDDIO_AD54': CDS_PINID='VDDIO_AD54';
NODE_NAME     U26 AF57
 '@T6G_MB_LIB.T6G(SCH_1):PAGE57_I45@PURE_QUANTA.GENOA_SP5(CHIPS)':
 'VDDIO_AF57': CDS_PINID='VDDIO_AF57';
NODE_NAME     U26 AF64
 '@T6G_MB_LIB.T6G(SCH_1):PAGE57_I45@PURE_QUANTA.GENOA_SP5(CHIPS)':
 'VDDIO_AF64': CDS_PINID='VDDIO_AF64';
NODE_NAME     U26 AF71
 '@T6G_MB_LIB.T6G(SCH_1):PAGE57_I45@PURE_QUANTA.GENOA_SP5(CHIPS)':
 'VDDIO_AF71': CDS_PINID='VDDIO_AF71';
NODE_NAME     U26 AH54
 '@T6G_MB_LIB.T6G(SCH_1):PAGE57_I45@PURE_QUANTA.GENOA_SP5(CHIPS)':
 'VDDIO_AH54': CDS_PINID='VDDIO_AH54';
NODE_NAME     U26 AJ58
 '@T6G_MB_LIB.T6G(SCH_1):PAGE57_I45@PURE_QUANTA.GENOA_SP5(CHIPS)':
 'VDDIO_AJ58': CDS_PINID='VDDIO_AJ58';
NODE_NAME     U26 AJ65
 '@T6G_MB_LIB.T6G(SCH_1):PAGE57_I45@PURE_QUANTA.GENOA_SP5(CHIPS)':
 'VDDIO_AJ65': CDS_PINID='VDDIO_AJ65';
NODE_NAME     U26 AJ72
 '@T6G_MB_LIB.T6G(SCH_1):PAGE57_I45@PURE_QUANTA.GENOA_SP5(CHIPS)':
 'VDDIO_AJ72': CDS_PINID='VDDIO_AJ72';
NODE_NAME     U26 AM54
 '@T6G_MB_LIB.T6G(SCH_1):PAGE57_I45@PURE_QUANTA.GENOA_SP5(CHIPS)':
 'VDDIO_AM54': CDS_PINID='VDDIO_AM54';
NODE_NAME     U26 AM57
 '@T6G_MB_LIB.T6G(SCH_1):PAGE57_I45@PURE_QUANTA.GENOA_SP5(CHIPS)':
 'VDDIO_AM57': CDS_PINID='VDDIO_AM57';
NODE_NAME     U26 AM64
 '@T6G_MB_LIB.T6G(SCH_1):PAGE57_I45@PURE_QUANTA.GENOA_SP5(CHIPS)':
 'VDDIO_AM64': CDS_PINID='VDDIO_AM64';
NODE_NAME     U26 AM71
 '@T6G_MB_LIB.T6G(SCH_1):PAGE57_I45@PURE_QUANTA.GENOA_SP5(CHIPS)':
 'VDDIO_AM71': CDS_PINID='VDDIO_AM71';
NODE_NAME     U26 AR58
 '@T6G_MB_LIB.T6G(SCH_1):PAGE57_I45@PURE_QUANTA.GENOA_SP5(CHIPS)':
 'VDDIO_AR58': CDS_PINID='VDDIO_AR58';
NODE_NAME     U26 AR65
 '@T6G_MB_LIB.T6G(SCH_1):PAGE57_I45@PURE_QUANTA.GENOA_SP5(CHIPS)':
 'VDDIO_AR65': CDS_PINID='VDDIO_AR65';
NODE_NAME     U26 AR72
 '@T6G_MB_LIB.T6G(SCH_1):PAGE57_I45@PURE_QUANTA.GENOA_SP5(CHIPS)':
 'VDDIO_AR72': CDS_PINID='VDDIO_AR72';
NODE_NAME     U26 AV57
 '@T6G_MB_LIB.T6G(SCH_1):PAGE57_I45@PURE_QUANTA.GENOA_SP5(CHIPS)':
 'VDDIO_AV57': CDS_PINID='VDDIO_AV57';
NODE_NAME     U26 AV64
 '@T6G_MB_LIB.T6G(SCH_1):PAGE57_I45@PURE_QUANTA.GENOA_SP5(CHIPS)':
 'VDDIO_AV64': CDS_PINID='VDDIO_AV64';
NODE_NAME     U26 AV71
 '@T6G_MB_LIB.T6G(SCH_1):PAGE57_I45@PURE_QUANTA.GENOA_SP5(CHIPS)':
 'VDDIO_AV71': CDS_PINID='VDDIO_AV71';
NODE_NAME     U26 BA58
 '@T6G_MB_LIB.T6G(SCH_1):PAGE57_I45@PURE_QUANTA.GENOA_SP5(CHIPS)':
 'VDDIO_BA58': CDS_PINID='VDDIO_BA58';
NODE_NAME     U26 BA65
 '@T6G_MB_LIB.T6G(SCH_1):PAGE57_I45@PURE_QUANTA.GENOA_SP5(CHIPS)':
 'VDDIO_BA65': CDS_PINID='VDDIO_BA65';
NODE_NAME     U26 BA72
 '@T6G_MB_LIB.T6G(SCH_1):PAGE57_I45@PURE_QUANTA.GENOA_SP5(CHIPS)':
 'VDDIO_BA72': CDS_PINID='VDDIO_BA72';
NODE_NAME     U26 BD50
 '@T6G_MB_LIB.T6G(SCH_1):PAGE57_I45@PURE_QUANTA.GENOA_SP5(CHIPS)':
 'VDDIO_BD50': CDS_PINID='VDDIO_BD50';
NODE_NAME     U26 BD52
 '@T6G_MB_LIB.T6G(SCH_1):PAGE57_I45@PURE_QUANTA.GENOA_SP5(CHIPS)':
 'VDDIO_BD52': CDS_PINID='VDDIO_BD52';
NODE_NAME     U26 BD54
 '@T6G_MB_LIB.T6G(SCH_1):PAGE57_I45@PURE_QUANTA.GENOA_SP5(CHIPS)':
 'VDDIO_BD54': CDS_PINID='VDDIO_BD54';
NODE_NAME     U26 BF51
 '@T6G_MB_LIB.T6G(SCH_1):PAGE57_I45@PURE_QUANTA.GENOA_SP5(CHIPS)':
 'VDDIO_BF51': CDS_PINID='VDDIO_BF51';
NODE_NAME     U26 BF53
 '@T6G_MB_LIB.T6G(SCH_1):PAGE57_I45@PURE_QUANTA.GENOA_SP5(CHIPS)':
 'VDDIO_BF53': CDS_PINID='VDDIO_BF53';
NODE_NAME     U26 BF57
 '@T6G_MB_LIB.T6G(SCH_1):PAGE57_I45@PURE_QUANTA.GENOA_SP5(CHIPS)':
 'VDDIO_BF57': CDS_PINID='VDDIO_BF57';
NODE_NAME     U26 BF64
 '@T6G_MB_LIB.T6G(SCH_1):PAGE57_I45@PURE_QUANTA.GENOA_SP5(CHIPS)':
 'VDDIO_BF64': CDS_PINID='VDDIO_BF64';
NODE_NAME     U26 BF71
 '@T6G_MB_LIB.T6G(SCH_1):PAGE57_I45@PURE_QUANTA.GENOA_SP5(CHIPS)':
 'VDDIO_BF71': CDS_PINID='VDDIO_BF71';
NODE_NAME     U26 BG50
 '@T6G_MB_LIB.T6G(SCH_1):PAGE57_I45@PURE_QUANTA.GENOA_SP5(CHIPS)':
 'VDDIO_BG50': CDS_PINID='VDDIO_BG50';
NODE_NAME     U26 BG52
 '@T6G_MB_LIB.T6G(SCH_1):PAGE57_I45@PURE_QUANTA.GENOA_SP5(CHIPS)':
 'VDDIO_BG52': CDS_PINID='VDDIO_BG52';
NODE_NAME     U26 BG54
 '@T6G_MB_LIB.T6G(SCH_1):PAGE57_I45@PURE_QUANTA.GENOA_SP5(CHIPS)':
 'VDDIO_BG54': CDS_PINID='VDDIO_BG54';
NODE_NAME     U26 BH51
 '@T6G_MB_LIB.T6G(SCH_1):PAGE57_I45@PURE_QUANTA.GENOA_SP5(CHIPS)':
 'VDDIO_BH51': CDS_PINID='VDDIO_BH51';
NODE_NAME     U26 BH53
 '@T6G_MB_LIB.T6G(SCH_1):PAGE57_I45@PURE_QUANTA.GENOA_SP5(CHIPS)':
 'VDDIO_BH53': CDS_PINID='VDDIO_BH53';
NODE_NAME     U26 BJ50
 '@T6G_MB_LIB.T6G(SCH_1):PAGE57_I45@PURE_QUANTA.GENOA_SP5(CHIPS)':
 'VDDIO_BJ50': CDS_PINID='VDDIO_BJ50';
NODE_NAME     U26 BJ52
 '@T6G_MB_LIB.T6G(SCH_1):PAGE57_I45@PURE_QUANTA.GENOA_SP5(CHIPS)':
 'VDDIO_BJ52': CDS_PINID='VDDIO_BJ52';
NODE_NAME     U26 BJ54
 '@T6G_MB_LIB.T6G(SCH_1):PAGE57_I45@PURE_QUANTA.GENOA_SP5(CHIPS)':
 'VDDIO_BJ54': CDS_PINID='VDDIO_BJ54';
NODE_NAME     U26 BJ58
 '@T6G_MB_LIB.T6G(SCH_1):PAGE57_I45@PURE_QUANTA.GENOA_SP5(CHIPS)':
 'VDDIO_BJ58': CDS_PINID='VDDIO_BJ58';
NODE_NAME     U26 BJ65
 '@T6G_MB_LIB.T6G(SCH_1):PAGE57_I45@PURE_QUANTA.GENOA_SP5(CHIPS)':
 'VDDIO_BJ65': CDS_PINID='VDDIO_BJ65';
NODE_NAME     U26 BJ72
 '@T6G_MB_LIB.T6G(SCH_1):PAGE57_I45@PURE_QUANTA.GENOA_SP5(CHIPS)':
 'VDDIO_BJ72': CDS_PINID='VDDIO_BJ72';
NODE_NAME     U26 BK51
 '@T6G_MB_LIB.T6G(SCH_1):PAGE57_I45@PURE_QUANTA.GENOA_SP5(CHIPS)':
 'VDDIO_BK51': CDS_PINID='VDDIO_BK51';
NODE_NAME     U26 BK53
 '@T6G_MB_LIB.T6G(SCH_1):PAGE57_I45@PURE_QUANTA.GENOA_SP5(CHIPS)':
 'VDDIO_BK53': CDS_PINID='VDDIO_BK53';
NODE_NAME     U26 BL50
 '@T6G_MB_LIB.T6G(SCH_1):PAGE57_I45@PURE_QUANTA.GENOA_SP5(CHIPS)':
 'VDDIO_BL50': CDS_PINID='VDDIO_BL50';
NODE_NAME     U26 BL52
 '@T6G_MB_LIB.T6G(SCH_1):PAGE57_I45@PURE_QUANTA.GENOA_SP5(CHIPS)':
 'VDDIO_BL52': CDS_PINID='VDDIO_BL52';
NODE_NAME     U26 BL54
 '@T6G_MB_LIB.T6G(SCH_1):PAGE57_I45@PURE_QUANTA.GENOA_SP5(CHIPS)':
 'VDDIO_BL54': CDS_PINID='VDDIO_BL54';
NODE_NAME     U26 BM51
 '@T6G_MB_LIB.T6G(SCH_1):PAGE57_I45@PURE_QUANTA.GENOA_SP5(CHIPS)':
 'VDDIO_BM51': CDS_PINID='VDDIO_BM51';
NODE_NAME     U26 BM53
 '@T6G_MB_LIB.T6G(SCH_1):PAGE57_I45@PURE_QUANTA.GENOA_SP5(CHIPS)':
 'VDDIO_BM53': CDS_PINID='VDDIO_BM53';
NODE_NAME     U26 BM57
 '@T6G_MB_LIB.T6G(SCH_1):PAGE57_I45@PURE_QUANTA.GENOA_SP5(CHIPS)':
 'VDDIO_BM57': CDS_PINID='VDDIO_BM57';
NODE_NAME     U26 BM64
 '@T6G_MB_LIB.T6G(SCH_1):PAGE57_I45@PURE_QUANTA.GENOA_SP5(CHIPS)':
 'VDDIO_BM64': CDS_PINID='VDDIO_BM64';
NODE_NAME     U26 BM71
 '@T6G_MB_LIB.T6G(SCH_1):PAGE57_I45@PURE_QUANTA.GENOA_SP5(CHIPS)':
 'VDDIO_BM71': CDS_PINID='VDDIO_BM71';
NODE_NAME     U26 BN54
 '@T6G_MB_LIB.T6G(SCH_1):PAGE57_I45@PURE_QUANTA.GENOA_SP5(CHIPS)':
 'VDDIO_BN54': CDS_PINID='VDDIO_BN54';
NODE_NAME     U26 BR58
 '@T6G_MB_LIB.T6G(SCH_1):PAGE57_I45@PURE_QUANTA.GENOA_SP5(CHIPS)':
 'VDDIO_BR58': CDS_PINID='VDDIO_BR58';
NODE_NAME     U26 BR65
 '@T6G_MB_LIB.T6G(SCH_1):PAGE57_I45@PURE_QUANTA.GENOA_SP5(CHIPS)':
 'VDDIO_BR65': CDS_PINID='VDDIO_BR65';
NODE_NAME     U26 BR72
 '@T6G_MB_LIB.T6G(SCH_1):PAGE57_I45@PURE_QUANTA.GENOA_SP5(CHIPS)':
 'VDDIO_BR72': CDS_PINID='VDDIO_BR72';
NODE_NAME     U26 BV54
 '@T6G_MB_LIB.T6G(SCH_1):PAGE57_I45@PURE_QUANTA.GENOA_SP5(CHIPS)':
 'VDDIO_BV54': CDS_PINID='VDDIO_BV54';
NODE_NAME     U26 BV57
 '@T6G_MB_LIB.T6G(SCH_1):PAGE57_I45@PURE_QUANTA.GENOA_SP5(CHIPS)':
 'VDDIO_BV57': CDS_PINID='VDDIO_BV57';
NODE_NAME     U26 BV64
 '@T6G_MB_LIB.T6G(SCH_1):PAGE57_I45@PURE_QUANTA.GENOA_SP5(CHIPS)':
 'VDDIO_BV64': CDS_PINID='VDDIO_BV64';
NODE_NAME     U26 BV71
 '@T6G_MB_LIB.T6G(SCH_1):PAGE57_I45@PURE_QUANTA.GENOA_SP5(CHIPS)':
 'VDDIO_BV71': CDS_PINID='VDDIO_BV71';
NODE_NAME     U26 CA58
 '@T6G_MB_LIB.T6G(SCH_1):PAGE57_I45@PURE_QUANTA.GENOA_SP5(CHIPS)':
 'VDDIO_CA58': CDS_PINID='VDDIO_CA58';
NODE_NAME     U26 CA65
 '@T6G_MB_LIB.T6G(SCH_1):PAGE57_I45@PURE_QUANTA.GENOA_SP5(CHIPS)':
 'VDDIO_CA65': CDS_PINID='VDDIO_CA65';
NODE_NAME     U26 CA72
 '@T6G_MB_LIB.T6G(SCH_1):PAGE57_I45@PURE_QUANTA.GENOA_SP5(CHIPS)':
 'VDDIO_CA72': CDS_PINID='VDDIO_CA72';
NODE_NAME     U26 CB54
 '@T6G_MB_LIB.T6G(SCH_1):PAGE57_I45@PURE_QUANTA.GENOA_SP5(CHIPS)':
 'VDDIO_CB54': CDS_PINID='VDDIO_CB54';
NODE_NAME     U26 CD57
 '@T6G_MB_LIB.T6G(SCH_1):PAGE57_I45@PURE_QUANTA.GENOA_SP5(CHIPS)':
 'VDDIO_CD57': CDS_PINID='VDDIO_CD57';
NODE_NAME     U26 CD64
 '@T6G_MB_LIB.T6G(SCH_1):PAGE57_I45@PURE_QUANTA.GENOA_SP5(CHIPS)':
 'VDDIO_CD64': CDS_PINID='VDDIO_CD64';
NODE_NAME     U26 CD71
 '@T6G_MB_LIB.T6G(SCH_1):PAGE57_I45@PURE_QUANTA.GENOA_SP5(CHIPS)':
 'VDDIO_CD71': CDS_PINID='VDDIO_CD71';
NODE_NAME     U26 CF54
 '@T6G_MB_LIB.T6G(SCH_1):PAGE57_I45@PURE_QUANTA.GENOA_SP5(CHIPS)':
 'VDDIO_CF54': CDS_PINID='VDDIO_CF54';
NODE_NAME     U26 CG58
 '@T6G_MB_LIB.T6G(SCH_1):PAGE57_I45@PURE_QUANTA.GENOA_SP5(CHIPS)':
 'VDDIO_CG58': CDS_PINID='VDDIO_CG58';
NODE_NAME     U26 CG65
 '@T6G_MB_LIB.T6G(SCH_1):PAGE57_I45@PURE_QUANTA.GENOA_SP5(CHIPS)':
 'VDDIO_CG65': CDS_PINID='VDDIO_CG65';
NODE_NAME     U26 CG72
 '@T6G_MB_LIB.T6G(SCH_1):PAGE57_I45@PURE_QUANTA.GENOA_SP5(CHIPS)':
 'VDDIO_CG72': CDS_PINID='VDDIO_CG72';
NODE_NAME     U26 CJ54
 '@T6G_MB_LIB.T6G(SCH_1):PAGE57_I45@PURE_QUANTA.GENOA_SP5(CHIPS)':
 'VDDIO_CJ54': CDS_PINID='VDDIO_CJ54';
NODE_NAME     U26 CK57
 '@T6G_MB_LIB.T6G(SCH_1):PAGE57_I45@PURE_QUANTA.GENOA_SP5(CHIPS)':
 'VDDIO_CK57': CDS_PINID='VDDIO_CK57';
NODE_NAME     U26 CK64
 '@T6G_MB_LIB.T6G(SCH_1):PAGE57_I45@PURE_QUANTA.GENOA_SP5(CHIPS)':
 'VDDIO_CK64': CDS_PINID='VDDIO_CK64';
NODE_NAME     U26 CK71
 '@T6G_MB_LIB.T6G(SCH_1):PAGE57_I45@PURE_QUANTA.GENOA_SP5(CHIPS)':
 'VDDIO_CK71': CDS_PINID='VDDIO_CK71';
NODE_NAME     U26 CM54
 '@T6G_MB_LIB.T6G(SCH_1):PAGE57_I45@PURE_QUANTA.GENOA_SP5(CHIPS)':
 'VDDIO_CM54': CDS_PINID='VDDIO_CM54';
NODE_NAME     U26 CN58
 '@T6G_MB_LIB.T6G(SCH_1):PAGE57_I45@PURE_QUANTA.GENOA_SP5(CHIPS)':
 'VDDIO_CN58': CDS_PINID='VDDIO_CN58';
NODE_NAME     U26 CN65
 '@T6G_MB_LIB.T6G(SCH_1):PAGE57_I45@PURE_QUANTA.GENOA_SP5(CHIPS)':
 'VDDIO_CN65': CDS_PINID='VDDIO_CN65';
NODE_NAME     U26 CN72
 '@T6G_MB_LIB.T6G(SCH_1):PAGE57_I45@PURE_QUANTA.GENOA_SP5(CHIPS)':
 'VDDIO_CN72': CDS_PINID='VDDIO_CN72';
NODE_NAME     U26 CT54
 '@T6G_MB_LIB.T6G(SCH_1):PAGE57_I45@PURE_QUANTA.GENOA_SP5(CHIPS)':
 'VDDIO_CT54': CDS_PINID='VDDIO_CT54';
NODE_NAME     U26 CT57
 '@T6G_MB_LIB.T6G(SCH_1):PAGE57_I45@PURE_QUANTA.GENOA_SP5(CHIPS)':
 'VDDIO_CT57': CDS_PINID='VDDIO_CT57';
NODE_NAME     U26 CT64
 '@T6G_MB_LIB.T6G(SCH_1):PAGE57_I45@PURE_QUANTA.GENOA_SP5(CHIPS)':
 'VDDIO_CT64': CDS_PINID='VDDIO_CT64';
NODE_NAME     U26 CT71
 '@T6G_MB_LIB.T6G(SCH_1):PAGE57_I45@PURE_QUANTA.GENOA_SP5(CHIPS)':
 'VDDIO_CT71': CDS_PINID='VDDIO_CT71';
NODE_NAME     U26 CW58
 '@T6G_MB_LIB.T6G(SCH_1):PAGE57_I45@PURE_QUANTA.GENOA_SP5(CHIPS)':
 'VDDIO_CW58': CDS_PINID='VDDIO_CW58';
NODE_NAME     U26 CW65
 '@T6G_MB_LIB.T6G(SCH_1):PAGE57_I45@PURE_QUANTA.GENOA_SP5(CHIPS)':
 'VDDIO_CW65': CDS_PINID='VDDIO_CW65';
NODE_NAME     U26 CW72
 '@T6G_MB_LIB.T6G(SCH_1):PAGE57_I45@PURE_QUANTA.GENOA_SP5(CHIPS)':
 'VDDIO_CW72': CDS_PINID='VDDIO_CW72';
NODE_NAME     U26 CY54
 '@T6G_MB_LIB.T6G(SCH_1):PAGE57_I45@PURE_QUANTA.GENOA_SP5(CHIPS)':
 'VDDIO_CY54': CDS_PINID='VDDIO_CY54';
NODE_NAME     U26 DB57
 '@T6G_MB_LIB.T6G(SCH_1):PAGE57_I45@PURE_QUANTA.GENOA_SP5(CHIPS)':
 'VDDIO_DB57': CDS_PINID='VDDIO_DB57';
NODE_NAME     U26 DB64
 '@T6G_MB_LIB.T6G(SCH_1):PAGE57_I45@PURE_QUANTA.GENOA_SP5(CHIPS)':
 'VDDIO_DB64': CDS_PINID='VDDIO_DB64';
NODE_NAME     U26 DB71
 '@T6G_MB_LIB.T6G(SCH_1):PAGE57_I45@PURE_QUANTA.GENOA_SP5(CHIPS)':
 'VDDIO_DB71': CDS_PINID='VDDIO_DB71';
NODE_NAME     U26 DE58
 '@T6G_MB_LIB.T6G(SCH_1):PAGE57_I45@PURE_QUANTA.GENOA_SP5(CHIPS)':
 'VDDIO_DE58': CDS_PINID='VDDIO_DE58';
NODE_NAME     U26 DE65
 '@T6G_MB_LIB.T6G(SCH_1):PAGE57_I45@PURE_QUANTA.GENOA_SP5(CHIPS)':
 'VDDIO_DE65': CDS_PINID='VDDIO_DE65';
NODE_NAME     U26 DE72
 '@T6G_MB_LIB.T6G(SCH_1):PAGE57_I45@PURE_QUANTA.GENOA_SP5(CHIPS)':
 'VDDIO_DE72': CDS_PINID='VDDIO_DE72';
NODE_NAME     U26 DG64
 '@T6G_MB_LIB.T6G(SCH_1):PAGE57_I45@PURE_QUANTA.GENOA_SP5(CHIPS)':
 'VDDIO_DG64': CDS_PINID='VDDIO_DG64';
NODE_NAME     U26 DG71
 '@T6G_MB_LIB.T6G(SCH_1):PAGE57_I45@PURE_QUANTA.GENOA_SP5(CHIPS)':
 'VDDIO_DG71': CDS_PINID='VDDIO_DG71';
NODE_NAME     U26 H57
 '@T6G_MB_LIB.T6G(SCH_1):PAGE57_I45@PURE_QUANTA.GENOA_SP5(CHIPS)':
 'VDDIO_H57': CDS_PINID='VDDIO_H57';
NODE_NAME     U26 H64
 '@T6G_MB_LIB.T6G(SCH_1):PAGE57_I45@PURE_QUANTA.GENOA_SP5(CHIPS)':
 'VDDIO_H64': CDS_PINID='VDDIO_H64';
NODE_NAME     U26 H71
 '@T6G_MB_LIB.T6G(SCH_1):PAGE57_I45@PURE_QUANTA.GENOA_SP5(CHIPS)':
 'VDDIO_H71': CDS_PINID='VDDIO_H71';
NODE_NAME     U26 K54
 '@T6G_MB_LIB.T6G(SCH_1):PAGE57_I45@PURE_QUANTA.GENOA_SP5(CHIPS)':
 'VDDIO_K54': CDS_PINID='VDDIO_K54';
NODE_NAME     U26 L58
 '@T6G_MB_LIB.T6G(SCH_1):PAGE57_I45@PURE_QUANTA.GENOA_SP5(CHIPS)':
 'VDDIO_L58': CDS_PINID='VDDIO_L58';
NODE_NAME     U26 L65
 '@T6G_MB_LIB.T6G(SCH_1):PAGE57_I45@PURE_QUANTA.GENOA_SP5(CHIPS)':
 'VDDIO_L65': CDS_PINID='VDDIO_L65';
NODE_NAME     U26 L72
 '@T6G_MB_LIB.T6G(SCH_1):PAGE57_I45@PURE_QUANTA.GENOA_SP5(CHIPS)':
 'VDDIO_L72': CDS_PINID='VDDIO_L72';
NODE_NAME     U26 P54
 '@T6G_MB_LIB.T6G(SCH_1):PAGE57_I45@PURE_QUANTA.GENOA_SP5(CHIPS)':
 'VDDIO_P54': CDS_PINID='VDDIO_P54';
NODE_NAME     U26 P57
 '@T6G_MB_LIB.T6G(SCH_1):PAGE57_I45@PURE_QUANTA.GENOA_SP5(CHIPS)':
 'VDDIO_P57': CDS_PINID='VDDIO_P57';
NODE_NAME     U26 P64
 '@T6G_MB_LIB.T6G(SCH_1):PAGE57_I45@PURE_QUANTA.GENOA_SP5(CHIPS)':
 'VDDIO_P64': CDS_PINID='VDDIO_P64';
NODE_NAME     U26 P71
 '@T6G_MB_LIB.T6G(SCH_1):PAGE57_I45@PURE_QUANTA.GENOA_SP5(CHIPS)':
 'VDDIO_P71': CDS_PINID='VDDIO_P71';
NODE_NAME     U26 U58
 '@T6G_MB_LIB.T6G(SCH_1):PAGE57_I45@PURE_QUANTA.GENOA_SP5(CHIPS)':
 'VDDIO_U58': CDS_PINID='VDDIO_U58';
NODE_NAME     U26 U65
 '@T6G_MB_LIB.T6G(SCH_1):PAGE57_I45@PURE_QUANTA.GENOA_SP5(CHIPS)':
 'VDDIO_U65': CDS_PINID='VDDIO_U65';
NODE_NAME     U26 U72
 '@T6G_MB_LIB.T6G(SCH_1):PAGE57_I45@PURE_QUANTA.GENOA_SP5(CHIPS)':
 'VDDIO_U72': CDS_PINID='VDDIO_U72';
NODE_NAME     U26 V54
 '@T6G_MB_LIB.T6G(SCH_1):PAGE57_I45@PURE_QUANTA.GENOA_SP5(CHIPS)':
 'VDDIO_V54': CDS_PINID='VDDIO_V54';
NODE_NAME     U26 Y57
 '@T6G_MB_LIB.T6G(SCH_1):PAGE57_I45@PURE_QUANTA.GENOA_SP5(CHIPS)':
 'VDDIO_Y57': CDS_PINID='VDDIO_Y57';
NODE_NAME     U26 Y64
 '@T6G_MB_LIB.T6G(SCH_1):PAGE57_I45@PURE_QUANTA.GENOA_SP5(CHIPS)':
 'VDDIO_Y64': CDS_PINID='VDDIO_Y64';
NODE_NAME     U26 Y71
 '@T6G_MB_LIB.T6G(SCH_1):PAGE57_I45@PURE_QUANTA.GENOA_SP5(CHIPS)':
 'VDDIO_Y71': CDS_PINID='VDDIO_Y71';
NODE_NAME     C2260 1
 '@T6G_MB_LIB.T6G(SCH_1):PAGE71_I53@PURE_QUANTA.Q_CAP(CHIPS)':
 'A': CDS_PINID='A';
NODE_NAME     C2265 1
 '@T6G_MB_LIB.T6G(SCH_1):PAGE71_I54@PURE_QUANTA.Q_CAP(CHIPS)':
 'A': CDS_PINID='A';
NODE_NAME     C2270 1
 '@T6G_MB_LIB.T6G(SCH_1):PAGE71_I56@PURE_QUANTA.Q_CAP(CHIPS)':
 'A': CDS_PINID='A';
NODE_NAME     C2274 1
 '@T6G_MB_LIB.T6G(SCH_1):PAGE71_I57@PURE_QUANTA.Q_CAP(CHIPS)':
 'A': CDS_PINID='A';
NODE_NAME     C2278 1
 '@T6G_MB_LIB.T6G(SCH_1):PAGE71_I58@PURE_QUANTA.Q_CAP(CHIPS)':
 'A': CDS_PINID='A';
NODE_NAME     C3910 1
 '@T6G_MB_LIB.T6G(SCH_1):PAGE71_I59@PURE_QUANTA.Q_CAP(CHIPS)':
 'A': CDS_PINID='A';
NODE_NAME     C3911 1
 '@T6G_MB_LIB.T6G(SCH_1):PAGE71_I61@PURE_QUANTA.Q_CAP(CHIPS)':
 'A': CDS_PINID='A';
NODE_NAME     C2479 1
 '@T6G_MB_LIB.T6G(SCH_1):PAGE73_I129@PURE_QUANTA.Q_CAP(CHIPS)':
 'A': CDS_PINID='A';
NODE_NAME     C2478 1
 '@T6G_MB_LIB.T6G(SCH_1):PAGE73_I134@PURE_QUANTA.Q_CAP(CHIPS)':
 'A': CDS_PINID='A';
NODE_NAME     C2477 1
 '@T6G_MB_LIB.T6G(SCH_1):PAGE73_I136@PURE_QUANTA.Q_CAP(CHIPS)':
 'A': CDS_PINID='A';
NODE_NAME     C2103 1
 '@T6G_MB_LIB.T6G(SCH_1):PAGE73_I137@PURE_QUANTA.Q_CAP(CHIPS)':
 'A': CDS_PINID='A';
NODE_NAME     C2106 1
 '@T6G_MB_LIB.T6G(SCH_1):PAGE73_I138@PURE_QUANTA.Q_CAP(CHIPS)':
 'A': CDS_PINID='A';
NODE_NAME     C2484 1
 '@T6G_MB_LIB.T6G(SCH_1):PAGE73_I139@PURE_QUANTA.Q_CAP(CHIPS)':
 'A': CDS_PINID='A';
NODE_NAME     C2102 1
 '@T6G_MB_LIB.T6G(SCH_1):PAGE73_I140@PURE_QUANTA.Q_CAP(CHIPS)':
 'A': CDS_PINID='A';
NODE_NAME     C2105 1
 '@T6G_MB_LIB.T6G(SCH_1):PAGE73_I141@PURE_QUANTA.Q_CAP(CHIPS)':
 'A': CDS_PINID='A';
NODE_NAME     C2104 1
 '@T6G_MB_LIB.T6G(SCH_1):PAGE73_I142@PURE_QUANTA.Q_CAP(CHIPS)':
 'A': CDS_PINID='A';
NODE_NAME     C2108 1
 '@T6G_MB_LIB.T6G(SCH_1):PAGE73_I144@PURE_QUANTA.Q_CAP(CHIPS)':
 'A': CDS_PINID='A';
NODE_NAME     C2107 1
 '@T6G_MB_LIB.T6G(SCH_1):PAGE73_I145@PURE_QUANTA.Q_CAP(CHIPS)':
 'A': CDS_PINID='A';
NODE_NAME     C2493 1
 '@T6G_MB_LIB.T6G(SCH_1):PAGE73_I146@PURE_QUANTA.Q_CAP(CHIPS)':
 'A': CDS_PINID='A';
NODE_NAME     C2498 1
 '@T6G_MB_LIB.T6G(SCH_1):PAGE73_I147@PURE_QUANTA.Q_CAP(CHIPS)':
 'A': CDS_PINID='A';
NODE_NAME     C2109 1
 '@T6G_MB_LIB.T6G(SCH_1):PAGE73_I148@PURE_QUANTA.Q_CAP(CHIPS)':
 'A': CDS_PINID='A';
NODE_NAME     C2111 1
 '@T6G_MB_LIB.T6G(SCH_1):PAGE73_I149@PURE_QUANTA.Q_CAP(CHIPS)':
 'A': CDS_PINID='A';
NODE_NAME     C2112 1
 '@T6G_MB_LIB.T6G(SCH_1):PAGE73_I150@PURE_QUANTA.Q_CAP(CHIPS)':
 'A': CDS_PINID='A';
NODE_NAME     C2110 1
 '@T6G_MB_LIB.T6G(SCH_1):PAGE73_I151@PURE_QUANTA.Q_CAP(CHIPS)':
 'A': CDS_PINID='A';
NODE_NAME     C2507 1
 '@T6G_MB_LIB.T6G(SCH_1):PAGE73_I152@PURE_QUANTA.Q_CAP(CHIPS)':
 'A': CDS_PINID='A';
NODE_NAME     C2117 1
 '@T6G_MB_LIB.T6G(SCH_1):PAGE73_I153@PURE_QUANTA.Q_CAP(CHIPS)':
 'A': CDS_PINID='A';
NODE_NAME     C2116 1
 '@T6G_MB_LIB.T6G(SCH_1):PAGE73_I154@PURE_QUANTA.Q_CAP(CHIPS)':
 'A': CDS_PINID='A';
NODE_NAME     C2123 1
 '@T6G_MB_LIB.T6G(SCH_1):PAGE73_I168@PURE_QUANTA.Q_CAP(CHIPS)':
 'A': CDS_PINID='A';
NODE_NAME     C2122 1
 '@T6G_MB_LIB.T6G(SCH_1):PAGE73_I169@PURE_QUANTA.Q_CAP(CHIPS)':
 'A': CDS_PINID='A';
NODE_NAME     C2509 1
 '@T6G_MB_LIB.T6G(SCH_1):PAGE73_I170@PURE_QUANTA.Q_CAP(CHIPS)':
 'A': CDS_PINID='A';
NODE_NAME     C2127 1
 '@T6G_MB_LIB.T6G(SCH_1):PAGE73_I172@PURE_QUANTA.Q_CAP(CHIPS)':
 'A': CDS_PINID='A';
NODE_NAME     PC634_4 1
 '@T6G_MB_LIB.T6G(SCH_1):PAGE198_I51@PURE_QUANTA.Q_CAP(CHIPS)':
 'A': CDS_PINID='A';
NODE_NAME     PR374 2
 '@T6G_MB_LIB.T6G(SCH_1):PAGE198_I55@PURE_QUANTA.Q_RES(CHIPS)':
 'B': CDS_PINID='B';
NODE_NAME     PC635_3 1
 '@T6G_MB_LIB.T6G(SCH_1):PAGE198_I68@PURE_QUANTA.Q_CAP(CHIPS)':
 'A': CDS_PINID='A';
NODE_NAME     PR227 2
 '@T6G_MB_LIB.T6G(SCH_1):PAGE192_I22@PURE_QUANTA.Q_RES(CHIPS)':
 'B': CDS_PINID='B';
NODE_NAME     PR281 2
 '@T6G_MB_LIB.T6G(SCH_1):PAGE197_I45@PURE_QUANTA.Q_RES(CHIPS)':
 'B': CDS_PINID='B';
NODE_NAME     PR280 2
 '@T6G_MB_LIB.T6G(SCH_1):PAGE197_I50@PURE_QUANTA.Q_RES(CHIPS)':
 'B': CDS_PINID='B';
NODE_NAME     PC458_2 1
 '@T6G_MB_LIB.T6G(SCH_1):PAGE197_I55@PURE_QUANTA.Q_CAP(CHIPS)':
 'A': CDS_PINID='A';
NODE_NAME     PC460_2 1
 '@T6G_MB_LIB.T6G(SCH_1):PAGE197_I57@PURE_QUANTA.Q_CAP(CHIPS)':
 'A': CDS_PINID='A';
NODE_NAME     PC450 1
 '@T6G_MB_LIB.T6G(SCH_1):PAGE197_I58@PURE_QUANTA.Q_CAPP(CHIPS)':
 'A': CDS_PINID='A';
NODE_NAME     PC452 1
 '@T6G_MB_LIB.T6G(SCH_1):PAGE197_I59@PURE_QUANTA.Q_CAPP(CHIPS)':
 'A': CDS_PINID='A';
NODE_NAME     PC455 1
 '@T6G_MB_LIB.T6G(SCH_1):PAGE197_I62@PURE_QUANTA.Q_CAPP(CHIPS)':
 'A': CDS_PINID='A';
NODE_NAME     PL47 4
 '@T6G_MB_LIB.T6G(SCH_1):PAGE197_I71@PURE_QUANTA.Q_INDUCTOR4P_14(CHIPS)':
 '4': CDS_PINID='\4\';
NODE_NAME     PC451 1
 '@T6G_MB_LIB.T6G(SCH_1):PAGE197_I77@PURE_QUANTA.Q_CAP(CHIPS)':
 'A': CDS_PINID='A';
NODE_NAME     PC456_1 1
 '@T6G_MB_LIB.T6G(SCH_1):PAGE197_I78@PURE_QUANTA.Q_CAP(CHIPS)':
 'A': CDS_PINID='A';
NODE_NAME     PC459_1 1
 '@T6G_MB_LIB.T6G(SCH_1):PAGE197_I79@PURE_QUANTA.Q_CAP(CHIPS)':
 'A': CDS_PINID='A';
NODE_NAME     PR378 1
 '@T6G_MB_LIB.T6G(SCH_1):PAGE197_I81@PURE_QUANTA.Q_RES(CHIPS)':
 'A': CDS_PINID='A';
NODE_NAME     PL48 4
 '@T6G_MB_LIB.T6G(SCH_1):PAGE197_I83@PURE_QUANTA.Q_INDUCTOR4P_14(CHIPS)':
 '4': CDS_PINID='\4\';
NODE_NAME     PR375 2
 '@T6G_MB_LIB.T6G(SCH_1):PAGE198_I41@PURE_QUANTA.Q_RES(CHIPS)':
 'B': CDS_PINID='B';
NODE_NAME     PL67 4
 '@T6G_MB_LIB.T6G(SCH_1):PAGE198_I42@PURE_QUANTA.Q_INDUCTOR4P_14(CHIPS)':
 '4': CDS_PINID='\4\';
NODE_NAME     PC636_4 1
 '@T6G_MB_LIB.T6G(SCH_1):PAGE198_I53@PURE_QUANTA.Q_CAP(CHIPS)':
 'A': CDS_PINID='A';
NODE_NAME     PL68 4
 '@T6G_MB_LIB.T6G(SCH_1):PAGE198_I62@PURE_QUANTA.Q_INDUCTOR4P_14(CHIPS)':
 '4': CDS_PINID='\4\';
NODE_NAME     PC637_3 1
 '@T6G_MB_LIB.T6G(SCH_1):PAGE198_I70@PURE_QUANTA.Q_CAP(CHIPS)':
 'A': CDS_PINID='A';
NET_NAME
'PVDDIO_P1_EN'
 '@T6G_MB_LIB.T6G(SCH_1):PVDDIO_P1_EN':
 C_SIGNAL='@t6g_mb_lib.t6g(sch_1):pvddio_p1_en';
NODE_NAME     R282 1
 '@T6G_MB_LIB.T6G(SCH_1):PAGE80_I31@PURE_QUANTA.Q_RES(CHIPS)':
 'A': CDS_PINID='A';
NODE_NAME     R8224 1
 '@T6G_MB_LIB.T6G(SCH_1):PAGE192_I2@PURE_QUANTA.Q_RES(CHIPS)':
 'A': CDS_PINID='A';
NET_NAME
'PVDDIO_P1_EN_G'
 '@T6G_MB_LIB.T6G(SCH_1):PVDDIO_P1_EN_G':
 C_SIGNAL='@t6g_mb_lib.t6g(sch_1):pvddio_p1_en_g';
NODE_NAME     PQ16 D
 '@T6G_MB_LIB.T6G(SCH_1):PAGE192_I6@PURE_QUANTA.MOSFET_N(CHIPS)':
 'DRAIN': CDS_PINID='DRAIN';
NODE_NAME     PQ12 G
 '@T6G_MB_LIB.T6G(SCH_1):PAGE192_I13@PURE_QUANTA.MOSFET_PCH_GDS_ESD_PROTECTED(CHIPS)':
 'G': CDS_PINID='G';
NODE_NAME     PR232 2
 '@T6G_MB_LIB.T6G(SCH_1):PAGE192_I17@PURE_QUANTA.Q_RES(CHIPS)':
 'B': CDS_PINID='B';
NET_NAME
'PVDDIO_P1_EN_R'
 '@T6G_MB_LIB.T6G(SCH_1):PVDDIO_P1_EN_R':
 C_SIGNAL='@t6g_mb_lib.t6g(sch_1):pvddio_p1_en_r';
NODE_NAME     R8224 2
 '@T6G_MB_LIB.T6G(SCH_1):PAGE192_I2@PURE_QUANTA.Q_RES(CHIPS)':
 'B': CDS_PINID='B';
NODE_NAME     C8356 1
 '@T6G_MB_LIB.T6G(SCH_1):PAGE192_I3@PURE_QUANTA.Q_CAP(CHIPS)':
 'A': CDS_PINID='A';
NODE_NAME     PQ16 G
 '@T6G_MB_LIB.T6G(SCH_1):PAGE192_I6@PURE_QUANTA.MOSFET_N(CHIPS)':
 'GATE': CDS_PINID='GATE';
NODE_NAME     R6088 1
 '@T6G_MB_LIB.T6G(SCH_1):PAGE192_I130@PURE_QUANTA.Q_RES(CHIPS)':
 'A': CDS_PINID='A';
NET_NAME
'PVDDIO_P1_IMON1'
 '@T6G_MB_LIB.T6G(SCH_1):PVDDIO_P1_IMON1':
 C_SIGNAL='@t6g_mb_lib.t6g(sch_1):pvddio_p1_imon1';
NODE_NAME     PU34 38
 '@T6G_MB_LIB.T6G(SCH_1):PAGE192_I128@PURE_QUANTA.RAA229620GNPHA0(CHIPS)':
 'CS0': CDS_PINID='CS0';
NODE_NAME     PU39 38
 '@T6G_MB_LIB.T6G(SCH_1):PAGE197_I39@PURE_QUANTA.ISL99390FRZTR5935(CHIPS)':
 'IOUT': CDS_PINID='IOUT';
NET_NAME
'PVDDIO_P1_IMON2'
 '@T6G_MB_LIB.T6G(SCH_1):PVDDIO_P1_IMON2':
 C_SIGNAL='@t6g_mb_lib.t6g(sch_1):pvddio_p1_imon2';
NODE_NAME     PU34 37
 '@T6G_MB_LIB.T6G(SCH_1):PAGE192_I128@PURE_QUANTA.RAA229620GNPHA0(CHIPS)':
 'CS1': CDS_PINID='CS1';
NODE_NAME     PU40 38
 '@T6G_MB_LIB.T6G(SCH_1):PAGE197_I84@PURE_QUANTA.ISL99390FRZTR5935(CHIPS)':
 'IOUT': CDS_PINID='IOUT';
NET_NAME
'PVDDIO_P1_IMON3'
 '@T6G_MB_LIB.T6G(SCH_1):PVDDIO_P1_IMON3':
 C_SIGNAL='@t6g_mb_lib.t6g(sch_1):pvddio_p1_imon3';
NODE_NAME     PU34 36
 '@T6G_MB_LIB.T6G(SCH_1):PAGE192_I128@PURE_QUANTA.RAA229620GNPHA0(CHIPS)':
 'CS2': CDS_PINID='CS2';
NODE_NAME     PU52 38
 '@T6G_MB_LIB.T6G(SCH_1):PAGE198_I73@PURE_QUANTA.ISL99390FRZTR5935(CHIPS)':
 'IOUT': CDS_PINID='IOUT';
NET_NAME
'PVDDIO_P1_IMON4'
 '@T6G_MB_LIB.T6G(SCH_1):PVDDIO_P1_IMON4':
 C_SIGNAL='@t6g_mb_lib.t6g(sch_1):pvddio_p1_imon4';
NODE_NAME     PU53 38
 '@T6G_MB_LIB.T6G(SCH_1):PAGE198_I15@PURE_QUANTA.ISL99390FRZTR5935(CHIPS)':
 'IOUT': CDS_PINID='IOUT';
NODE_NAME     PU34 35
 '@T6G_MB_LIB.T6G(SCH_1):PAGE192_I128@PURE_QUANTA.RAA229620GNPHA0(CHIPS)':
 'CS3': CDS_PINID='CS3';
NET_NAME
'PVDDIO_P1_LSET1'
 '@T6G_MB_LIB.T6G(SCH_1):PVDDIO_P1_LSET1':
 C_SIGNAL='@t6g_mb_lib.t6g(sch_1):pvddio_p1_lset1';
NODE_NAME     PR275 1
 '@T6G_MB_LIB.T6G(SCH_1):PAGE197_I28@PURE_QUANTA.Q_RES(CHIPS)':
 'A': CDS_PINID='A';
NODE_NAME     PU39 37
 '@T6G_MB_LIB.T6G(SCH_1):PAGE197_I39@PURE_QUANTA.ISL99390FRZTR5935(CHIPS)':
 'LSET': CDS_PINID='LSET';
NET_NAME
'PVDDIO_P1_LSET2'
 '@T6G_MB_LIB.T6G(SCH_1):PVDDIO_P1_LSET2':
 C_SIGNAL='@t6g_mb_lib.t6g(sch_1):pvddio_p1_lset2';
NODE_NAME     PR274 1
 '@T6G_MB_LIB.T6G(SCH_1):PAGE197_I6@PURE_QUANTA.Q_RES(CHIPS)':
 'A': CDS_PINID='A';
NODE_NAME     PU40 37
 '@T6G_MB_LIB.T6G(SCH_1):PAGE197_I84@PURE_QUANTA.ISL99390FRZTR5935(CHIPS)':
 'LSET': CDS_PINID='LSET';
NET_NAME
'PVDDIO_P1_LSET3'
 '@T6G_MB_LIB.T6G(SCH_1):PVDDIO_P1_LSET3':
 C_SIGNAL='@t6g_mb_lib.t6g(sch_1):pvddio_p1_lset3';
NODE_NAME     PR369 1
 '@T6G_MB_LIB.T6G(SCH_1):PAGE198_I22@PURE_QUANTA.Q_RES(CHIPS)':
 'A': CDS_PINID='A';
NODE_NAME     PU52 37
 '@T6G_MB_LIB.T6G(SCH_1):PAGE198_I73@PURE_QUANTA.ISL99390FRZTR5935(CHIPS)':
 'LSET': CDS_PINID='LSET';
NET_NAME
'PVDDIO_P1_LSET4'
 '@T6G_MB_LIB.T6G(SCH_1):PVDDIO_P1_LSET4':
 C_SIGNAL='@t6g_mb_lib.t6g(sch_1):pvddio_p1_lset4';
NODE_NAME     PU53 37
 '@T6G_MB_LIB.T6G(SCH_1):PAGE198_I15@PURE_QUANTA.ISL99390FRZTR5935(CHIPS)':
 'LSET': CDS_PINID='LSET';
NODE_NAME     PR368 1
 '@T6G_MB_LIB.T6G(SCH_1):PAGE198_I4@PURE_QUANTA.Q_RES(CHIPS)':
 'A': CDS_PINID='A';
NET_NAME
'PVDDIO_P1_PWM1'
 '@T6G_MB_LIB.T6G(SCH_1):PVDDIO_P1_PWM1':
 C_SIGNAL='@t6g_mb_lib.t6g(sch_1):pvddio_p1_pwm1';
NODE_NAME     PU34 1
 '@T6G_MB_LIB.T6G(SCH_1):PAGE192_I128@PURE_QUANTA.RAA229620GNPHA0(CHIPS)':
 'PWM0': CDS_PINID='PWM0';
NODE_NAME     PU39 34
 '@T6G_MB_LIB.T6G(SCH_1):PAGE197_I39@PURE_QUANTA.ISL99390FRZTR5935(CHIPS)':
 'PWM': CDS_PINID='PWM';
NET_NAME
'PVDDIO_P1_PWM2'
 '@T6G_MB_LIB.T6G(SCH_1):PVDDIO_P1_PWM2':
 C_SIGNAL='@t6g_mb_lib.t6g(sch_1):pvddio_p1_pwm2';
NODE_NAME     PU34 2
 '@T6G_MB_LIB.T6G(SCH_1):PAGE192_I128@PURE_QUANTA.RAA229620GNPHA0(CHIPS)':
 'PWM1': CDS_PINID='PWM1';
NODE_NAME     PU40 34
 '@T6G_MB_LIB.T6G(SCH_1):PAGE197_I84@PURE_QUANTA.ISL99390FRZTR5935(CHIPS)':
 'PWM': CDS_PINID='PWM';
NET_NAME
'PVDDIO_P1_PWM3'
 '@T6G_MB_LIB.T6G(SCH_1):PVDDIO_P1_PWM3':
 C_SIGNAL='@t6g_mb_lib.t6g(sch_1):pvddio_p1_pwm3';
NODE_NAME     PU34 3
 '@T6G_MB_LIB.T6G(SCH_1):PAGE192_I128@PURE_QUANTA.RAA229620GNPHA0(CHIPS)':
 'PWM2': CDS_PINID='PWM2';
NODE_NAME     PU52 34
 '@T6G_MB_LIB.T6G(SCH_1):PAGE198_I73@PURE_QUANTA.ISL99390FRZTR5935(CHIPS)':
 'PWM': CDS_PINID='PWM';
NET_NAME
'PVDDIO_P1_PWM4'
 '@T6G_MB_LIB.T6G(SCH_1):PVDDIO_P1_PWM4':
 C_SIGNAL='@t6g_mb_lib.t6g(sch_1):pvddio_p1_pwm4';
NODE_NAME     PU53 34
 '@T6G_MB_LIB.T6G(SCH_1):PAGE198_I15@PURE_QUANTA.ISL99390FRZTR5935(CHIPS)':
 'PWM': CDS_PINID='PWM';
NODE_NAME     PU34 4
 '@T6G_MB_LIB.T6G(SCH_1):PAGE192_I128@PURE_QUANTA.RAA229620GNPHA0(CHIPS)':
 'PWM3': CDS_PINID='PWM3';
NET_NAME
'PVDDIO_P1_TEMP1'
 '@T6G_MB_LIB.T6G(SCH_1):PVDDIO_P1_TEMP1':
 C_SIGNAL='@t6g_mb_lib.t6g(sch_1):pvddio_p1_temp1';
NODE_NAME     PU53 36
 '@T6G_MB_LIB.T6G(SCH_1):PAGE198_I15@PURE_QUANTA.ISL99390FRZTR5935(CHIPS)':
 'TOUT_FLT': CDS_PINID='TOUT_FLT';
NODE_NAME     PC367 1
 '@T6G_MB_LIB.T6G(SCH_1):PAGE192_I75@PURE_QUANTA.Q_CAP(CHIPS)':
 'A': CDS_PINID='A';
NODE_NAME     PU34 43
 '@T6G_MB_LIB.T6G(SCH_1):PAGE192_I128@PURE_QUANTA.RAA229620GNPHA0(CHIPS)':
 'TEMP1': CDS_PINID='TEMP1';
NODE_NAME     PU39 36
 '@T6G_MB_LIB.T6G(SCH_1):PAGE197_I39@PURE_QUANTA.ISL99390FRZTR5935(CHIPS)':
 'TOUT_FLT': CDS_PINID='TOUT_FLT';
NODE_NAME     PU40 36
 '@T6G_MB_LIB.T6G(SCH_1):PAGE197_I84@PURE_QUANTA.ISL99390FRZTR5935(CHIPS)':
 'TOUT_FLT': CDS_PINID='TOUT_FLT';
NODE_NAME     PU52 36
 '@T6G_MB_LIB.T6G(SCH_1):PAGE198_I73@PURE_QUANTA.ISL99390FRZTR5935(CHIPS)':
 'TOUT_FLT': CDS_PINID='TOUT_FLT';
NET_NAME
'PVDDIO_P1_VCC1'
 '@T6G_MB_LIB.T6G(SCH_1):PVDDIO_P1_VCC1':
 C_SIGNAL='@t6g_mb_lib.t6g(sch_1):pvddio_p1_vcc1';
NODE_NAME     PC433 1
 '@T6G_MB_LIB.T6G(SCH_1):PAGE197_I34@PURE_QUANTA.Q_CAP(CHIPS)':
 'A': CDS_PINID='A';
NODE_NAME     PR277 2
 '@T6G_MB_LIB.T6G(SCH_1):PAGE197_I35@PURE_QUANTA.Q_RES(CHIPS)':
 'B': CDS_PINID='B';
NODE_NAME     PU39 35
 '@T6G_MB_LIB.T6G(SCH_1):PAGE197_I39@PURE_QUANTA.ISL99390FRZTR5935(CHIPS)':
 'EN': CDS_PINID='EN';
NODE_NAME     PU39 3
 '@T6G_MB_LIB.T6G(SCH_1):PAGE197_I39@PURE_QUANTA.ISL99390FRZTR5935(CHIPS)':
 'VCC': CDS_PINID='VCC';
NET_NAME
'PVDDIO_P1_VCC2'
 '@T6G_MB_LIB.T6G(SCH_1):PVDDIO_P1_VCC2':
 C_SIGNAL='@t6g_mb_lib.t6g(sch_1):pvddio_p1_vcc2';
NODE_NAME     PC432 1
 '@T6G_MB_LIB.T6G(SCH_1):PAGE197_I12@PURE_QUANTA.Q_CAP(CHIPS)':
 'A': CDS_PINID='A';
NODE_NAME     PR276 2
 '@T6G_MB_LIB.T6G(SCH_1):PAGE197_I13@PURE_QUANTA.Q_RES(CHIPS)':
 'B': CDS_PINID='B';
NODE_NAME     PU40 35
 '@T6G_MB_LIB.T6G(SCH_1):PAGE197_I84@PURE_QUANTA.ISL99390FRZTR5935(CHIPS)':
 'EN': CDS_PINID='EN';
NODE_NAME     PU40 3
 '@T6G_MB_LIB.T6G(SCH_1):PAGE197_I84@PURE_QUANTA.ISL99390FRZTR5935(CHIPS)':
 'VCC': CDS_PINID='VCC';
NET_NAME
'PVDDIO_P1_VCC3'
 '@T6G_MB_LIB.T6G(SCH_1):PVDDIO_P1_VCC3':
 C_SIGNAL='@t6g_mb_lib.t6g(sch_1):pvddio_p1_vcc3';
NODE_NAME     PC617 1
 '@T6G_MB_LIB.T6G(SCH_1):PAGE198_I28@PURE_QUANTA.Q_CAP(CHIPS)':
 'A': CDS_PINID='A';
NODE_NAME     PR371 2
 '@T6G_MB_LIB.T6G(SCH_1):PAGE198_I29@PURE_QUANTA.Q_RES(CHIPS)':
 'B': CDS_PINID='B';
NODE_NAME     PU52 35
 '@T6G_MB_LIB.T6G(SCH_1):PAGE198_I73@PURE_QUANTA.ISL99390FRZTR5935(CHIPS)':
 'EN': CDS_PINID='EN';
NODE_NAME     PU52 3
 '@T6G_MB_LIB.T6G(SCH_1):PAGE198_I73@PURE_QUANTA.ISL99390FRZTR5935(CHIPS)':
 'VCC': CDS_PINID='VCC';
NET_NAME
'PVDDIO_P1_VCC4'
 '@T6G_MB_LIB.T6G(SCH_1):PVDDIO_P1_VCC4':
 C_SIGNAL='@t6g_mb_lib.t6g(sch_1):pvddio_p1_vcc4';
NODE_NAME     PU53 35
 '@T6G_MB_LIB.T6G(SCH_1):PAGE198_I15@PURE_QUANTA.ISL99390FRZTR5935(CHIPS)':
 'EN': CDS_PINID='EN';
NODE_NAME     PU53 3
 '@T6G_MB_LIB.T6G(SCH_1):PAGE198_I15@PURE_QUANTA.ISL99390FRZTR5935(CHIPS)':
 'VCC': CDS_PINID='VCC';
NODE_NAME     PC616 1
 '@T6G_MB_LIB.T6G(SCH_1):PAGE198_I10@PURE_QUANTA.Q_CAP(CHIPS)':
 'A': CDS_PINID='A';
NODE_NAME     PR370 2
 '@T6G_MB_LIB.T6G(SCH_1):PAGE198_I12@PURE_QUANTA.Q_RES(CHIPS)':
 'B': CDS_PINID='B';
NET_NAME
'PVDDIO_P1_VOS1'
 '@T6G_MB_LIB.T6G(SCH_1):PVDDIO_P1_VOS1':
 C_SIGNAL='@t6g_mb_lib.t6g(sch_1):pvddio_p1_vos1';
NODE_NAME     PU39 1
 '@T6G_MB_LIB.T6G(SCH_1):PAGE197_I39@PURE_QUANTA.ISL99390FRZTR5935(CHIPS)':
 'VOS': CDS_PINID='VOS';
NODE_NAME     PR280 1
 '@T6G_MB_LIB.T6G(SCH_1):PAGE197_I50@PURE_QUANTA.Q_RES(CHIPS)':
 'A': CDS_PINID='A';
NET_NAME
'PVDDIO_P1_VOS2'
 '@T6G_MB_LIB.T6G(SCH_1):PVDDIO_P1_VOS2':
 C_SIGNAL='@t6g_mb_lib.t6g(sch_1):pvddio_p1_vos2';
NODE_NAME     PR281 1
 '@T6G_MB_LIB.T6G(SCH_1):PAGE197_I45@PURE_QUANTA.Q_RES(CHIPS)':
 'A': CDS_PINID='A';
NODE_NAME     PU40 1
 '@T6G_MB_LIB.T6G(SCH_1):PAGE197_I84@PURE_QUANTA.ISL99390FRZTR5935(CHIPS)':
 'VOS': CDS_PINID='VOS';
NET_NAME
'PVDDIO_P1_VOS3'
 '@T6G_MB_LIB.T6G(SCH_1):PVDDIO_P1_VOS3':
 C_SIGNAL='@t6g_mb_lib.t6g(sch_1):pvddio_p1_vos3';
NODE_NAME     PR374 1
 '@T6G_MB_LIB.T6G(SCH_1):PAGE198_I55@PURE_QUANTA.Q_RES(CHIPS)':
 'A': CDS_PINID='A';
NODE_NAME     PU52 1
 '@T6G_MB_LIB.T6G(SCH_1):PAGE198_I73@PURE_QUANTA.ISL99390FRZTR5935(CHIPS)':
 'VOS': CDS_PINID='VOS';
NET_NAME
'PVDDIO_P1_VOS4'
 '@T6G_MB_LIB.T6G(SCH_1):PVDDIO_P1_VOS4':
 C_SIGNAL='@t6g_mb_lib.t6g(sch_1):pvddio_p1_vos4';
NODE_NAME     PU53 1
 '@T6G_MB_LIB.T6G(SCH_1):PAGE198_I15@PURE_QUANTA.ISL99390FRZTR5935(CHIPS)':
 'VOS': CDS_PINID='VOS';
NODE_NAME     PR375 1
 '@T6G_MB_LIB.T6G(SCH_1):PAGE198_I41@PURE_QUANTA.Q_RES(CHIPS)':
 'A': CDS_PINID='A';
NET_NAME
'PVDD_33_S5'
 '@T6G_MB_LIB.T6G(SCH_1):PVDD_33_S5':
 C_SIGNAL='@t6g_mb_lib.t6g(sch_1):pvdd_33_s5',
 CDS_GLOBAL_NET='TRUE';
NODE_NAME     U25 BN52
 '@T6G_MB_LIB.T6G(SCH_1):PAGE30_I28@PURE_QUANTA.GENOA_SP5(CHIPS)':
 'VDD_33_S5_BN52': CDS_PINID='VDD_33_S5_BN52';
NODE_NAME     U25 BP51
 '@T6G_MB_LIB.T6G(SCH_1):PAGE30_I28@PURE_QUANTA.GENOA_SP5(CHIPS)':
 'VDD_33_S5_BP51': CDS_PINID='VDD_33_S5_BP51';
NODE_NAME     U26 BN52
 '@T6G_MB_LIB.T6G(SCH_1):PAGE57_I45@PURE_QUANTA.GENOA_SP5(CHIPS)':
 'VDD_33_S5_BN52': CDS_PINID='VDD_33_S5_BN52';
NODE_NAME     U26 BP51
 '@T6G_MB_LIB.T6G(SCH_1):PAGE57_I45@PURE_QUANTA.GENOA_SP5(CHIPS)':
 'VDD_33_S5_BP51': CDS_PINID='VDD_33_S5_BP51';
NODE_NAME     PC132 2
 '@T6G_MB_LIB.T6G(SCH_1):PAGE167_I24@PURE_QUANTA.Q_CAP(CHIPS)':
 'B': CDS_PINID='B';
NODE_NAME     PR455 2
 '@T6G_MB_LIB.T6G(SCH_1):PAGE167_I25@PURE_QUANTA.Q_RES(CHIPS)':
 'B': CDS_PINID='B';
NODE_NAME     PC129 1
 '@T6G_MB_LIB.T6G(SCH_1):PAGE167_I27@PURE_QUANTA.Q_CAP(CHIPS)':
 'A': CDS_PINID='A';
NODE_NAME     PC130 1
 '@T6G_MB_LIB.T6G(SCH_1):PAGE167_I28@PURE_QUANTA.Q_CAP(CHIPS)':
 'A': CDS_PINID='A';
NODE_NAME     PC134 1
 '@T6G_MB_LIB.T6G(SCH_1):PAGE167_I35@PURE_QUANTA.Q_CAP(CHIPS)':
 'A': CDS_PINID='A';
NODE_NAME     PC135 1
 '@T6G_MB_LIB.T6G(SCH_1):PAGE167_I36@PURE_QUANTA.Q_CAP(CHIPS)':
 'A': CDS_PINID='A';
NODE_NAME     PC136 1
 '@T6G_MB_LIB.T6G(SCH_1):PAGE167_I37@PURE_QUANTA.Q_CAP(CHIPS)':
 'A': CDS_PINID='A';
NODE_NAME     PL72 2
 '@T6G_MB_LIB.T6G(SCH_1):PAGE167_I47@PURE_QUANTA.Q_INDUCTOR(CHIPS)':
 '2': CDS_PINID='\2\';
NODE_NAME     C2515 1
 '@T6G_MB_LIB.T6G(SCH_1):PAGE70_I25@PURE_QUANTA.Q_CAP(CHIPS)':
 'A': CDS_PINID='A';
NODE_NAME     C2512 1
 '@T6G_MB_LIB.T6G(SCH_1):PAGE70_I26@PURE_QUANTA.Q_CAP(CHIPS)':
 'A': CDS_PINID='A';
NODE_NAME     C2662 1
 '@T6G_MB_LIB.T6G(SCH_1):PAGE74_I25@PURE_QUANTA.Q_CAP(CHIPS)':
 'A': CDS_PINID='A';
NODE_NAME     C2659 1
 '@T6G_MB_LIB.T6G(SCH_1):PAGE74_I26@PURE_QUANTA.Q_CAP(CHIPS)':
 'A': CDS_PINID='A';
NODE_NAME     R1235 1
 '@T6G_MB_LIB.T6G(SCH_1):PAGE263_I215@PURE_QUANTA.Q_RES(CHIPS)':
 'A': CDS_PINID='A';
NET_NAME
'PVDD_33_S5_ADC'
 '@T6G_MB_LIB.T6G(SCH_1):PVDD_33_S5_ADC':
 C_SIGNAL='@t6g_mb_lib.t6g(sch_1):pvdd_33_s5_adc';
NODE_NAME     R1248 1
 '@T6G_MB_LIB.T6G(SCH_1):PAGE263_I213@PURE_QUANTA.Q_RES(CHIPS)':
 'A': CDS_PINID='A';
NODE_NAME     R1255 1
 '@T6G_MB_LIB.T6G(SCH_1):PAGE263_I214@PURE_QUANTA.Q_RES(CHIPS)':
 'A': CDS_PINID='A';
NODE_NAME     R1235 2
 '@T6G_MB_LIB.T6G(SCH_1):PAGE263_I215@PURE_QUANTA.Q_RES(CHIPS)':
 'B': CDS_PINID='B';
NODE_NAME     R1224 1
 '@T6G_MB_LIB.T6G(SCH_1):PAGE263_I216@PURE_QUANTA.Q_RES(CHIPS)':
 'A': CDS_PINID='A';
NET_NAME
'PVDD_33_S5_ADC_MAM'
 '@T6G_MB_LIB.T6G(SCH_1):PVDD_33_S5_ADC_MAM':
 C_SIGNAL='@t6g_mb_lib.t6g(sch_1):pvdd_33_s5_adc_mam';
NODE_NAME     U50 10
 '@T6G_MB_LIB.T6G(SCH_1):PAGE263_I156@PURE_QUANTA.MAX11617EEET(CHIPS)':
 'AIN5': CDS_PINID='AIN5';
NODE_NAME     C1082 1
 '@T6G_MB_LIB.T6G(SCH_1):PAGE263_I209@PURE_QUANTA.Q_CAP(CHIPS)':
 'A': CDS_PINID='A';
NODE_NAME     R1248 2
 '@T6G_MB_LIB.T6G(SCH_1):PAGE263_I213@PURE_QUANTA.Q_RES(CHIPS)':
 'B': CDS_PINID='B';
NET_NAME
'PVDD_33_S5_ADC_TIC'
 '@T6G_MB_LIB.T6G(SCH_1):PVDD_33_S5_ADC_TIC':
 C_SIGNAL='@t6g_mb_lib.t6g(sch_1):pvdd_33_s5_adc_tic';
NODE_NAME     U51 11
 '@T6G_MB_LIB.T6G(SCH_1):PAGE263_I142@PURE_QUANTA.ADC128D818CIMTXNOPB(CHIPS)':
 'IN5': CDS_PINID='IN5';
NODE_NAME     C1089 1
 '@T6G_MB_LIB.T6G(SCH_1):PAGE263_I211@PURE_QUANTA.Q_CAP(CHIPS)':
 'A': CDS_PINID='A';
NODE_NAME     R1255 2
 '@T6G_MB_LIB.T6G(SCH_1):PAGE263_I214@PURE_QUANTA.Q_RES(CHIPS)':
 'B': CDS_PINID='B';
NET_NAME
'PVDD_33_S5_CS'
 '@T6G_MB_LIB.T6G(SCH_1):PVDD_33_S5_CS':
 C_SIGNAL='@t6g_mb_lib.t6g(sch_1):pvdd_33_s5_cs';
NODE_NAME     PR452 1
 '@T6G_MB_LIB.T6G(SCH_1):PAGE167_I15@PURE_QUANTA.Q_RES(CHIPS)':
 'A': CDS_PINID='A';
NODE_NAME     PU55 3
 '@T6G_MB_LIB.T6G(SCH_1):PAGE167_I41@PURE_QUANTA.MPQ8633AGLEC807Z(CHIPS)':
 'CS': CDS_PINID='CS';
NET_NAME
'PVDD_33_S5_FB'
 '@T6G_MB_LIB.T6G(SCH_1):PVDD_33_S5_FB':
 C_SIGNAL='@t6g_mb_lib.t6g(sch_1):pvdd_33_s5_fb';
NODE_NAME     PR454 1
 '@T6G_MB_LIB.T6G(SCH_1):PAGE167_I23@PURE_QUANTA.Q_RES(CHIPS)':
 'A': CDS_PINID='A';
NODE_NAME     PC132 1
 '@T6G_MB_LIB.T6G(SCH_1):PAGE167_I24@PURE_QUANTA.Q_CAP(CHIPS)':
 'A': CDS_PINID='A';
NODE_NAME     PR455 1
 '@T6G_MB_LIB.T6G(SCH_1):PAGE167_I25@PURE_QUANTA.Q_RES(CHIPS)':
 'A': CDS_PINID='A';
NODE_NAME     PU55 7
 '@T6G_MB_LIB.T6G(SCH_1):PAGE167_I41@PURE_QUANTA.MPQ8633AGLEC807Z(CHIPS)':
 'FB': CDS_PINID='FB';
NET_NAME
'PVDD_33_S5_MODE'
 '@T6G_MB_LIB.T6G(SCH_1):PVDD_33_S5_MODE':
 C_SIGNAL='@t6g_mb_lib.t6g(sch_1):pvdd_33_s5_mode';
NODE_NAME     PR6000 2
 '@T6G_MB_LIB.T6G(SCH_1):PAGE167_I17@PURE_QUANTA.Q_RES(CHIPS)':
 'B': CDS_PINID='B';
NODE_NAME     PU55 4
 '@T6G_MB_LIB.T6G(SCH_1):PAGE167_I41@PURE_QUANTA.MPQ8633AGLEC807Z(CHIPS)':
 'MODE': CDS_PINID='MODE';
NET_NAME
'PVDD_33_S5_REF'
 '@T6G_MB_LIB.T6G(SCH_1):PVDD_33_S5_REF':
 C_SIGNAL='@t6g_mb_lib.t6g(sch_1):pvdd_33_s5_ref';
NODE_NAME     PC127 1
 '@T6G_MB_LIB.T6G(SCH_1):PAGE167_I19@PURE_QUANTA.Q_CAP(CHIPS)':
 'A': CDS_PINID='A';
NODE_NAME     PU55 5
 '@T6G_MB_LIB.T6G(SCH_1):PAGE167_I41@PURE_QUANTA.MPQ8633AGLEC807Z(CHIPS)':
 'TRK_REF': CDS_PINID='TRK_REF';
NET_NAME
'PVDD_33_S5_VCC'
 '@T6G_MB_LIB.T6G(SCH_1):PVDD_33_S5_VCC':
 C_SIGNAL='@t6g_mb_lib.t6g(sch_1):pvdd_33_s5_vcc',
 CDS_GLOBAL_NET='TRUE';
NODE_NAME     PC118 1
 '@T6G_MB_LIB.T6G(SCH_1):PAGE167_I2@PURE_QUANTA.Q_CAP(CHIPS)':
 'A': CDS_PINID='A';
NODE_NAME     R453 1
 '@T6G_MB_LIB.T6G(SCH_1):PAGE167_I31@PURE_QUANTA.Q_RES(CHIPS)':
 'A': CDS_PINID='A';
NODE_NAME     PU55 19
 '@T6G_MB_LIB.T6G(SCH_1):PAGE167_I41@PURE_QUANTA.MPQ8633AGLEC807Z(CHIPS)':
 'VCC': CDS_PINID='VCC';
NET_NAME
'PWRGD_CHAF_CPU0'
 '@T6G_MB_LIB.T6G(SCH_1):PWRGD_CHAF_CPU0':
 C_SIGNAL='@t6g_mb_lib.t6g(sch_1):pwrgd_chaf_cpu0';
NODE_NAME     R291 2
 '@T6G_MB_LIB.T6G(SCH_1):PAGE85_I525@PURE_QUANTA.Q_RES(CHIPS)':
 'B': CDS_PINID='B';
NODE_NAME     R88 2
 '@T6G_MB_LIB.T6G(SCH_1):PAGE85_I526@PURE_QUANTA.Q_RES(CHIPS)':
 'B': CDS_PINID='B';
NODE_NAME     R292 2
 '@T6G_MB_LIB.T6G(SCH_1):PAGE86_I364@PURE_QUANTA.Q_RES(CHIPS)':
 'B': CDS_PINID='B';
NODE_NAME     R293 2
 '@T6G_MB_LIB.T6G(SCH_1):PAGE87_I364@PURE_QUANTA.Q_RES(CHIPS)':
 'B': CDS_PINID='B';
NODE_NAME     R294 2
 '@T6G_MB_LIB.T6G(SCH_1):PAGE88_I369@PURE_QUANTA.Q_RES(CHIPS)':
 'B': CDS_PINID='B';
NODE_NAME     R295 2
 '@T6G_MB_LIB.T6G(SCH_1):PAGE89_I362@PURE_QUANTA.Q_RES(CHIPS)':
 'B': CDS_PINID='B';
NODE_NAME     R296 2
 '@T6G_MB_LIB.T6G(SCH_1):PAGE90_I364@PURE_QUANTA.Q_RES(CHIPS)':
 'B': CDS_PINID='B';
NODE_NAME     R8037 2
 '@T6G_MB_LIB.T6G(SCH_1):PAGE85_I540@PURE_QUANTA.Q_RES(CHIPS)':
 'B': CDS_PINID='B';
NODE_NAME     R8080 1
 '@T6G_MB_LIB.T6G(SCH_1):PAGE85_I544@PURE_QUANTA.Q_RES(CHIPS)':
 'A': CDS_PINID='A';
NET_NAME
'PWRGD_CHAF_CPU0_R1'
 '@T6G_MB_LIB.T6G(SCH_1):PWRGD_CHAF_CPU0_R1':
 C_SIGNAL='@t6g_mb_lib.t6g(sch_1):pwrgd_chaf_cpu0_r1';
NODE_NAME     R8080 2
 '@T6G_MB_LIB.T6G(SCH_1):PAGE85_I544@PURE_QUANTA.Q_RES(CHIPS)':
 'B': CDS_PINID='B';
NODE_NAME     R8081 1
 '@T6G_MB_LIB.T6G(SCH_1):PAGE85_I545@PURE_QUANTA.Q_RES(CHIPS)':
 'A': CDS_PINID='A';
NODE_NAME     R8082 2
 '@T6G_MB_LIB.T6G(SCH_1):PAGE85_I547@PURE_QUANTA.Q_RES(CHIPS)':
 'B': CDS_PINID='B';
NODE_NAME     D8003 1
 '@T6G_MB_LIB.T6G(SCH_1):PAGE85_I549@PURE_QUANTA.SCHOTTKY_12(CHIPS)':
 'A': CDS_PINID='A';
NET_NAME
'PWRGD_CHAF_CPU0_R2'
 '@T6G_MB_LIB.T6G(SCH_1):PWRGD_CHAF_CPU0_R2':
 C_SIGNAL='@t6g_mb_lib.t6g(sch_1):pwrgd_chaf_cpu0_r2';
NODE_NAME     U18 W1
 '@T6G_MB_LIB.T6G(SCH_1):PAGE81_I143@PURE_QUANTA.LCMXO3LF9400C5BG484C(CHIPS)':
 'PL28A': CDS_PINID='PL28A';
NODE_NAME     R8081 2
 '@T6G_MB_LIB.T6G(SCH_1):PAGE85_I545@PURE_QUANTA.Q_RES(CHIPS)':
 'B': CDS_PINID='B';
NET_NAME
'PWRGD_CHAF_CPU1'
 '@T6G_MB_LIB.T6G(SCH_1):PWRGD_CHAF_CPU1':
 C_SIGNAL='@t6g_mb_lib.t6g(sch_1):pwrgd_chaf_cpu1';
NODE_NAME     R102 2
 '@T6G_MB_LIB.T6G(SCH_1):PAGE97_I189@PURE_QUANTA.Q_RES(CHIPS)':
 'B': CDS_PINID='B';
NODE_NAME     R303 2
 '@T6G_MB_LIB.T6G(SCH_1):PAGE97_I190@PURE_QUANTA.Q_RES(CHIPS)':
 'B': CDS_PINID='B';
NODE_NAME     R304 2
 '@T6G_MB_LIB.T6G(SCH_1):PAGE98_I188@PURE_QUANTA.Q_RES(CHIPS)':
 'B': CDS_PINID='B';
NODE_NAME     R305 2
 '@T6G_MB_LIB.T6G(SCH_1):PAGE99_I188@PURE_QUANTA.Q_RES(CHIPS)':
 'B': CDS_PINID='B';
NODE_NAME     R306 2
 '@T6G_MB_LIB.T6G(SCH_1):PAGE100_I188@PURE_QUANTA.Q_RES(CHIPS)':
 'B': CDS_PINID='B';
NODE_NAME     R307 2
 '@T6G_MB_LIB.T6G(SCH_1):PAGE101_I188@PURE_QUANTA.Q_RES(CHIPS)':
 'B': CDS_PINID='B';
NODE_NAME     R1183 2
 '@T6G_MB_LIB.T6G(SCH_1):PAGE102_I188@PURE_QUANTA.Q_RES(CHIPS)':
 'B': CDS_PINID='B';
NODE_NAME     R8039 2
 '@T6G_MB_LIB.T6G(SCH_1):PAGE97_I245@PURE_QUANTA.Q_RES(CHIPS)':
 'B': CDS_PINID='B';
NODE_NAME     R8086 1
 '@T6G_MB_LIB.T6G(SCH_1):PAGE97_I250@PURE_QUANTA.Q_RES(CHIPS)':
 'A': CDS_PINID='A';
NET_NAME
'PWRGD_CHAF_CPU1_R1'
 '@T6G_MB_LIB.T6G(SCH_1):PWRGD_CHAF_CPU1_R1':
 C_SIGNAL='@t6g_mb_lib.t6g(sch_1):pwrgd_chaf_cpu1_r1';
NODE_NAME     R8086 2
 '@T6G_MB_LIB.T6G(SCH_1):PAGE97_I250@PURE_QUANTA.Q_RES(CHIPS)':
 'B': CDS_PINID='B';
NODE_NAME     R8088 2
 '@T6G_MB_LIB.T6G(SCH_1):PAGE97_I251@PURE_QUANTA.Q_RES(CHIPS)':
 'B': CDS_PINID='B';
NODE_NAME     R8087 1
 '@T6G_MB_LIB.T6G(SCH_1):PAGE97_I252@PURE_QUANTA.Q_RES(CHIPS)':
 'A': CDS_PINID='A';
NODE_NAME     D8005 1
 '@T6G_MB_LIB.T6G(SCH_1):PAGE97_I253@PURE_QUANTA.SCHOTTKY_12(CHIPS)':
 'A': CDS_PINID='A';
NET_NAME
'PWRGD_CHAF_CPU1_R2'
 '@T6G_MB_LIB.T6G(SCH_1):PWRGD_CHAF_CPU1_R2':
 C_SIGNAL='@t6g_mb_lib.t6g(sch_1):pwrgd_chaf_cpu1_r2';
NODE_NAME     U18 R6
 '@T6G_MB_LIB.T6G(SCH_1):PAGE81_I143@PURE_QUANTA.LCMXO3LF9400C5BG484C(CHIPS)':
 'PL25C': CDS_PINID='PL25C';
NODE_NAME     R8087 2
 '@T6G_MB_LIB.T6G(SCH_1):PAGE97_I252@PURE_QUANTA.Q_RES(CHIPS)':
 'B': CDS_PINID='B';
NET_NAME
'PWRGD_CHA_CPU0_DIMM0'
 '@T6G_MB_LIB.T6G(SCH_1):PWRGD_CHA_CPU0_DIMM0':
 C_SIGNAL='@t6g_mb_lib.t6g(sch_1):pwrgd_cha_cpu0_dimm0';
NODE_NAME     R291 1
 '@T6G_MB_LIB.T6G(SCH_1):PAGE85_I525@PURE_QUANTA.Q_RES(CHIPS)':
 'A': CDS_PINID='A';
NODE_NAME     R89 2
 '@T6G_MB_LIB.T6G(SCH_1):PAGE85_I528@PURE_QUANTA.Q_RES(CHIPS)':
 'B': CDS_PINID='B';
NODE_NAME     J1 147
 '@T6G_MB_LIB.T6G(SCH_1):PAGE85_I536@PURE_QUANTA.SCONN288_DDR506112002KQ(CHIPS)':
 'PWR_GOOD||FAIL_N': CDS_PINID='\pwr_good||fail_n\';
NET_NAME
'PWRGD_CHA_CPU1_DIMM0'
 '@T6G_MB_LIB.T6G(SCH_1):PWRGD_CHA_CPU1_DIMM0':
 C_SIGNAL='@t6g_mb_lib.t6g(sch_1):pwrgd_cha_cpu1_dimm0';
NODE_NAME     J24 147
 '@T6G_MB_LIB.T6G(SCH_1):PAGE97_I22@PURE_QUANTA.SCONN288_DDR506112002KQ(CHIPS)':
 'PWR_GOOD||FAIL_N': CDS_PINID='\pwr_good||fail_n\';
NODE_NAME     R303 1
 '@T6G_MB_LIB.T6G(SCH_1):PAGE97_I190@PURE_QUANTA.Q_RES(CHIPS)':
 'A': CDS_PINID='A';
NODE_NAME     R103 2
 '@T6G_MB_LIB.T6G(SCH_1):PAGE97_I191@PURE_QUANTA.Q_RES(CHIPS)':
 'B': CDS_PINID='B';
NET_NAME
'PWRGD_CHB_CPU0_DIMM'
 '@T6G_MB_LIB.T6G(SCH_1):PWRGD_CHB_CPU0_DIMM':
 C_SIGNAL='@t6g_mb_lib.t6g(sch_1):pwrgd_chb_cpu0_dimm';
NODE_NAME     J15 147
 '@T6G_MB_LIB.T6G(SCH_1):PAGE86_I350@PURE_QUANTA.SCONN288_DDR506112002KQ(CHIPS)':
 'PWR_GOOD||FAIL_N': CDS_PINID='\pwr_good||fail_n\';
NODE_NAME     R292 1
 '@T6G_MB_LIB.T6G(SCH_1):PAGE86_I364@PURE_QUANTA.Q_RES(CHIPS)':
 'A': CDS_PINID='A';
NODE_NAME     R90 2
 '@T6G_MB_LIB.T6G(SCH_1):PAGE86_I365@PURE_QUANTA.Q_RES(CHIPS)':
 'B': CDS_PINID='B';
NET_NAME
'PWRGD_CHB_CPU1_DIMM'
 '@T6G_MB_LIB.T6G(SCH_1):PWRGD_CHB_CPU1_DIMM':
 C_SIGNAL='@t6g_mb_lib.t6g(sch_1):pwrgd_chb_cpu1_dimm';
NODE_NAME     J26 147
 '@T6G_MB_LIB.T6G(SCH_1):PAGE98_I22@PURE_QUANTA.SCONN288_DDR506112002KQ(CHIPS)':
 'PWR_GOOD||FAIL_N': CDS_PINID='\pwr_good||fail_n\';
NODE_NAME     R304 1
 '@T6G_MB_LIB.T6G(SCH_1):PAGE98_I188@PURE_QUANTA.Q_RES(CHIPS)':
 'A': CDS_PINID='A';
NODE_NAME     R104 2
 '@T6G_MB_LIB.T6G(SCH_1):PAGE98_I190@PURE_QUANTA.Q_RES(CHIPS)':
 'B': CDS_PINID='B';
NET_NAME
'PWRGD_CHC_CPU0_DIMM'
 '@T6G_MB_LIB.T6G(SCH_1):PWRGD_CHC_CPU0_DIMM':
 C_SIGNAL='@t6g_mb_lib.t6g(sch_1):pwrgd_chc_cpu0_dimm';
NODE_NAME     J17 147
 '@T6G_MB_LIB.T6G(SCH_1):PAGE87_I350@PURE_QUANTA.SCONN288_DDR506112002KQ(CHIPS)':
 'PWR_GOOD||FAIL_N': CDS_PINID='\pwr_good||fail_n\';
NODE_NAME     R293 1
 '@T6G_MB_LIB.T6G(SCH_1):PAGE87_I364@PURE_QUANTA.Q_RES(CHIPS)':
 'A': CDS_PINID='A';
NODE_NAME     R91 2
 '@T6G_MB_LIB.T6G(SCH_1):PAGE87_I365@PURE_QUANTA.Q_RES(CHIPS)':
 'B': CDS_PINID='B';
NET_NAME
'PWRGD_CHC_CPU1_DIMM'
 '@T6G_MB_LIB.T6G(SCH_1):PWRGD_CHC_CPU1_DIMM':
 C_SIGNAL='@t6g_mb_lib.t6g(sch_1):pwrgd_chc_cpu1_dimm';
NODE_NAME     J28 147
 '@T6G_MB_LIB.T6G(SCH_1):PAGE99_I22@PURE_QUANTA.SCONN288_DDR506112002KQ(CHIPS)':
 'PWR_GOOD||FAIL_N': CDS_PINID='\pwr_good||fail_n\';
NODE_NAME     R305 1
 '@T6G_MB_LIB.T6G(SCH_1):PAGE99_I188@PURE_QUANTA.Q_RES(CHIPS)':
 'A': CDS_PINID='A';
NODE_NAME     R105 2
 '@T6G_MB_LIB.T6G(SCH_1):PAGE99_I190@PURE_QUANTA.Q_RES(CHIPS)':
 'B': CDS_PINID='B';
NET_NAME
'PWRGD_CHD_CPU0_DIMM'
 '@T6G_MB_LIB.T6G(SCH_1):PWRGD_CHD_CPU0_DIMM':
 C_SIGNAL='@t6g_mb_lib.t6g(sch_1):pwrgd_chd_cpu0_dimm';
NODE_NAME     J19 147
 '@T6G_MB_LIB.T6G(SCH_1):PAGE88_I350@PURE_QUANTA.SCONN288_DDR506112002KQ(CHIPS)':
 'PWR_GOOD||FAIL_N': CDS_PINID='\pwr_good||fail_n\';
NODE_NAME     R92 2
 '@T6G_MB_LIB.T6G(SCH_1):PAGE88_I367@PURE_QUANTA.Q_RES(CHIPS)':
 'B': CDS_PINID='B';
NODE_NAME     R294 1
 '@T6G_MB_LIB.T6G(SCH_1):PAGE88_I369@PURE_QUANTA.Q_RES(CHIPS)':
 'A': CDS_PINID='A';
NET_NAME
'PWRGD_CHD_CPU1_DIMM'
 '@T6G_MB_LIB.T6G(SCH_1):PWRGD_CHD_CPU1_DIMM':
 C_SIGNAL='@t6g_mb_lib.t6g(sch_1):pwrgd_chd_cpu1_dimm';
NODE_NAME     J30 147
 '@T6G_MB_LIB.T6G(SCH_1):PAGE100_I52@PURE_QUANTA.SCONN288_DDR506112002KQ(CHIPS)':
 'PWR_GOOD||FAIL_N': CDS_PINID='\pwr_good||fail_n\';
NODE_NAME     R306 1
 '@T6G_MB_LIB.T6G(SCH_1):PAGE100_I188@PURE_QUANTA.Q_RES(CHIPS)':
 'A': CDS_PINID='A';
NODE_NAME     R106 2
 '@T6G_MB_LIB.T6G(SCH_1):PAGE100_I190@PURE_QUANTA.Q_RES(CHIPS)':
 'B': CDS_PINID='B';
NET_NAME
'PWRGD_CHE_CPU0_DIMM'
 '@T6G_MB_LIB.T6G(SCH_1):PWRGD_CHE_CPU0_DIMM':
 C_SIGNAL='@t6g_mb_lib.t6g(sch_1):pwrgd_che_cpu0_dimm';
NODE_NAME     J21 147
 '@T6G_MB_LIB.T6G(SCH_1):PAGE89_I348@PURE_QUANTA.SCONN288_DDR506112002KQ(CHIPS)':
 'PWR_GOOD||FAIL_N': CDS_PINID='\pwr_good||fail_n\';
NODE_NAME     R295 1
 '@T6G_MB_LIB.T6G(SCH_1):PAGE89_I362@PURE_QUANTA.Q_RES(CHIPS)':
 'A': CDS_PINID='A';
NODE_NAME     R93 2
 '@T6G_MB_LIB.T6G(SCH_1):PAGE89_I364@PURE_QUANTA.Q_RES(CHIPS)':
 'B': CDS_PINID='B';
NET_NAME
'PWRGD_CHE_CPU1_DIMM'
 '@T6G_MB_LIB.T6G(SCH_1):PWRGD_CHE_CPU1_DIMM':
 C_SIGNAL='@t6g_mb_lib.t6g(sch_1):pwrgd_che_cpu1_dimm';
NODE_NAME     J32 147
 '@T6G_MB_LIB.T6G(SCH_1):PAGE101_I52@PURE_QUANTA.SCONN288_DDR506112002KQ(CHIPS)':
 'PWR_GOOD||FAIL_N': CDS_PINID='\pwr_good||fail_n\';
NODE_NAME     R307 1
 '@T6G_MB_LIB.T6G(SCH_1):PAGE101_I188@PURE_QUANTA.Q_RES(CHIPS)':
 'A': CDS_PINID='A';
NODE_NAME     R107 2
 '@T6G_MB_LIB.T6G(SCH_1):PAGE101_I190@PURE_QUANTA.Q_RES(CHIPS)':
 'B': CDS_PINID='B';
NET_NAME
'PWRGD_CHF_CPU0_DIMM'
 '@T6G_MB_LIB.T6G(SCH_1):PWRGD_CHF_CPU0_DIMM':
 C_SIGNAL='@t6g_mb_lib.t6g(sch_1):pwrgd_chf_cpu0_dimm';
NODE_NAME     J23 147
 '@T6G_MB_LIB.T6G(SCH_1):PAGE90_I350@PURE_QUANTA.SCONN288_DDR506112002KQ(CHIPS)':
 'PWR_GOOD||FAIL_N': CDS_PINID='\pwr_good||fail_n\';
NODE_NAME     R296 1
 '@T6G_MB_LIB.T6G(SCH_1):PAGE90_I364@PURE_QUANTA.Q_RES(CHIPS)':
 'A': CDS_PINID='A';
NODE_NAME     R94 2
 '@T6G_MB_LIB.T6G(SCH_1):PAGE90_I365@PURE_QUANTA.Q_RES(CHIPS)':
 'B': CDS_PINID='B';
NET_NAME
'PWRGD_CHF_CPU1_DIMM'
 '@T6G_MB_LIB.T6G(SCH_1):PWRGD_CHF_CPU1_DIMM':
 C_SIGNAL='@t6g_mb_lib.t6g(sch_1):pwrgd_chf_cpu1_dimm';
NODE_NAME     J33 147
 '@T6G_MB_LIB.T6G(SCH_1):PAGE102_I22@PURE_QUANTA.SCONN288_DDR506112002KQ(CHIPS)':
 'PWR_GOOD||FAIL_N': CDS_PINID='\pwr_good||fail_n\';
NODE_NAME     R1183 1
 '@T6G_MB_LIB.T6G(SCH_1):PAGE102_I188@PURE_QUANTA.Q_RES(CHIPS)':
 'A': CDS_PINID='A';
NODE_NAME     R108 2
 '@T6G_MB_LIB.T6G(SCH_1):PAGE102_I190@PURE_QUANTA.Q_RES(CHIPS)':
 'B': CDS_PINID='B';
NET_NAME
'PWRGD_CHGL_CPU0'
 '@T6G_MB_LIB.T6G(SCH_1):PWRGD_CHGL_CPU0':
 C_SIGNAL='@t6g_mb_lib.t6g(sch_1):pwrgd_chgl_cpu0';
NODE_NAME     R297 2
 '@T6G_MB_LIB.T6G(SCH_1):PAGE91_I186@PURE_QUANTA.Q_RES(CHIPS)':
 'B': CDS_PINID='B';
NODE_NAME     R95 2
 '@T6G_MB_LIB.T6G(SCH_1):PAGE91_I190@PURE_QUANTA.Q_RES(CHIPS)':
 'B': CDS_PINID='B';
NODE_NAME     R298 2
 '@T6G_MB_LIB.T6G(SCH_1):PAGE92_I189@PURE_QUANTA.Q_RES(CHIPS)':
 'B': CDS_PINID='B';
NODE_NAME     R299 2
 '@T6G_MB_LIB.T6G(SCH_1):PAGE93_I188@PURE_QUANTA.Q_RES(CHIPS)':
 'B': CDS_PINID='B';
NODE_NAME     R300 2
 '@T6G_MB_LIB.T6G(SCH_1):PAGE94_I188@PURE_QUANTA.Q_RES(CHIPS)':
 'B': CDS_PINID='B';
NODE_NAME     R301 2
 '@T6G_MB_LIB.T6G(SCH_1):PAGE95_I188@PURE_QUANTA.Q_RES(CHIPS)':
 'B': CDS_PINID='B';
NODE_NAME     R302 2
 '@T6G_MB_LIB.T6G(SCH_1):PAGE96_I188@PURE_QUANTA.Q_RES(CHIPS)':
 'B': CDS_PINID='B';
NODE_NAME     R8038 2
 '@T6G_MB_LIB.T6G(SCH_1):PAGE91_I243@PURE_QUANTA.Q_RES(CHIPS)':
 'B': CDS_PINID='B';
NODE_NAME     R8083 1
 '@T6G_MB_LIB.T6G(SCH_1):PAGE91_I248@PURE_QUANTA.Q_RES(CHIPS)':
 'A': CDS_PINID='A';
NET_NAME
'PWRGD_CHGL_CPU0_R1'
 '@T6G_MB_LIB.T6G(SCH_1):PWRGD_CHGL_CPU0_R1':
 C_SIGNAL='@t6g_mb_lib.t6g(sch_1):pwrgd_chgl_cpu0_r1';
NODE_NAME     R8083 2
 '@T6G_MB_LIB.T6G(SCH_1):PAGE91_I248@PURE_QUANTA.Q_RES(CHIPS)':
 'B': CDS_PINID='B';
NODE_NAME     R8085 2
 '@T6G_MB_LIB.T6G(SCH_1):PAGE91_I249@PURE_QUANTA.Q_RES(CHIPS)':
 'B': CDS_PINID='B';
NODE_NAME     R8084 1
 '@T6G_MB_LIB.T6G(SCH_1):PAGE91_I250@PURE_QUANTA.Q_RES(CHIPS)':
 'A': CDS_PINID='A';
NODE_NAME     D8004 1
 '@T6G_MB_LIB.T6G(SCH_1):PAGE91_I251@PURE_QUANTA.SCHOTTKY_12(CHIPS)':
 'A': CDS_PINID='A';
NET_NAME
'PWRGD_CHGL_CPU0_R2'
 '@T6G_MB_LIB.T6G(SCH_1):PWRGD_CHGL_CPU0_R2':
 C_SIGNAL='@t6g_mb_lib.t6g(sch_1):pwrgd_chgl_cpu0_r2';
NODE_NAME     U18 Y1
 '@T6G_MB_LIB.T6G(SCH_1):PAGE81_I143@PURE_QUANTA.LCMXO3LF9400C5BG484C(CHIPS)':
 'PL29A': CDS_PINID='PL29A';
NODE_NAME     R8084 2
 '@T6G_MB_LIB.T6G(SCH_1):PAGE91_I250@PURE_QUANTA.Q_RES(CHIPS)':
 'B': CDS_PINID='B';
NET_NAME
'PWRGD_CHGL_CPU1'
 '@T6G_MB_LIB.T6G(SCH_1):PWRGD_CHGL_CPU1':
 C_SIGNAL='@t6g_mb_lib.t6g(sch_1):pwrgd_chgl_cpu1';
NODE_NAME     R1184 2
 '@T6G_MB_LIB.T6G(SCH_1):PAGE103_I188@PURE_QUANTA.Q_RES(CHIPS)':
 'B': CDS_PINID='B';
NODE_NAME     R109 2
 '@T6G_MB_LIB.T6G(SCH_1):PAGE103_I189@PURE_QUANTA.Q_RES(CHIPS)':
 'B': CDS_PINID='B';
NODE_NAME     R310 2
 '@T6G_MB_LIB.T6G(SCH_1):PAGE104_I189@PURE_QUANTA.Q_RES(CHIPS)':
 'B': CDS_PINID='B';
NODE_NAME     R311 2
 '@T6G_MB_LIB.T6G(SCH_1):PAGE105_I188@PURE_QUANTA.Q_RES(CHIPS)':
 'B': CDS_PINID='B';
NODE_NAME     R312 2
 '@T6G_MB_LIB.T6G(SCH_1):PAGE106_I188@PURE_QUANTA.Q_RES(CHIPS)':
 'B': CDS_PINID='B';
NODE_NAME     R313 2
 '@T6G_MB_LIB.T6G(SCH_1):PAGE107_I188@PURE_QUANTA.Q_RES(CHIPS)':
 'B': CDS_PINID='B';
NODE_NAME     R314 2
 '@T6G_MB_LIB.T6G(SCH_1):PAGE108_I188@PURE_QUANTA.Q_RES(CHIPS)':
 'B': CDS_PINID='B';
NODE_NAME     R8040 2
 '@T6G_MB_LIB.T6G(SCH_1):PAGE103_I245@PURE_QUANTA.Q_RES(CHIPS)':
 'B': CDS_PINID='B';
NODE_NAME     R8089 1
 '@T6G_MB_LIB.T6G(SCH_1):PAGE103_I249@PURE_QUANTA.Q_RES(CHIPS)':
 'A': CDS_PINID='A';
NET_NAME
'PWRGD_CHGL_CPU1_R1'
 '@T6G_MB_LIB.T6G(SCH_1):PWRGD_CHGL_CPU1_R1':
 C_SIGNAL='@t6g_mb_lib.t6g(sch_1):pwrgd_chgl_cpu1_r1';
NODE_NAME     R8089 2
 '@T6G_MB_LIB.T6G(SCH_1):PAGE103_I249@PURE_QUANTA.Q_RES(CHIPS)':
 'B': CDS_PINID='B';
NODE_NAME     R8091 2
 '@T6G_MB_LIB.T6G(SCH_1):PAGE103_I251@PURE_QUANTA.Q_RES(CHIPS)':
 'B': CDS_PINID='B';
NODE_NAME     R8090 1
 '@T6G_MB_LIB.T6G(SCH_1):PAGE103_I252@PURE_QUANTA.Q_RES(CHIPS)':
 'A': CDS_PINID='A';
NODE_NAME     D8006 1
 '@T6G_MB_LIB.T6G(SCH_1):PAGE103_I253@PURE_QUANTA.SCHOTTKY_12(CHIPS)':
 'A': CDS_PINID='A';
NET_NAME
'PWRGD_CHGL_CPU1_R2'
 '@T6G_MB_LIB.T6G(SCH_1):PWRGD_CHGL_CPU1_R2':
 C_SIGNAL='@t6g_mb_lib.t6g(sch_1):pwrgd_chgl_cpu1_r2';
NODE_NAME     U18 T6
 '@T6G_MB_LIB.T6G(SCH_1):PAGE81_I143@PURE_QUANTA.LCMXO3LF9400C5BG484C(CHIPS)':
 'PL26D': CDS_PINID='PL26D';
NODE_NAME     R8090 2
 '@T6G_MB_LIB.T6G(SCH_1):PAGE103_I252@PURE_QUANTA.Q_RES(CHIPS)':
 'B': CDS_PINID='B';
NET_NAME
'PWRGD_CHG_CPU0_DIMM0'
 '@T6G_MB_LIB.T6G(SCH_1):PWRGD_CHG_CPU0_DIMM0':
 C_SIGNAL='@t6g_mb_lib.t6g(sch_1):pwrgd_chg_cpu0_dimm0';
NODE_NAME     J16 147
 '@T6G_MB_LIB.T6G(SCH_1):PAGE91_I22@PURE_QUANTA.SCONN288_DDR506112002KQ(CHIPS)':
 'PWR_GOOD||FAIL_N': CDS_PINID='\pwr_good||fail_n\';
NODE_NAME     R297 1
 '@T6G_MB_LIB.T6G(SCH_1):PAGE91_I186@PURE_QUANTA.Q_RES(CHIPS)':
 'A': CDS_PINID='A';
NODE_NAME     R96 2
 '@T6G_MB_LIB.T6G(SCH_1):PAGE91_I187@PURE_QUANTA.Q_RES(CHIPS)':
 'B': CDS_PINID='B';
NET_NAME
'PWRGD_CHG_CPU1_DIMM0'
 '@T6G_MB_LIB.T6G(SCH_1):PWRGD_CHG_CPU1_DIMM0':
 C_SIGNAL='@t6g_mb_lib.t6g(sch_1):pwrgd_chg_cpu1_dimm0';
NODE_NAME     J102 147
 '@T6G_MB_LIB.T6G(SCH_1):PAGE103_I22@PURE_QUANTA.SCONN288_DDR506112002KQ(CHIPS)':
 'PWR_GOOD||FAIL_N': CDS_PINID='\pwr_good||fail_n\';
NODE_NAME     R1184 1
 '@T6G_MB_LIB.T6G(SCH_1):PAGE103_I188@PURE_QUANTA.Q_RES(CHIPS)':
 'A': CDS_PINID='A';
NODE_NAME     R110 2
 '@T6G_MB_LIB.T6G(SCH_1):PAGE103_I192@PURE_QUANTA.Q_RES(CHIPS)':
 'B': CDS_PINID='B';
NET_NAME
'PWRGD_CHH_CPU0_DIMM'
 '@T6G_MB_LIB.T6G(SCH_1):PWRGD_CHH_CPU0_DIMM':
 C_SIGNAL='@t6g_mb_lib.t6g(sch_1):pwrgd_chh_cpu0_dimm';
NODE_NAME     J69 147
 '@T6G_MB_LIB.T6G(SCH_1):PAGE92_I22@PURE_QUANTA.SCONN288_DDR506112002KQ(CHIPS)':
 'PWR_GOOD||FAIL_N': CDS_PINID='\pwr_good||fail_n\';
NODE_NAME     R298 1
 '@T6G_MB_LIB.T6G(SCH_1):PAGE92_I189@PURE_QUANTA.Q_RES(CHIPS)':
 'A': CDS_PINID='A';
NODE_NAME     R97 2
 '@T6G_MB_LIB.T6G(SCH_1):PAGE92_I191@PURE_QUANTA.Q_RES(CHIPS)':
 'B': CDS_PINID='B';
NET_NAME
'PWRGD_CHH_CPU1_DIMM'
 '@T6G_MB_LIB.T6G(SCH_1):PWRGD_CHH_CPU1_DIMM':
 C_SIGNAL='@t6g_mb_lib.t6g(sch_1):pwrgd_chh_cpu1_dimm';
NODE_NAME     J27 147
 '@T6G_MB_LIB.T6G(SCH_1):PAGE104_I22@PURE_QUANTA.SCONN288_DDR506112002KQ(CHIPS)':
 'PWR_GOOD||FAIL_N': CDS_PINID='\pwr_good||fail_n\';
NODE_NAME     R310 1
 '@T6G_MB_LIB.T6G(SCH_1):PAGE104_I189@PURE_QUANTA.Q_RES(CHIPS)':
 'A': CDS_PINID='A';
NODE_NAME     R111 2
 '@T6G_MB_LIB.T6G(SCH_1):PAGE104_I190@PURE_QUANTA.Q_RES(CHIPS)':
 'B': CDS_PINID='B';
NET_NAME
'PWRGD_CHI_CPU0_DIMM'
 '@T6G_MB_LIB.T6G(SCH_1):PWRGD_CHI_CPU0_DIMM':
 C_SIGNAL='@t6g_mb_lib.t6g(sch_1):pwrgd_chi_cpu0_dimm';
NODE_NAME     J18 147
 '@T6G_MB_LIB.T6G(SCH_1):PAGE93_I22@PURE_QUANTA.SCONN288_DDR506112002KQ(CHIPS)':
 'PWR_GOOD||FAIL_N': CDS_PINID='\pwr_good||fail_n\';
NODE_NAME     R299 1
 '@T6G_MB_LIB.T6G(SCH_1):PAGE93_I188@PURE_QUANTA.Q_RES(CHIPS)':
 'A': CDS_PINID='A';
NODE_NAME     R98 2
 '@T6G_MB_LIB.T6G(SCH_1):PAGE93_I189@PURE_QUANTA.Q_RES(CHIPS)':
 'B': CDS_PINID='B';
NET_NAME
'PWRGD_CHI_CPU1_DIMM'
 '@T6G_MB_LIB.T6G(SCH_1):PWRGD_CHI_CPU1_DIMM':
 C_SIGNAL='@t6g_mb_lib.t6g(sch_1):pwrgd_chi_cpu1_dimm';
NODE_NAME     J100 147
 '@T6G_MB_LIB.T6G(SCH_1):PAGE105_I22@PURE_QUANTA.SCONN288_DDR506112002KQ(CHIPS)':
 'PWR_GOOD||FAIL_N': CDS_PINID='\pwr_good||fail_n\';
NODE_NAME     R311 1
 '@T6G_MB_LIB.T6G(SCH_1):PAGE105_I188@PURE_QUANTA.Q_RES(CHIPS)':
 'A': CDS_PINID='A';
NODE_NAME     R112 2
 '@T6G_MB_LIB.T6G(SCH_1):PAGE105_I190@PURE_QUANTA.Q_RES(CHIPS)':
 'B': CDS_PINID='B';
NET_NAME
'PWRGD_CHJ_CPU0_DIMM'
 '@T6G_MB_LIB.T6G(SCH_1):PWRGD_CHJ_CPU0_DIMM':
 C_SIGNAL='@t6g_mb_lib.t6g(sch_1):pwrgd_chj_cpu0_dimm';
NODE_NAME     J68 147
 '@T6G_MB_LIB.T6G(SCH_1):PAGE94_I22@PURE_QUANTA.SCONN288_DDR506112002KQ(CHIPS)':
 'PWR_GOOD||FAIL_N': CDS_PINID='\pwr_good||fail_n\';
NODE_NAME     R300 1
 '@T6G_MB_LIB.T6G(SCH_1):PAGE94_I188@PURE_QUANTA.Q_RES(CHIPS)':
 'A': CDS_PINID='A';
NODE_NAME     R99 2
 '@T6G_MB_LIB.T6G(SCH_1):PAGE94_I189@PURE_QUANTA.Q_RES(CHIPS)':
 'B': CDS_PINID='B';
NET_NAME
'PWRGD_CHJ_CPU1_DIMM'
 '@T6G_MB_LIB.T6G(SCH_1):PWRGD_CHJ_CPU1_DIMM':
 C_SIGNAL='@t6g_mb_lib.t6g(sch_1):pwrgd_chj_cpu1_dimm';
NODE_NAME     J29 147
 '@T6G_MB_LIB.T6G(SCH_1):PAGE106_I22@PURE_QUANTA.SCONN288_DDR506112002KQ(CHIPS)':
 'PWR_GOOD||FAIL_N': CDS_PINID='\pwr_good||fail_n\';
NODE_NAME     R312 1
 '@T6G_MB_LIB.T6G(SCH_1):PAGE106_I188@PURE_QUANTA.Q_RES(CHIPS)':
 'A': CDS_PINID='A';
NODE_NAME     R113 2
 '@T6G_MB_LIB.T6G(SCH_1):PAGE106_I190@PURE_QUANTA.Q_RES(CHIPS)':
 'B': CDS_PINID='B';
NET_NAME
'PWRGD_CHK_CPU0_DIMM'
 '@T6G_MB_LIB.T6G(SCH_1):PWRGD_CHK_CPU0_DIMM':
 C_SIGNAL='@t6g_mb_lib.t6g(sch_1):pwrgd_chk_cpu0_dimm';
NODE_NAME     J20 147
 '@T6G_MB_LIB.T6G(SCH_1):PAGE95_I22@PURE_QUANTA.SCONN288_DDR506112002KQ(CHIPS)':
 'PWR_GOOD||FAIL_N': CDS_PINID='\pwr_good||fail_n\';
NODE_NAME     R301 1
 '@T6G_MB_LIB.T6G(SCH_1):PAGE95_I188@PURE_QUANTA.Q_RES(CHIPS)':
 'A': CDS_PINID='A';
NODE_NAME     R100 2
 '@T6G_MB_LIB.T6G(SCH_1):PAGE95_I189@PURE_QUANTA.Q_RES(CHIPS)':
 'B': CDS_PINID='B';
NET_NAME
'PWRGD_CHK_CPU1_DIMM'
 '@T6G_MB_LIB.T6G(SCH_1):PWRGD_CHK_CPU1_DIMM':
 C_SIGNAL='@t6g_mb_lib.t6g(sch_1):pwrgd_chk_cpu1_dimm';
NODE_NAME     J99 147
 '@T6G_MB_LIB.T6G(SCH_1):PAGE107_I22@PURE_QUANTA.SCONN288_DDR506112002KQ(CHIPS)':
 'PWR_GOOD||FAIL_N': CDS_PINID='\pwr_good||fail_n\';
NODE_NAME     R313 1
 '@T6G_MB_LIB.T6G(SCH_1):PAGE107_I188@PURE_QUANTA.Q_RES(CHIPS)':
 'A': CDS_PINID='A';
NODE_NAME     R114 2
 '@T6G_MB_LIB.T6G(SCH_1):PAGE107_I190@PURE_QUANTA.Q_RES(CHIPS)':
 'B': CDS_PINID='B';
NET_NAME
'PWRGD_CHL_CPU0_DIMM'
 '@T6G_MB_LIB.T6G(SCH_1):PWRGD_CHL_CPU0_DIMM':
 C_SIGNAL='@t6g_mb_lib.t6g(sch_1):pwrgd_chl_cpu0_dimm';
NODE_NAME     J67 147
 '@T6G_MB_LIB.T6G(SCH_1):PAGE96_I22@PURE_QUANTA.SCONN288_DDR506112002KQ(CHIPS)':
 'PWR_GOOD||FAIL_N': CDS_PINID='\pwr_good||fail_n\';
NODE_NAME     R302 1
 '@T6G_MB_LIB.T6G(SCH_1):PAGE96_I188@PURE_QUANTA.Q_RES(CHIPS)':
 'A': CDS_PINID='A';
NODE_NAME     R101 2
 '@T6G_MB_LIB.T6G(SCH_1):PAGE96_I189@PURE_QUANTA.Q_RES(CHIPS)':
 'B': CDS_PINID='B';
NET_NAME
'PWRGD_CHL_CPU1_DIMM'
 '@T6G_MB_LIB.T6G(SCH_1):PWRGD_CHL_CPU1_DIMM':
 C_SIGNAL='@t6g_mb_lib.t6g(sch_1):pwrgd_chl_cpu1_dimm';
NODE_NAME     J37 147
 '@T6G_MB_LIB.T6G(SCH_1):PAGE108_I22@PURE_QUANTA.SCONN288_DDR506112002KQ(CHIPS)':
 'PWR_GOOD||FAIL_N': CDS_PINID='\pwr_good||fail_n\';
NODE_NAME     R314 1
 '@T6G_MB_LIB.T6G(SCH_1):PAGE108_I188@PURE_QUANTA.Q_RES(CHIPS)':
 'A': CDS_PINID='A';
NODE_NAME     R115 2
 '@T6G_MB_LIB.T6G(SCH_1):PAGE108_I190@PURE_QUANTA.Q_RES(CHIPS)':
 'B': CDS_PINID='B';
NET_NAME
'PWRGD_CPU0_PWROK'
 '@T6G_MB_LIB.T6G(SCH_1):PWRGD_CPU0_PWROK':
 C_SIGNAL='@t6g_mb_lib.t6g(sch_1):pwrgd_cpu0_pwrok';
NODE_NAME     R702 1
 '@T6G_MB_LIB.T6G(SCH_1):PAGE77_I1@PURE_QUANTA.Q_RES(CHIPS)':
 'A': CDS_PINID='A';
NODE_NAME     U29 1
 '@T6G_MB_LIB.T6G(SCH_1):PAGE77_I15@PURE_QUANTA.SN74LVC2G07DCKR(CHIPS)':
 '1A': CDS_PINID='\1a\';
NODE_NAME     U29 3
 '@T6G_MB_LIB.T6G(SCH_1):PAGE77_I15@PURE_QUANTA.SN74LVC2G07DCKR(CHIPS)':
 '2A': CDS_PINID='\2a\';
NODE_NAME     R443 1
 '@T6G_MB_LIB.T6G(SCH_1):PAGE28_I53@PURE_QUANTA.Q_RES(CHIPS)':
 'A': CDS_PINID='A';
NODE_NAME     R242 1
 '@T6G_MB_LIB.T6G(SCH_1):PAGE80_I110@PURE_QUANTA.Q_RES(CHIPS)':
 'A': CDS_PINID='A';
NODE_NAME     U25 D69
 '@T6G_MB_LIB.T6G(SCH_1):PAGE28_I188@PURE_QUANTA.GENOA_SP5(CHIPS)':
 'PWROK||SVI_RST_L': CDS_PINID='\pwrok||svi_rst_l\';
NODE_NAME     R1422 1
 '@T6G_MB_LIB.T6G(SCH_1):PAGE84_I104@PURE_QUANTA.Q_RES(CHIPS)':
 'A': CDS_PINID='A';
NET_NAME
'PWRGD_CPU1_PWROK'
 '@T6G_MB_LIB.T6G(SCH_1):PWRGD_CPU1_PWROK':
 C_SIGNAL='@t6g_mb_lib.t6g(sch_1):pwrgd_cpu1_pwrok';
NODE_NAME     U26 D69
 '@T6G_MB_LIB.T6G(SCH_1):PAGE55_I182@PURE_QUANTA.GENOA_SP5(CHIPS)':
 'PWROK||SVI_RST_L': CDS_PINID='\pwrok||svi_rst_l\';
NODE_NAME     R703 1
 '@T6G_MB_LIB.T6G(SCH_1):PAGE77_I5@PURE_QUANTA.Q_RES(CHIPS)':
 'A': CDS_PINID='A';
NODE_NAME     U40 1
 '@T6G_MB_LIB.T6G(SCH_1):PAGE77_I21@PURE_QUANTA.SN74LVC2G07DCKR(CHIPS)':
 '1A': CDS_PINID='\1a\';
NODE_NAME     U40 3
 '@T6G_MB_LIB.T6G(SCH_1):PAGE77_I21@PURE_QUANTA.SN74LVC2G07DCKR(CHIPS)':
 '2A': CDS_PINID='\2a\';
NODE_NAME     R203 1
 '@T6G_MB_LIB.T6G(SCH_1):PAGE80_I106@PURE_QUANTA.Q_RES(CHIPS)':
 'A': CDS_PINID='A';
NODE_NAME     R557 2
 '@T6G_MB_LIB.T6G(SCH_1):PAGE55_I364@PURE_QUANTA.Q_RES(CHIPS)':
 'B': CDS_PINID='B';
NODE_NAME     R1422 2
 '@T6G_MB_LIB.T6G(SCH_1):PAGE84_I104@PURE_QUANTA.Q_RES(CHIPS)':
 'B': CDS_PINID='B';
NET_NAME
'PWRGD_OCP_SFF_PWR_GOOD'
 '@T6G_MB_LIB.T6G(SCH_1):PWRGD_OCP_SFF_PWR_GOOD':
 C_SIGNAL='@t6g_mb_lib.t6g(sch_1):pwrgd_ocp_sff_pwr_good';
NODE_NAME     U18 N4
 '@T6G_MB_LIB.T6G(SCH_1):PAGE81_I143@PURE_QUANTA.LCMXO3LF9400C5BG484C(CHIPS)':
 'PL18D': CDS_PINID='PL18D';
NODE_NAME     R6054 2
 '@T6G_MB_LIB.T6G(SCH_1):PAGE81_I83@PURE_QUANTA.Q_RES(CHIPS)':
 'B': CDS_PINID='B';
NET_NAME
'PWRGD_P0V9_RETIMER_CPU0'
 '@T6G_MB_LIB.T6G(SCH_1):PWRGD_P0V9_RETIMER_CPU0':
 C_SIGNAL='@t6g_mb_lib.t6g(sch_1):pwrgd_p0v9_retimer_cpu0';
NODE_NAME     R650 1
 '@T6G_MB_LIB.T6G(SCH_1):PAGE475_I119@PURE_QUANTA.Q_RES(CHIPS)':
 'A': CDS_PINID='A';
NODE_NAME     R6852 1
 '@T6G_MB_LIB.T6G(SCH_1):PAGE80_I360@PURE_QUANTA.Q_RES(CHIPS)':
 'A': CDS_PINID='A';
NET_NAME
'PWRGD_P0V9_RETIMER_CPU0_R'
 '@T6G_MB_LIB.T6G(SCH_1):PWRGD_P0V9_RETIMER_CPU0_R':
 C_SIGNAL='@t6g_mb_lib.t6g(sch_1):pwrgd_p0v9_retimer_cpu0_r';
NODE_NAME     PU6502 12
 '@T6G_MB_LIB.T6G(SCH_1):PAGE475_I42@PURE_QUANTA.ISL69260IRAZT(CHIPS)':
 'PG0': CDS_PINID='PG0';
NODE_NAME     C101 1
 '@T6G_MB_LIB.T6G(SCH_1):PAGE475_I118@PURE_QUANTA.Q_CAP(CHIPS)':
 'A': CDS_PINID='A';
NODE_NAME     R650 2
 '@T6G_MB_LIB.T6G(SCH_1):PAGE475_I119@PURE_QUANTA.Q_RES(CHIPS)':
 'B': CDS_PINID='B';
NODE_NAME     R643 2
 '@T6G_MB_LIB.T6G(SCH_1):PAGE475_I212@PURE_QUANTA.Q_RES(CHIPS)':
 'B': CDS_PINID='B';
NODE_NAME     R6860 2
 '@T6G_MB_LIB.T6G(SCH_1):PAGE475_I213@PURE_QUANTA.Q_RES(CHIPS)':
 'B': CDS_PINID='B';
NET_NAME
'PWRGD_P0V9_RETIMER_CPU0_R2'
 '@T6G_MB_LIB.T6G(SCH_1):PWRGD_P0V9_RETIMER_CPU0_R2':
 C_SIGNAL='@t6g_mb_lib.t6g(sch_1):pwrgd_p0v9_retimer_cpu0_r2';
NODE_NAME     U18 D19
 '@T6G_MB_LIB.T6G(SCH_1):PAGE80_I217@PURE_QUANTA.LCMXO3LF9400C5BG484C(CHIPS)':
 'PR3C': CDS_PINID='PR3C';
NODE_NAME     R6852 2
 '@T6G_MB_LIB.T6G(SCH_1):PAGE80_I360@PURE_QUANTA.Q_RES(CHIPS)':
 'B': CDS_PINID='B';
NET_NAME
'PWRGD_P0V9_RETIMER_CPU1'
 '@T6G_MB_LIB.T6G(SCH_1):PWRGD_P0V9_RETIMER_CPU1':
 C_SIGNAL='@t6g_mb_lib.t6g(sch_1):pwrgd_p0v9_retimer_cpu1';
NODE_NAME     R661 1
 '@T6G_MB_LIB.T6G(SCH_1):PAGE477_I39@PURE_QUANTA.Q_RES(CHIPS)':
 'A': CDS_PINID='A';
NODE_NAME     R6853 1
 '@T6G_MB_LIB.T6G(SCH_1):PAGE80_I362@PURE_QUANTA.Q_RES(CHIPS)':
 'A': CDS_PINID='A';
NET_NAME
'PWRGD_P0V9_RETIMER_CPU1_R'
 '@T6G_MB_LIB.T6G(SCH_1):PWRGD_P0V9_RETIMER_CPU1_R':
 C_SIGNAL='@t6g_mb_lib.t6g(sch_1):pwrgd_p0v9_retimer_cpu1_r';
NODE_NAME     R661 2
 '@T6G_MB_LIB.T6G(SCH_1):PAGE477_I39@PURE_QUANTA.Q_RES(CHIPS)':
 'B': CDS_PINID='B';
NODE_NAME     C107 1
 '@T6G_MB_LIB.T6G(SCH_1):PAGE477_I45@PURE_QUANTA.Q_CAP(CHIPS)':
 'A': CDS_PINID='A';
NODE_NAME     PU6510 12
 '@T6G_MB_LIB.T6G(SCH_1):PAGE477_I88@PURE_QUANTA.ISL69260IRAZT(CHIPS)':
 'PG0': CDS_PINID='PG0';
NODE_NAME     R656 2
 '@T6G_MB_LIB.T6G(SCH_1):PAGE477_I92@PURE_QUANTA.Q_RES(CHIPS)':
 'B': CDS_PINID='B';
NODE_NAME     R6861 2
 '@T6G_MB_LIB.T6G(SCH_1):PAGE477_I93@PURE_QUANTA.Q_RES(CHIPS)':
 'B': CDS_PINID='B';
NET_NAME
'PWRGD_P0V9_RETIMER_CPU1_R2'
 '@T6G_MB_LIB.T6G(SCH_1):PWRGD_P0V9_RETIMER_CPU1_R2':
 C_SIGNAL='@t6g_mb_lib.t6g(sch_1):pwrgd_p0v9_retimer_cpu1_r2';
NODE_NAME     U18 E20
 '@T6G_MB_LIB.T6G(SCH_1):PAGE80_I217@PURE_QUANTA.LCMXO3LF9400C5BG484C(CHIPS)':
 'PR4D': CDS_PINID='PR4D';
NODE_NAME     R6853 2
 '@T6G_MB_LIB.T6G(SCH_1):PAGE80_I362@PURE_QUANTA.Q_RES(CHIPS)':
 'B': CDS_PINID='B';
NET_NAME
'PWRGD_P12V_MEM'
 '@T6G_MB_LIB.T6G(SCH_1):PWRGD_P12V_MEM':
 C_SIGNAL='@t6g_mb_lib.t6g(sch_1):pwrgd_p12v_mem';
NODE_NAME     U38 4
 '@T6G_MB_LIB.T6G(SCH_1):PAGE264_I8@PURE_QUANTA.SN74LVC1G11DCKR(CHIPS)':
 'Y': CDS_PINID='Y';
NODE_NAME     R1363 1
 '@T6G_MB_LIB.T6G(SCH_1):PAGE264_I17@PURE_QUANTA.Q_RES(CHIPS)':
 'A': CDS_PINID='A';
NET_NAME
'PWRGD_P12V_MEM_CPU0'
 '@T6G_MB_LIB.T6G(SCH_1):PWRGD_P12V_MEM_CPU0':
 C_SIGNAL='@t6g_mb_lib.t6g(sch_1):pwrgd_p12v_mem_cpu0';
NODE_NAME     R1458 1
 '@T6G_MB_LIB.T6G(SCH_1):PAGE264_I6@PURE_QUANTA.Q_RES(CHIPS)':
 'A': CDS_PINID='A';
NODE_NAME     Q18 3
 '@T6G_MB_LIB.T6G(SCH_1):PAGE264_I36@PURE_QUANTA.BSS138DW7F(CHIPS)':
 'D2': CDS_PINID='D2';
NODE_NAME     R1457 2
 '@T6G_MB_LIB.T6G(SCH_1):PAGE264_I41@PURE_QUANTA.Q_RES(CHIPS)':
 'B': CDS_PINID='B';
NET_NAME
'PWRGD_P12V_MEM_CPU0_EN'
 '@T6G_MB_LIB.T6G(SCH_1):PWRGD_P12V_MEM_CPU0_EN':
 C_SIGNAL='@t6g_mb_lib.t6g(sch_1):pwrgd_p12v_mem_cpu0_en';
NODE_NAME     R1443 1
 '@T6G_MB_LIB.T6G(SCH_1):PAGE264_I27@PURE_QUANTA.Q_RES(CHIPS)':
 'A': CDS_PINID='A';
NODE_NAME     R1442 2
 '@T6G_MB_LIB.T6G(SCH_1):PAGE264_I30@PURE_QUANTA.Q_RES(CHIPS)':
 'B': CDS_PINID='B';
NODE_NAME     Q18 2
 '@T6G_MB_LIB.T6G(SCH_1):PAGE264_I36@PURE_QUANTA.BSS138DW7F(CHIPS)':
 'G1': CDS_PINID='G1';
NET_NAME
'PWRGD_P12V_MEM_CPU0_EN_N'
 '@T6G_MB_LIB.T6G(SCH_1):PWRGD_P12V_MEM_CPU0_EN_N':
 C_SIGNAL='@t6g_mb_lib.t6g(sch_1):pwrgd_p12v_mem_cpu0_en_n';
NODE_NAME     Q18 6
 '@T6G_MB_LIB.T6G(SCH_1):PAGE264_I36@PURE_QUANTA.BSS138DW7F(CHIPS)':
 'D1': CDS_PINID='D1';
NODE_NAME     Q18 5
 '@T6G_MB_LIB.T6G(SCH_1):PAGE264_I36@PURE_QUANTA.BSS138DW7F(CHIPS)':
 'G2': CDS_PINID='G2';
NODE_NAME     R1450 2
 '@T6G_MB_LIB.T6G(SCH_1):PAGE264_I39@PURE_QUANTA.Q_RES(CHIPS)':
 'B': CDS_PINID='B';
NET_NAME
'PWRGD_P12V_MEM_CPU0_R'
 '@T6G_MB_LIB.T6G(SCH_1):PWRGD_P12V_MEM_CPU0_R':
 C_SIGNAL='@t6g_mb_lib.t6g(sch_1):pwrgd_p12v_mem_cpu0_r';
NODE_NAME     R1458 2
 '@T6G_MB_LIB.T6G(SCH_1):PAGE264_I6@PURE_QUANTA.Q_RES(CHIPS)':
 'B': CDS_PINID='B';
NODE_NAME     U38 1
 '@T6G_MB_LIB.T6G(SCH_1):PAGE264_I8@PURE_QUANTA.SN74LVC1G11DCKR(CHIPS)':
 'A': CDS_PINID='A';
NET_NAME
'PWRGD_P12V_MEM_CPU1'
 '@T6G_MB_LIB.T6G(SCH_1):PWRGD_P12V_MEM_CPU1':
 C_SIGNAL='@t6g_mb_lib.t6g(sch_1):pwrgd_p12v_mem_cpu1';
NODE_NAME     R1459 1
 '@T6G_MB_LIB.T6G(SCH_1):PAGE264_I5@PURE_QUANTA.Q_RES(CHIPS)':
 'A': CDS_PINID='A';
NODE_NAME     Q19 3
 '@T6G_MB_LIB.T6G(SCH_1):PAGE264_I33@PURE_QUANTA.BSS138DW7F(CHIPS)':
 'D2': CDS_PINID='D2';
NODE_NAME     R1452 2
 '@T6G_MB_LIB.T6G(SCH_1):PAGE264_I43@PURE_QUANTA.Q_RES(CHIPS)':
 'B': CDS_PINID='B';
NET_NAME
'PWRGD_P12V_MEM_CPU1_EN'
 '@T6G_MB_LIB.T6G(SCH_1):PWRGD_P12V_MEM_CPU1_EN':
 C_SIGNAL='@t6g_mb_lib.t6g(sch_1):pwrgd_p12v_mem_cpu1_en';
NODE_NAME     R1441 1
 '@T6G_MB_LIB.T6G(SCH_1):PAGE264_I24@PURE_QUANTA.Q_RES(CHIPS)':
 'A': CDS_PINID='A';
NODE_NAME     R1440 2
 '@T6G_MB_LIB.T6G(SCH_1):PAGE264_I25@PURE_QUANTA.Q_RES(CHIPS)':
 'B': CDS_PINID='B';
NODE_NAME     Q19 2
 '@T6G_MB_LIB.T6G(SCH_1):PAGE264_I33@PURE_QUANTA.BSS138DW7F(CHIPS)':
 'G1': CDS_PINID='G1';
NET_NAME
'PWRGD_P12V_MEM_CPU1_EN_N'
 '@T6G_MB_LIB.T6G(SCH_1):PWRGD_P12V_MEM_CPU1_EN_N':
 C_SIGNAL='@t6g_mb_lib.t6g(sch_1):pwrgd_p12v_mem_cpu1_en_n';
NODE_NAME     R1449 2
 '@T6G_MB_LIB.T6G(SCH_1):PAGE264_I26@PURE_QUANTA.Q_RES(CHIPS)':
 'B': CDS_PINID='B';
NODE_NAME     Q19 6
 '@T6G_MB_LIB.T6G(SCH_1):PAGE264_I33@PURE_QUANTA.BSS138DW7F(CHIPS)':
 'D1': CDS_PINID='D1';
NODE_NAME     Q19 5
 '@T6G_MB_LIB.T6G(SCH_1):PAGE264_I33@PURE_QUANTA.BSS138DW7F(CHIPS)':
 'G2': CDS_PINID='G2';
NET_NAME
'PWRGD_P12V_MEM_CPU1_R'
 '@T6G_MB_LIB.T6G(SCH_1):PWRGD_P12V_MEM_CPU1_R':
 C_SIGNAL='@t6g_mb_lib.t6g(sch_1):pwrgd_p12v_mem_cpu1_r';
NODE_NAME     R1459 2
 '@T6G_MB_LIB.T6G(SCH_1):PAGE264_I5@PURE_QUANTA.Q_RES(CHIPS)':
 'B': CDS_PINID='B';
NODE_NAME     U38 3
 '@T6G_MB_LIB.T6G(SCH_1):PAGE264_I8@PURE_QUANTA.SN74LVC1G11DCKR(CHIPS)':
 'B': CDS_PINID='B';
NET_NAME
'PWRGD_P12V_MEM_R'
 '@T6G_MB_LIB.T6G(SCH_1):PWRGD_P12V_MEM_R':
 C_SIGNAL='@t6g_mb_lib.t6g(sch_1):pwrgd_p12v_mem_r';
NODE_NAME     U18 N19
 '@T6G_MB_LIB.T6G(SCH_1):PAGE80_I217@PURE_QUANTA.LCMXO3LF9400C5BG484C(CHIPS)':
 'PR19D': CDS_PINID='PR19D';
NODE_NAME     R1363 2
 '@T6G_MB_LIB.T6G(SCH_1):PAGE264_I17@PURE_QUANTA.Q_RES(CHIPS)':
 'B': CDS_PINID='B';
NODE_NAME     C5014 1
 '@T6G_MB_LIB.T6G(SCH_1):PAGE264_I49@PURE_QUANTA.Q_CAP(CHIPS)':
 'A': CDS_PINID='A';
NET_NAME
'PWRGD_P1V2_AUX'
 '@T6G_MB_LIB.T6G(SCH_1):PWRGD_P1V2_AUX':
 C_SIGNAL='@t6g_mb_lib.t6g(sch_1):pwrgd_p1v2_aux';
NODE_NAME     PU6001 9
 '@T6G_MB_LIB.T6G(SCH_1):PAGE380_I16@PURE_QUANTA.MPQ8626GDZ(CHIPS)':
 'PGOOD': CDS_PINID='PGOOD';
NODE_NAME     R6244 2
 '@T6G_MB_LIB.T6G(SCH_1):PAGE380_I19@PURE_QUANTA.Q_RES(CHIPS)':
 'B': CDS_PINID='B';
NODE_NAME     R6241 1
 '@T6G_MB_LIB.T6G(SCH_1):PAGE380_I44@PURE_QUANTA.Q_RES(CHIPS)':
 'A': CDS_PINID='A';
NET_NAME
'PWRGD_P1V2_AUX_R'
 '@T6G_MB_LIB.T6G(SCH_1):PWRGD_P1V2_AUX_R':
 C_SIGNAL='@t6g_mb_lib.t6g(sch_1):pwrgd_p1v2_aux_r';
NODE_NAME     U18 Y9
 '@T6G_MB_LIB.T6G(SCH_1):PAGE80_I216@PURE_QUANTA.LCMXO3LF9400C5BG484C(CHIPS)':
 'PB21C': CDS_PINID='PB21C';
NODE_NAME     R6241 2
 '@T6G_MB_LIB.T6G(SCH_1):PAGE380_I44@PURE_QUANTA.Q_RES(CHIPS)':
 'B': CDS_PINID='B';
NODE_NAME     Q6000 2
 '@T6G_MB_LIB.T6G(SCH_1):PAGE254_I47@PURE_QUANTA.MOSFET_NCH_DUAL(CHIPS)':
 'G1': CDS_PINID='G1';
NET_NAME
'PWRGD_P1V8_AUX'
 '@T6G_MB_LIB.T6G(SCH_1):PWRGD_P1V8_AUX':
 C_SIGNAL='@t6g_mb_lib.t6g(sch_1):pwrgd_p1v8_aux';
NODE_NAME     PU6000 9
 '@T6G_MB_LIB.T6G(SCH_1):PAGE315_I18@PURE_QUANTA.MPQ8626GDZ(CHIPS)':
 'PGOOD': CDS_PINID='PGOOD';
NODE_NAME     R6243 2
 '@T6G_MB_LIB.T6G(SCH_1):PAGE315_I32@PURE_QUANTA.Q_RES(CHIPS)':
 'B': CDS_PINID='B';
NODE_NAME     R214 1
 '@T6G_MB_LIB.T6G(SCH_1):PAGE315_I44@PURE_QUANTA.Q_RES(CHIPS)':
 'A': CDS_PINID='A';
NET_NAME
'PWRGD_P1V8_AUX_R'
 '@T6G_MB_LIB.T6G(SCH_1):PWRGD_P1V8_AUX_R':
 C_SIGNAL='@t6g_mb_lib.t6g(sch_1):pwrgd_p1v8_aux_r';
NODE_NAME     R2476 2
 '@T6G_MB_LIB.T6G(SCH_1):PAGE346_I70@PURE_QUANTA.Q_RES(CHIPS)':
 'B': CDS_PINID='B';
NODE_NAME     U18 Y8
 '@T6G_MB_LIB.T6G(SCH_1):PAGE80_I216@PURE_QUANTA.LCMXO3LF9400C5BG484C(CHIPS)':
 'PB18C': CDS_PINID='PB18C';
NODE_NAME     Q78 2
 '@T6G_MB_LIB.T6G(SCH_1):PAGE254_I24@PURE_QUANTA.MOSFET_NCH_DUAL(CHIPS)':
 'G1': CDS_PINID='G1';
NODE_NAME     R214 2
 '@T6G_MB_LIB.T6G(SCH_1):PAGE315_I44@PURE_QUANTA.Q_RES(CHIPS)':
 'B': CDS_PINID='B';
NODE_NAME     R6240 1
 '@T6G_MB_LIB.T6G(SCH_1):PAGE380_I40@PURE_QUANTA.Q_RES(CHIPS)':
 'A': CDS_PINID='A';
NODE_NAME     C6085 1
 '@T6G_MB_LIB.T6G(SCH_1):PAGE380_I41@PURE_QUANTA.Q_CAP(CHIPS)':
 'A': CDS_PINID='A';
NET_NAME
'PWRGD_P1V8_RETIMER_CPU0'
 '@T6G_MB_LIB.T6G(SCH_1):PWRGD_P1V8_RETIMER_CPU0':
 C_SIGNAL='@t6g_mb_lib.t6g(sch_1):pwrgd_p1v8_retimer_cpu0';
NODE_NAME     R6505 2
 '@T6G_MB_LIB.T6G(SCH_1):PAGE469_I28@PURE_QUANTA.Q_RES(CHIPS)':
 'B': CDS_PINID='B';
NODE_NAME     R6506 1
 '@T6G_MB_LIB.T6G(SCH_1):PAGE469_I37@PURE_QUANTA.Q_RES(CHIPS)':
 'A': CDS_PINID='A';
NODE_NAME     PU6500 9
 '@T6G_MB_LIB.T6G(SCH_1):PAGE469_I51@PURE_QUANTA.MPQ8633BGLEC838Z(CHIPS)':
 'PGOOD': CDS_PINID='PGOOD';
NET_NAME
'PWRGD_P1V8_RETIMER_CPU1'
 '@T6G_MB_LIB.T6G(SCH_1):PWRGD_P1V8_RETIMER_CPU1':
 C_SIGNAL='@t6g_mb_lib.t6g(sch_1):pwrgd_p1v8_retimer_cpu1';
NODE_NAME     R644 2
 '@T6G_MB_LIB.T6G(SCH_1):PAGE470_I29@PURE_QUANTA.Q_RES(CHIPS)':
 'B': CDS_PINID='B';
NODE_NAME     R645 1
 '@T6G_MB_LIB.T6G(SCH_1):PAGE470_I36@PURE_QUANTA.Q_RES(CHIPS)':
 'A': CDS_PINID='A';
NODE_NAME     PU6501 9
 '@T6G_MB_LIB.T6G(SCH_1):PAGE470_I51@PURE_QUANTA.MPQ8633BGLEC838Z(CHIPS)':
 'PGOOD': CDS_PINID='PGOOD';
NET_NAME
'PWRGD_P3V3_AUX'
 '@T6G_MB_LIB.T6G(SCH_1):PWRGD_P3V3_AUX':
 C_SIGNAL='@t6g_mb_lib.t6g(sch_1):pwrgd_p3v3_aux';
NODE_NAME     R6047 1
 '@T6G_MB_LIB.T6G(SCH_1):PAGE80_I34@PURE_QUANTA.Q_RES(CHIPS)':
 'A': CDS_PINID='A';
NODE_NAME     R6078 1
 '@T6G_MB_LIB.T6G(SCH_1):PAGE84_I61@PURE_QUANTA.Q_RES(CHIPS)':
 'A': CDS_PINID='A';
NODE_NAME     R6099 2
 '@T6G_MB_LIB.T6G(SCH_1):PAGE245_I67@PURE_QUANTA.Q_RES(CHIPS)':
 'B': CDS_PINID='B';
NODE_NAME     C5015 1
 '@T6G_MB_LIB.T6G(SCH_1):PAGE245_I68@PURE_QUANTA.Q_CAP(CHIPS)':
 'A': CDS_PINID='A';
NODE_NAME     R6119 1
 '@T6G_MB_LIB.T6G(SCH_1):PAGE315_I40@PURE_QUANTA.Q_RES(CHIPS)':
 'A': CDS_PINID='A';
NET_NAME
'PWRGD_P3V3_AUX_PDB'
 '@T6G_MB_LIB.T6G(SCH_1):PWRGD_P3V3_AUX_PDB':
 C_SIGNAL='@t6g_mb_lib.t6g(sch_1):pwrgd_p3v3_aux_pdb';
NODE_NAME     R4268 1
 '@T6G_MB_LIB.T6G(SCH_1):PAGE364_I41@PURE_QUANTA.Q_RES(CHIPS)':
 'A': CDS_PINID='A';
NODE_NAME     R6078 2
 '@T6G_MB_LIB.T6G(SCH_1):PAGE84_I61@PURE_QUANTA.Q_RES(CHIPS)':
 'B': CDS_PINID='B';
NET_NAME
'PWRGD_P3V3_AUX_PDB_BUF'
 '@T6G_MB_LIB.T6G(SCH_1):PWRGD_P3V3_AUX_PDB_BUF':
 C_SIGNAL='@t6g_mb_lib.t6g(sch_1):pwrgd_p3v3_aux_pdb_buf';
NODE_NAME     R4266 2
 '@T6G_MB_LIB.T6G(SCH_1):PAGE364_I48@PURE_QUANTA.Q_RES(CHIPS)':
 'B': CDS_PINID='B';
NODE_NAME     J45 B2
 '@T6G_MB_LIB.T6G(SCH_1):PAGE363_I466@PURE_QUANTA.CONN60_101062636003K02LF(CHIPS)':
 'B2': CDS_PINID='B2';
NET_NAME
'PWRGD_P3V3_AUX_PDB_BUF_R'
 '@T6G_MB_LIB.T6G(SCH_1):PWRGD_P3V3_AUX_PDB_BUF_R':
 C_SIGNAL='@t6g_mb_lib.t6g(sch_1):pwrgd_p3v3_aux_pdb_buf_r';
NODE_NAME     U308 6
 '@T6G_MB_LIB.T6G(SCH_1):PAGE364_I37@PURE_QUANTA.74LVC2G07DW7(CHIPS)':
 '1Y': CDS_PINID='\1y\';
NODE_NAME     R4265 1
 '@T6G_MB_LIB.T6G(SCH_1):PAGE364_I43@PURE_QUANTA.Q_RES(CHIPS)':
 'A': CDS_PINID='A';
NODE_NAME     R4264 2
 '@T6G_MB_LIB.T6G(SCH_1):PAGE364_I47@PURE_QUANTA.Q_RES(CHIPS)':
 'B': CDS_PINID='B';
NODE_NAME     R4266 1
 '@T6G_MB_LIB.T6G(SCH_1):PAGE364_I48@PURE_QUANTA.Q_RES(CHIPS)':
 'A': CDS_PINID='A';
NET_NAME
'PWRGD_P3V3_AUX_PDB_R'
 '@T6G_MB_LIB.T6G(SCH_1):PWRGD_P3V3_AUX_PDB_R':
 C_SIGNAL='@t6g_mb_lib.t6g(sch_1):pwrgd_p3v3_aux_pdb_r';
NODE_NAME     U308 1
 '@T6G_MB_LIB.T6G(SCH_1):PAGE364_I37@PURE_QUANTA.74LVC2G07DW7(CHIPS)':
 '1A': CDS_PINID='\1a\';
NODE_NAME     R4268 2
 '@T6G_MB_LIB.T6G(SCH_1):PAGE364_I41@PURE_QUANTA.Q_RES(CHIPS)':
 'B': CDS_PINID='B';
NET_NAME
'PWRGD_P3V3_AUX_R'
 '@T6G_MB_LIB.T6G(SCH_1):PWRGD_P3V3_AUX_R':
 C_SIGNAL='@t6g_mb_lib.t6g(sch_1):pwrgd_p3v3_aux_r';
NODE_NAME     R6047 2
 '@T6G_MB_LIB.T6G(SCH_1):PAGE80_I34@PURE_QUANTA.Q_RES(CHIPS)':
 'B': CDS_PINID='B';
NODE_NAME     U18 W8
 '@T6G_MB_LIB.T6G(SCH_1):PAGE80_I216@PURE_QUANTA.LCMXO3LF9400C5BG484C(CHIPS)':
 'PB16D': CDS_PINID='PB16D';
NET_NAME
'PWRGD_P3V3_AUX_R1'
 '@T6G_MB_LIB.T6G(SCH_1):PWRGD_P3V3_AUX_R1':
 C_SIGNAL='@t6g_mb_lib.t6g(sch_1):pwrgd_p3v3_aux_r1';
NODE_NAME     PU9 2
 '@T6G_MB_LIB.T6G(SCH_1):PAGE245_I21@PURE_QUANTA.NCP3284AMNTXG(CHIPS)':
 'PGOOD': CDS_PINID='PGOOD';
NODE_NAME     PR8073 2
 '@T6G_MB_LIB.T6G(SCH_1):PAGE245_I65@PURE_QUANTA.Q_RES(CHIPS)':
 'B': CDS_PINID='B';
NODE_NAME     R6099 1
 '@T6G_MB_LIB.T6G(SCH_1):PAGE245_I67@PURE_QUANTA.Q_RES(CHIPS)':
 'A': CDS_PINID='A';
NET_NAME
'PWRGD_P3V3_EN'
 '@T6G_MB_LIB.T6G(SCH_1):PWRGD_P3V3_EN':
 C_SIGNAL='@t6g_mb_lib.t6g(sch_1):pwrgd_p3v3_en';
NODE_NAME     Q27 2
 '@T6G_MB_LIB.T6G(SCH_1):PAGE273_I123@PURE_QUANTA.BSS138DW7F(CHIPS)':
 'G1': CDS_PINID='G1';
NODE_NAME     R6500 2
 '@T6G_MB_LIB.T6G(SCH_1):PAGE273_I136@PURE_QUANTA.Q_RES(CHIPS)':
 'B': CDS_PINID='B';
NET_NAME
'PWRGD_P3V3_EN_N'
 '@T6G_MB_LIB.T6G(SCH_1):PWRGD_P3V3_EN_N':
 C_SIGNAL='@t6g_mb_lib.t6g(sch_1):pwrgd_p3v3_en_n';
NODE_NAME     R1492 2
 '@T6G_MB_LIB.T6G(SCH_1):PAGE273_I120@PURE_QUANTA.Q_RES(CHIPS)':
 'B': CDS_PINID='B';
NODE_NAME     Q27 6
 '@T6G_MB_LIB.T6G(SCH_1):PAGE273_I123@PURE_QUANTA.BSS138DW7F(CHIPS)':
 'D1': CDS_PINID='D1';
NODE_NAME     Q27 5
 '@T6G_MB_LIB.T6G(SCH_1):PAGE273_I123@PURE_QUANTA.BSS138DW7F(CHIPS)':
 'G2': CDS_PINID='G2';
NET_NAME
'PWRGD_P3V3_EN_R'
 '@T6G_MB_LIB.T6G(SCH_1):PWRGD_P3V3_EN_R':
 C_SIGNAL='@t6g_mb_lib.t6g(sch_1):pwrgd_p3v3_en_r';
NODE_NAME     U6006 2
 '@T6G_MB_LIB.T6G(SCH_1):PAGE273_I131@PURE_QUANTA.APX80929SAG7(CHIPS)':
 'RESET_L': CDS_PINID='RESET_L';
NODE_NAME     R6500 1
 '@T6G_MB_LIB.T6G(SCH_1):PAGE273_I136@PURE_QUANTA.Q_RES(CHIPS)':
 'A': CDS_PINID='A';
NODE_NAME     R6501 1
 '@T6G_MB_LIB.T6G(SCH_1):PAGE273_I139@PURE_QUANTA.Q_RES(CHIPS)':
 'A': CDS_PINID='A';
NODE_NAME     R1491 2
 '@T6G_MB_LIB.T6G(SCH_1):PAGE273_I141@PURE_QUANTA.Q_RES(CHIPS)':
 'B': CDS_PINID='B';
NET_NAME
'PWRGD_P3V3_R1'
 '@T6G_MB_LIB.T6G(SCH_1):PWRGD_P3V3_R1':
 C_SIGNAL='@t6g_mb_lib.t6g(sch_1):pwrgd_p3v3_r1';
NODE_NAME     Q27 3
 '@T6G_MB_LIB.T6G(SCH_1):PAGE273_I123@PURE_QUANTA.BSS138DW7F(CHIPS)':
 'D2': CDS_PINID='D2';
NODE_NAME     R1493 2
 '@T6G_MB_LIB.T6G(SCH_1):PAGE273_I125@PURE_QUANTA.Q_RES(CHIPS)':
 'B': CDS_PINID='B';
NODE_NAME     R1362 1
 '@T6G_MB_LIB.T6G(SCH_1):PAGE273_I130@PURE_QUANTA.Q_RES(CHIPS)':
 'A': CDS_PINID='A';
NET_NAME
'PWRGD_P3V3_R2'
 '@T6G_MB_LIB.T6G(SCH_1):PWRGD_P3V3_R2':
 C_SIGNAL='@t6g_mb_lib.t6g(sch_1):pwrgd_p3v3_r2';
NODE_NAME     U18 M16
 '@T6G_MB_LIB.T6G(SCH_1):PAGE80_I217@PURE_QUANTA.LCMXO3LF9400C5BG484C(CHIPS)':
 'PR18A': CDS_PINID='PR18A';
NODE_NAME     R1362 2
 '@T6G_MB_LIB.T6G(SCH_1):PAGE273_I130@PURE_QUANTA.Q_RES(CHIPS)':
 'B': CDS_PINID='B';
NET_NAME
'PWRGD_P5V'
 '@T6G_MB_LIB.T6G(SCH_1):PWRGD_P5V':
 C_SIGNAL='@t6g_mb_lib.t6g(sch_1):pwrgd_p5v';
NODE_NAME     U18 A16
 '@T6G_MB_LIB.T6G(SCH_1):PAGE79_I94@PURE_QUANTA.LCMXO3LF9400C5BG484C(CHIPS)':
 'PT39A': CDS_PINID='PT39A';
NODE_NAME     R439 1
 '@T6G_MB_LIB.T6G(SCH_1):PAGE79_I144@PURE_QUANTA.Q_RES(CHIPS)':
 'A': CDS_PINID='A';
NET_NAME
'PWRGD_P5V_AUX'
 '@T6G_MB_LIB.T6G(SCH_1):PWRGD_P5V_AUX':
 C_SIGNAL='@t6g_mb_lib.t6g(sch_1):pwrgd_p5v_aux';
NODE_NAME     R1571 1
 '@T6G_MB_LIB.T6G(SCH_1):PAGE245_I11@PURE_QUANTA.Q_RES(CHIPS)':
 'A': CDS_PINID='A';
NODE_NAME     R2316 2
 '@T6G_MB_LIB.T6G(SCH_1):PAGE244_I26@PURE_QUANTA.Q_RES(CHIPS)':
 'B': CDS_PINID='B';
NODE_NAME     R2343 2
 '@T6G_MB_LIB.T6G(SCH_1):PAGE84_I63@PURE_QUANTA.Q_RES(CHIPS)':
 'B': CDS_PINID='B';
NODE_NAME     Q50 2
 '@T6G_MB_LIB.T6G(SCH_1):PAGE84_I65@PURE_QUANTA.MOSFET_NCH_DUAL(CHIPS)':
 'G1': CDS_PINID='G1';
NET_NAME
'PWRGD_P5V_AUX_R'
 '@T6G_MB_LIB.T6G(SCH_1):PWRGD_P5V_AUX_R':
 C_SIGNAL='@t6g_mb_lib.t6g(sch_1):pwrgd_p5v_aux_r';
NODE_NAME     R2356 2
 '@T6G_MB_LIB.T6G(SCH_1):PAGE244_I25@PURE_QUANTA.Q_RES(CHIPS)':
 'B': CDS_PINID='B';
NODE_NAME     R2316 1
 '@T6G_MB_LIB.T6G(SCH_1):PAGE244_I26@PURE_QUANTA.Q_RES(CHIPS)':
 'A': CDS_PINID='A';
NODE_NAME     U326 9
 '@T6G_MB_LIB.T6G(SCH_1):PAGE244_I38@PURE_QUANTA.MPQ8633AGLEC807Z(CHIPS)':
 'PGOOD': CDS_PINID='PGOOD';
NET_NAME
'PWRGD_P5V_AUX_R1'
 '@T6G_MB_LIB.T6G(SCH_1):PWRGD_P5V_AUX_R1':
 C_SIGNAL='@t6g_mb_lib.t6g(sch_1):pwrgd_p5v_aux_r1';
NODE_NAME     Q50 6
 '@T6G_MB_LIB.T6G(SCH_1):PAGE84_I65@PURE_QUANTA.MOSFET_NCH_DUAL(CHIPS)':
 'D1': CDS_PINID='D1';
NODE_NAME     R2344 2
 '@T6G_MB_LIB.T6G(SCH_1):PAGE84_I67@PURE_QUANTA.Q_RES(CHIPS)':
 'B': CDS_PINID='B';
NODE_NAME     Q50 5
 '@T6G_MB_LIB.T6G(SCH_1):PAGE84_I73@PURE_QUANTA.MOSFET_NCH_DUAL(CHIPS)':
 'G2': CDS_PINID='G2';
NET_NAME
'PWRGD_P5V_AUX_R2'
 '@T6G_MB_LIB.T6G(SCH_1):PWRGD_P5V_AUX_R2':
 C_SIGNAL='@t6g_mb_lib.t6g(sch_1):pwrgd_p5v_aux_r2';
NODE_NAME     R2346 2
 '@T6G_MB_LIB.T6G(SCH_1):PAGE84_I70@PURE_QUANTA.Q_RES(CHIPS)':
 'B': CDS_PINID='B';
NODE_NAME     Q50 3
 '@T6G_MB_LIB.T6G(SCH_1):PAGE84_I73@PURE_QUANTA.MOSFET_NCH_DUAL(CHIPS)':
 'D2': CDS_PINID='D2';
NODE_NAME     R6118 2
 '@T6G_MB_LIB.T6G(SCH_1):PAGE84_I103@PURE_QUANTA.Q_RES(CHIPS)':
 'B': CDS_PINID='B';
NET_NAME
'PWRGD_P5V_AUX_R3'
 '@T6G_MB_LIB.T6G(SCH_1):PWRGD_P5V_AUX_R3':
 C_SIGNAL='@t6g_mb_lib.t6g(sch_1):pwrgd_p5v_aux_r3';
NODE_NAME     U18 U4
 '@T6G_MB_LIB.T6G(SCH_1):PAGE81_I143@PURE_QUANTA.LCMXO3LF9400C5BG484C(CHIPS)':
 'PL27D': CDS_PINID='PL27D';
NODE_NAME     C8005 1
 '@T6G_MB_LIB.T6G(SCH_1):PAGE84_I101@PURE_QUANTA.Q_CAP(CHIPS)':
 'A': CDS_PINID='A';
NODE_NAME     R6118 1
 '@T6G_MB_LIB.T6G(SCH_1):PAGE84_I103@PURE_QUANTA.Q_RES(CHIPS)':
 'A': CDS_PINID='A';
NET_NAME
'PWRGD_P5V_N'
 '@T6G_MB_LIB.T6G(SCH_1):PWRGD_P5V_N':
 C_SIGNAL='@t6g_mb_lib.t6g(sch_1):pwrgd_p5v_n';
NODE_NAME     Q1 5
 '@T6G_MB_LIB.T6G(SCH_1):PAGE273_I98@PURE_QUANTA.MOSFET_NCH_DUAL(CHIPS)':
 'G2': CDS_PINID='G2';
NODE_NAME     R494 2
 '@T6G_MB_LIB.T6G(SCH_1):PAGE273_I102@PURE_QUANTA.Q_RES(CHIPS)':
 'B': CDS_PINID='B';
NET_NAME
'PWRGD_P5V_R'
 '@T6G_MB_LIB.T6G(SCH_1):PWRGD_P5V_R':
 C_SIGNAL='@t6g_mb_lib.t6g(sch_1):pwrgd_p5v_r';
NODE_NAME     U100 1
 '@T6G_MB_LIB.T6G(SCH_1):PAGE273_I77@PURE_QUANTA.RT9818C44GV(CHIPS)':
 'RESET#': CDS_PINID='\reset#\';
NODE_NAME     R479 2
 '@T6G_MB_LIB.T6G(SCH_1):PAGE273_I83@PURE_QUANTA.Q_RES(CHIPS)':
 'B': CDS_PINID='B';
NODE_NAME     R480 1
 '@T6G_MB_LIB.T6G(SCH_1):PAGE273_I84@PURE_QUANTA.Q_RES(CHIPS)':
 'A': CDS_PINID='A';
NODE_NAME     R490 1
 '@T6G_MB_LIB.T6G(SCH_1):PAGE273_I88@PURE_QUANTA.Q_RES(CHIPS)':
 'A': CDS_PINID='A';
NODE_NAME     R482 1
 '@T6G_MB_LIB.T6G(SCH_1):PAGE273_I96@PURE_QUANTA.Q_RES(CHIPS)':
 'A': CDS_PINID='A';
NET_NAME
'PWRGD_P5V_R1'
 '@T6G_MB_LIB.T6G(SCH_1):PWRGD_P5V_R1':
 C_SIGNAL='@t6g_mb_lib.t6g(sch_1):pwrgd_p5v_r1';
NODE_NAME     R482 2
 '@T6G_MB_LIB.T6G(SCH_1):PAGE273_I96@PURE_QUANTA.Q_RES(CHIPS)':
 'B': CDS_PINID='B';
NODE_NAME     Q1 2
 '@T6G_MB_LIB.T6G(SCH_1):PAGE273_I97@PURE_QUANTA.MOSFET_NCH_DUAL(CHIPS)':
 'G1': CDS_PINID='G1';
NET_NAME
'PWRGD_P5V_R2'
 '@T6G_MB_LIB.T6G(SCH_1):PWRGD_P5V_R2':
 C_SIGNAL='@t6g_mb_lib.t6g(sch_1):pwrgd_p5v_r2';
NODE_NAME     Q1 3
 '@T6G_MB_LIB.T6G(SCH_1):PAGE273_I98@PURE_QUANTA.MOSFET_NCH_DUAL(CHIPS)':
 'D2': CDS_PINID='D2';
NODE_NAME     R552 2
 '@T6G_MB_LIB.T6G(SCH_1):PAGE273_I104@PURE_QUANTA.Q_RES(CHIPS)':
 'B': CDS_PINID='B';
NODE_NAME     R439 2
 '@T6G_MB_LIB.T6G(SCH_1):PAGE79_I144@PURE_QUANTA.Q_RES(CHIPS)':
 'B': CDS_PINID='B';
NET_NAME
'PWRGD_P5V_R_N'
 '@T6G_MB_LIB.T6G(SCH_1):PWRGD_P5V_R_N':
 C_SIGNAL='@t6g_mb_lib.t6g(sch_1):pwrgd_p5v_r_n';
NODE_NAME     Q1 6
 '@T6G_MB_LIB.T6G(SCH_1):PAGE273_I97@PURE_QUANTA.MOSFET_NCH_DUAL(CHIPS)':
 'D1': CDS_PINID='D1';
NODE_NAME     R492 2
 '@T6G_MB_LIB.T6G(SCH_1):PAGE273_I99@PURE_QUANTA.Q_RES(CHIPS)':
 'B': CDS_PINID='B';
NODE_NAME     R494 1
 '@T6G_MB_LIB.T6G(SCH_1):PAGE273_I102@PURE_QUANTA.Q_RES(CHIPS)':
 'A': CDS_PINID='A';
NET_NAME
'PWRGD_PS_PWROK'
 '@T6G_MB_LIB.T6G(SCH_1):PWRGD_PS_PWROK':
 C_SIGNAL='@t6g_mb_lib.t6g(sch_1):pwrgd_ps_pwrok';
NODE_NAME     R1816 1
 '@T6G_MB_LIB.T6G(SCH_1):PAGE348_I32@PURE_QUANTA.Q_RES(CHIPS)':
 'A': CDS_PINID='A';
NODE_NAME     R3048 2
 '@T6G_MB_LIB.T6G(SCH_1):PAGE368_I7@PURE_QUANTA.Q_RES(CHIPS)':
 'B': CDS_PINID='B';
NET_NAME
'PWRGD_PS_PWROK_PLD'
 '@T6G_MB_LIB.T6G(SCH_1):PWRGD_PS_PWROK_PLD':
 C_SIGNAL='@t6g_mb_lib.t6g(sch_1):pwrgd_ps_pwrok_pld';
NODE_NAME     Q144 2
 '@T6G_MB_LIB.T6G(SCH_1):PAGE368_I3@PURE_QUANTA.MOSFET_NCH_DUAL(CHIPS)':
 'G1': CDS_PINID='G1';
NODE_NAME     R3047 2
 '@T6G_MB_LIB.T6G(SCH_1):PAGE368_I8@PURE_QUANTA.Q_RES(CHIPS)':
 'B': CDS_PINID='B';
NODE_NAME     Q78 5
 '@T6G_MB_LIB.T6G(SCH_1):PAGE254_I18@PURE_QUANTA.MOSFET_NCH_DUAL(CHIPS)':
 'G2': CDS_PINID='G2';
NET_NAME
'PWRGD_PS_PWROK_PLD_ISO'
 '@T6G_MB_LIB.T6G(SCH_1):PWRGD_PS_PWROK_PLD_ISO':
 C_SIGNAL='@t6g_mb_lib.t6g(sch_1):pwrgd_ps_pwrok_pld_iso';
NODE_NAME     Q144 3
 '@T6G_MB_LIB.T6G(SCH_1):PAGE368_I10@PURE_QUANTA.MOSFET_NCH_DUAL(CHIPS)':
 'D2': CDS_PINID='D2';
NODE_NAME     R4605 2
 '@T6G_MB_LIB.T6G(SCH_1):PAGE368_I11@PURE_QUANTA.Q_RES(CHIPS)':
 'B': CDS_PINID='B';
NODE_NAME     R9446 1
 '@T6G_MB_LIB.T6G(SCH_1):PAGE368_I13@PURE_QUANTA.Q_RES(CHIPS)':
 'A': CDS_PINID='A';
NET_NAME
'PWRGD_PS_PWROK_PLD_ISO_R'
 '@T6G_MB_LIB.T6G(SCH_1):PWRGD_PS_PWROK_PLD_ISO_R':
 C_SIGNAL='@t6g_mb_lib.t6g(sch_1):pwrgd_ps_pwrok_pld_iso_r';
NODE_NAME     R9446 2
 '@T6G_MB_LIB.T6G(SCH_1):PAGE368_I13@PURE_QUANTA.Q_RES(CHIPS)':
 'B': CDS_PINID='B';
NODE_NAME     U18 F8
 '@T6G_MB_LIB.T6G(SCH_1):PAGE79_I94@PURE_QUANTA.LCMXO3LF9400C5BG484C(CHIPS)':
 'PT11C': CDS_PINID='PT11C';
NET_NAME
'PWRGD_PS_PWROK_PLD_N'
 '@T6G_MB_LIB.T6G(SCH_1):PWRGD_PS_PWROK_PLD_N':
 C_SIGNAL='@t6g_mb_lib.t6g(sch_1):pwrgd_ps_pwrok_pld_n';
NODE_NAME     Q144 6
 '@T6G_MB_LIB.T6G(SCH_1):PAGE368_I3@PURE_QUANTA.MOSFET_NCH_DUAL(CHIPS)':
 'D1': CDS_PINID='D1';
NODE_NAME     R4604 2
 '@T6G_MB_LIB.T6G(SCH_1):PAGE368_I5@PURE_QUANTA.Q_RES(CHIPS)':
 'B': CDS_PINID='B';
NODE_NAME     Q144 5
 '@T6G_MB_LIB.T6G(SCH_1):PAGE368_I10@PURE_QUANTA.MOSFET_NCH_DUAL(CHIPS)':
 'G2': CDS_PINID='G2';
NET_NAME
'PWRGD_PS_PWROK_R'
 '@T6G_MB_LIB.T6G(SCH_1):PWRGD_PS_PWROK_R':
 C_SIGNAL='@t6g_mb_lib.t6g(sch_1):pwrgd_ps_pwrok_r';
NODE_NAME     R1816 2
 '@T6G_MB_LIB.T6G(SCH_1):PAGE348_I32@PURE_QUANTA.Q_RES(CHIPS)':
 'B': CDS_PINID='B';
NODE_NAME     J41 A44
 '@T6G_MB_LIB.T6G(SCH_1):PAGE348_I176@PURE_QUANTA.SCONN168_ME1016810202011(CHIPS)':
 'PERN8': CDS_PINID='PERN8';
NET_NAME
'PWRGD_PVDD11_S3_P0'
 '@T6G_MB_LIB.T6G(SCH_1):PWRGD_PVDD11_S3_P0':
 C_SIGNAL='@t6g_mb_lib.t6g(sch_1):pwrgd_pvdd11_s3_p0';
NODE_NAME     R228 1
 '@T6G_MB_LIB.T6G(SCH_1):PAGE80_I66@PURE_QUANTA.Q_RES(CHIPS)':
 'A': CDS_PINID='A';
NODE_NAME     R122 1
 '@T6G_MB_LIB.T6G(SCH_1):PAGE182_I44@PURE_QUANTA.Q_RES(CHIPS)':
 'A': CDS_PINID='A';
NET_NAME
'PWRGD_PVDD11_S3_P0_R'
 '@T6G_MB_LIB.T6G(SCH_1):PWRGD_PVDD11_S3_P0_R':
 C_SIGNAL='@t6g_mb_lib.t6g(sch_1):pwrgd_pvdd11_s3_p0_r';
NODE_NAME     C196 1
 '@T6G_MB_LIB.T6G(SCH_1):PAGE182_I47@PURE_QUANTA.Q_CAP(CHIPS)':
 'A': CDS_PINID='A';
NODE_NAME     PU21 12
 '@T6G_MB_LIB.T6G(SCH_1):PAGE182_I24@PURE_QUANTA.RAA229621GNPHA0(CHIPS)':
 'PG0': CDS_PINID='PG0';
NODE_NAME     R117 2
 '@T6G_MB_LIB.T6G(SCH_1):PAGE182_I38@PURE_QUANTA.Q_RES(CHIPS)':
 'B': CDS_PINID='B';
NODE_NAME     R122 2
 '@T6G_MB_LIB.T6G(SCH_1):PAGE182_I44@PURE_QUANTA.Q_RES(CHIPS)':
 'B': CDS_PINID='B';
NET_NAME
'PWRGD_PVDD11_S3_P1'
 '@T6G_MB_LIB.T6G(SCH_1):PWRGD_PVDD11_S3_P1':
 C_SIGNAL='@t6g_mb_lib.t6g(sch_1):pwrgd_pvdd11_s3_p1';
NODE_NAME     R280 1
 '@T6G_MB_LIB.T6G(SCH_1):PAGE80_I59@PURE_QUANTA.Q_RES(CHIPS)':
 'A': CDS_PINID='A';
NODE_NAME     R8385 1
 '@T6G_MB_LIB.T6G(SCH_1):PAGE199_I43@PURE_QUANTA.Q_RES(CHIPS)':
 'A': CDS_PINID='A';
NET_NAME
'PWRGD_PVDD11_S3_P1_R'
 '@T6G_MB_LIB.T6G(SCH_1):PWRGD_PVDD11_S3_P1_R':
 C_SIGNAL='@t6g_mb_lib.t6g(sch_1):pwrgd_pvdd11_s3_p1_r';
NODE_NAME     R8380 2
 '@T6G_MB_LIB.T6G(SCH_1):PAGE199_I37@PURE_QUANTA.Q_RES(CHIPS)':
 'B': CDS_PINID='B';
NODE_NAME     R8385 2
 '@T6G_MB_LIB.T6G(SCH_1):PAGE199_I43@PURE_QUANTA.Q_RES(CHIPS)':
 'B': CDS_PINID='B';
NODE_NAME     C8641 1
 '@T6G_MB_LIB.T6G(SCH_1):PAGE199_I46@PURE_QUANTA.Q_CAP(CHIPS)':
 'A': CDS_PINID='A';
NODE_NAME     PU54 12
 '@T6G_MB_LIB.T6G(SCH_1):PAGE199_I86@PURE_QUANTA.RAA229621GNPHA0(CHIPS)':
 'PG0': CDS_PINID='PG0';
NET_NAME
'PWRGD_PVDD18_S5_P0'
 '@T6G_MB_LIB.T6G(SCH_1):PWRGD_PVDD18_S5_P0':
 C_SIGNAL='@t6g_mb_lib.t6g(sch_1):pwrgd_pvdd18_s5_p0';
NODE_NAME     PU57 9
 '@T6G_MB_LIB.T6G(SCH_1):PAGE184_I18@PURE_QUANTA.MPQ8633BGLEC838Z(CHIPS)':
 'PGOOD': CDS_PINID='PGOOD';
NODE_NAME     R8465 2
 '@T6G_MB_LIB.T6G(SCH_1):PAGE184_I29@PURE_QUANTA.Q_RES(CHIPS)':
 'B': CDS_PINID='B';
NODE_NAME     R177 1
 '@T6G_MB_LIB.T6G(SCH_1):PAGE184_I52@PURE_QUANTA.Q_RES(CHIPS)':
 'A': CDS_PINID='A';
NET_NAME
'PWRGD_PVDD18_S5_P1'
 '@T6G_MB_LIB.T6G(SCH_1):PWRGD_PVDD18_S5_P1':
 C_SIGNAL='@t6g_mb_lib.t6g(sch_1):pwrgd_pvdd18_s5_p1';
NODE_NAME     PU3 9
 '@T6G_MB_LIB.T6G(SCH_1):PAGE201_I15@PURE_QUANTA.MPQ8633BGLEC838Z(CHIPS)':
 'PGOOD': CDS_PINID='PGOOD';
NODE_NAME     R8009 2
 '@T6G_MB_LIB.T6G(SCH_1):PAGE201_I26@PURE_QUANTA.Q_RES(CHIPS)':
 'B': CDS_PINID='B';
NODE_NAME     R259 1
 '@T6G_MB_LIB.T6G(SCH_1):PAGE201_I48@PURE_QUANTA.Q_RES(CHIPS)':
 'A': CDS_PINID='A';
NET_NAME
'PWRGD_PVDD18_S5_R_P1'
 '@T6G_MB_LIB.T6G(SCH_1):PWRGD_PVDD18_S5_R_P1':
 C_SIGNAL='@t6g_mb_lib.t6g(sch_1):pwrgd_pvdd18_s5_r_p1';
NODE_NAME     R259 2
 '@T6G_MB_LIB.T6G(SCH_1):PAGE201_I48@PURE_QUANTA.Q_RES(CHIPS)':
 'B': CDS_PINID='B';
NODE_NAME     U18 AA6
 '@T6G_MB_LIB.T6G(SCH_1):PAGE80_I216@PURE_QUANTA.LCMXO3LF9400C5BG484C(CHIPS)':
 'PB11A': CDS_PINID='PB11A';
NODE_NAME     C5016 1
 '@T6G_MB_LIB.T6G(SCH_1):PAGE201_I55@PURE_QUANTA.Q_CAP(CHIPS)':
 'A': CDS_PINID='A';
NET_NAME
'PWRGD_PVDD33_S5'
 '@T6G_MB_LIB.T6G(SCH_1):PWRGD_PVDD33_S5':
 C_SIGNAL='@t6g_mb_lib.t6g(sch_1):pwrgd_pvdd33_s5';
NODE_NAME     R453 2
 '@T6G_MB_LIB.T6G(SCH_1):PAGE167_I31@PURE_QUANTA.Q_RES(CHIPS)':
 'B': CDS_PINID='B';
NODE_NAME     R225 1
 '@T6G_MB_LIB.T6G(SCH_1):PAGE167_I33@PURE_QUANTA.Q_RES(CHIPS)':
 'A': CDS_PINID='A';
NODE_NAME     PU55 9
 '@T6G_MB_LIB.T6G(SCH_1):PAGE167_I41@PURE_QUANTA.MPQ8633AGLEC807Z(CHIPS)':
 'PGOOD': CDS_PINID='PGOOD';
NET_NAME
'PWRGD_PVDDCR_CPU0_P0'
 '@T6G_MB_LIB.T6G(SCH_1):PWRGD_PVDDCR_CPU0_P0':
 C_SIGNAL='@t6g_mb_lib.t6g(sch_1):pwrgd_pvddcr_cpu0_p0';
NODE_NAME     U18 Y3
 '@T6G_MB_LIB.T6G(SCH_1):PAGE81_I143@PURE_QUANTA.LCMXO3LF9400C5BG484C(CHIPS)':
 'PL30A': CDS_PINID='PL30A';
NODE_NAME     R8311 1
 '@T6G_MB_LIB.T6G(SCH_1):PAGE168_I89@PURE_QUANTA.Q_RES(CHIPS)':
 'A': CDS_PINID='A';
NODE_NAME     C5017 2
 '@T6G_MB_LIB.T6G(SCH_1):PAGE168_I139@PURE_QUANTA.Q_CAP(CHIPS)':
 'B': CDS_PINID='B';
NET_NAME
'PWRGD_PVDDCR_CPU0_P0_R'
 '@T6G_MB_LIB.T6G(SCH_1):PWRGD_PVDDCR_CPU0_P0_R':
 C_SIGNAL='@t6g_mb_lib.t6g(sch_1):pwrgd_pvddcr_cpu0_p0_r';
NODE_NAME     R8300 2
 '@T6G_MB_LIB.T6G(SCH_1):PAGE168_I82@PURE_QUANTA.Q_RES(CHIPS)':
 'B': CDS_PINID='B';
NODE_NAME     R8311 2
 '@T6G_MB_LIB.T6G(SCH_1):PAGE168_I89@PURE_QUANTA.Q_RES(CHIPS)':
 'B': CDS_PINID='B';
NODE_NAME     C467 1
 '@T6G_MB_LIB.T6G(SCH_1):PAGE168_I92@PURE_QUANTA.Q_CAP(CHIPS)':
 'A': CDS_PINID='A';
NODE_NAME     PU42 16
 '@T6G_MB_LIB.T6G(SCH_1):PAGE168_I135@PURE_QUANTA.RAA229620GNPHA0(CHIPS)':
 'PG0': CDS_PINID='PG0';
NET_NAME
'PWRGD_PVDDCR_CPU0_P1'
 '@T6G_MB_LIB.T6G(SCH_1):PWRGD_PVDDCR_CPU0_P1':
 C_SIGNAL='@t6g_mb_lib.t6g(sch_1):pwrgd_pvddcr_cpu0_p1';
NODE_NAME     R209 1
 '@T6G_MB_LIB.T6G(SCH_1):PAGE80_I61@PURE_QUANTA.Q_RES(CHIPS)':
 'A': CDS_PINID='A';
NODE_NAME     R8178 1
 '@T6G_MB_LIB.T6G(SCH_1):PAGE185_I85@PURE_QUANTA.Q_RES(CHIPS)':
 'A': CDS_PINID='A';
NODE_NAME     C5003 2
 '@T6G_MB_LIB.T6G(SCH_1):PAGE185_I141@PURE_QUANTA.Q_CAP(CHIPS)':
 'B': CDS_PINID='B';
NET_NAME
'PWRGD_PVDDCR_CPU0_P1_R'
 '@T6G_MB_LIB.T6G(SCH_1):PWRGD_PVDDCR_CPU0_P1_R':
 C_SIGNAL='@t6g_mb_lib.t6g(sch_1):pwrgd_pvddcr_cpu0_p1_r';
NODE_NAME     C248 1
 '@T6G_MB_LIB.T6G(SCH_1):PAGE185_I88@PURE_QUANTA.Q_CAP(CHIPS)':
 'A': CDS_PINID='A';
NODE_NAME     R8167 2
 '@T6G_MB_LIB.T6G(SCH_1):PAGE185_I78@PURE_QUANTA.Q_RES(CHIPS)':
 'B': CDS_PINID='B';
NODE_NAME     R8178 2
 '@T6G_MB_LIB.T6G(SCH_1):PAGE185_I85@PURE_QUANTA.Q_RES(CHIPS)':
 'B': CDS_PINID='B';
NODE_NAME     PU25 16
 '@T6G_MB_LIB.T6G(SCH_1):PAGE185_I133@PURE_QUANTA.RAA229620GNPHA0(CHIPS)':
 'PG0': CDS_PINID='PG0';
NET_NAME
'PWRGD_PVDDCR_CPU1_P0'
 '@T6G_MB_LIB.T6G(SCH_1):PWRGD_PVDDCR_CPU1_P0':
 C_SIGNAL='@t6g_mb_lib.t6g(sch_1):pwrgd_pvddcr_cpu1_p0';
NODE_NAME     R233 1
 '@T6G_MB_LIB.T6G(SCH_1):PAGE81_I54@PURE_QUANTA.Q_RES(CHIPS)':
 'A': CDS_PINID='A';
NODE_NAME     R8057 1
 '@T6G_MB_LIB.T6G(SCH_1):PAGE175_I89@PURE_QUANTA.Q_RES(CHIPS)':
 'A': CDS_PINID='A';
NODE_NAME     C5004 2
 '@T6G_MB_LIB.T6G(SCH_1):PAGE175_I135@PURE_QUANTA.Q_CAP(CHIPS)':
 'B': CDS_PINID='B';
NET_NAME
'PWRGD_PVDDCR_CPU1_P0_R'
 '@T6G_MB_LIB.T6G(SCH_1):PWRGD_PVDDCR_CPU1_P0_R':
 C_SIGNAL='@t6g_mb_lib.t6g(sch_1):pwrgd_pvddcr_cpu1_p0_r';
NODE_NAME     R8057 2
 '@T6G_MB_LIB.T6G(SCH_1):PAGE175_I89@PURE_QUANTA.Q_RES(CHIPS)':
 'B': CDS_PINID='B';
NODE_NAME     R8056 2
 '@T6G_MB_LIB.T6G(SCH_1):PAGE175_I90@PURE_QUANTA.Q_RES(CHIPS)':
 'B': CDS_PINID='B';
NODE_NAME     C8070 1
 '@T6G_MB_LIB.T6G(SCH_1):PAGE175_I91@PURE_QUANTA.Q_CAP(CHIPS)':
 'A': CDS_PINID='A';
NODE_NAME     PU12 16
 '@T6G_MB_LIB.T6G(SCH_1):PAGE175_I128@PURE_QUANTA.RAA229620GNPHA0(CHIPS)':
 'PG0': CDS_PINID='PG0';
NET_NAME
'PWRGD_PVDDCR_CPU1_P1'
 '@T6G_MB_LIB.T6G(SCH_1):PWRGD_PVDDCR_CPU1_P1':
 C_SIGNAL='@t6g_mb_lib.t6g(sch_1):pwrgd_pvddcr_cpu1_p1';
NODE_NAME     R286 1
 '@T6G_MB_LIB.T6G(SCH_1):PAGE80_I62@PURE_QUANTA.Q_RES(CHIPS)':
 'A': CDS_PINID='A';
NODE_NAME     R8234 1
 '@T6G_MB_LIB.T6G(SCH_1):PAGE192_I88@PURE_QUANTA.Q_RES(CHIPS)':
 'A': CDS_PINID='A';
NODE_NAME     C5022 2
 '@T6G_MB_LIB.T6G(SCH_1):PAGE192_I131@PURE_QUANTA.Q_CAP(CHIPS)':
 'B': CDS_PINID='B';
NET_NAME
'PWRGD_PVDDCR_CPU1_P1_R'
 '@T6G_MB_LIB.T6G(SCH_1):PWRGD_PVDDCR_CPU1_P1_R':
 C_SIGNAL='@t6g_mb_lib.t6g(sch_1):pwrgd_pvddcr_cpu1_p1_r';
NODE_NAME     R8234 2
 '@T6G_MB_LIB.T6G(SCH_1):PAGE192_I88@PURE_QUANTA.Q_RES(CHIPS)':
 'B': CDS_PINID='B';
NODE_NAME     R8233 2
 '@T6G_MB_LIB.T6G(SCH_1):PAGE192_I89@PURE_QUANTA.Q_RES(CHIPS)':
 'B': CDS_PINID='B';
NODE_NAME     C8360 1
 '@T6G_MB_LIB.T6G(SCH_1):PAGE192_I90@PURE_QUANTA.Q_CAP(CHIPS)':
 'A': CDS_PINID='A';
NODE_NAME     PU34 16
 '@T6G_MB_LIB.T6G(SCH_1):PAGE192_I128@PURE_QUANTA.RAA229620GNPHA0(CHIPS)':
 'PG0': CDS_PINID='PG0';
NET_NAME
'PWRGD_PVDDCR_SOC_P0'
 '@T6G_MB_LIB.T6G(SCH_1):PWRGD_PVDDCR_SOC_P0':
 C_SIGNAL='@t6g_mb_lib.t6g(sch_1):pwrgd_pvddcr_soc_p0';
NODE_NAME     U18 Y2
 '@T6G_MB_LIB.T6G(SCH_1):PAGE81_I143@PURE_QUANTA.LCMXO3LF9400C5BG484C(CHIPS)':
 'PL29D': CDS_PINID='PL29D';
NODE_NAME     R8299 1
 '@T6G_MB_LIB.T6G(SCH_1):PAGE168_I24@PURE_QUANTA.Q_RES(CHIPS)':
 'A': CDS_PINID='A';
NODE_NAME     C5018 2
 '@T6G_MB_LIB.T6G(SCH_1):PAGE168_I138@PURE_QUANTA.Q_CAP(CHIPS)':
 'B': CDS_PINID='B';
NET_NAME
'PWRGD_PVDDCR_SOC_P0_R'
 '@T6G_MB_LIB.T6G(SCH_1):PWRGD_PVDDCR_SOC_P0_R':
 C_SIGNAL='@t6g_mb_lib.t6g(sch_1):pwrgd_pvddcr_soc_p0_r';
NODE_NAME     R8299 2
 '@T6G_MB_LIB.T6G(SCH_1):PAGE168_I24@PURE_QUANTA.Q_RES(CHIPS)':
 'B': CDS_PINID='B';
NODE_NAME     R8298 2
 '@T6G_MB_LIB.T6G(SCH_1):PAGE168_I28@PURE_QUANTA.Q_RES(CHIPS)':
 'B': CDS_PINID='B';
NODE_NAME     C465 1
 '@T6G_MB_LIB.T6G(SCH_1):PAGE168_I51@PURE_QUANTA.Q_CAP(CHIPS)':
 'A': CDS_PINID='A';
NODE_NAME     PU42 20
 '@T6G_MB_LIB.T6G(SCH_1):PAGE168_I135@PURE_QUANTA.RAA229620GNPHA0(CHIPS)':
 'PG1': CDS_PINID='PG1';
NET_NAME
'PWRGD_PVDDCR_SOC_P1'
 '@T6G_MB_LIB.T6G(SCH_1):PWRGD_PVDDCR_SOC_P1':
 C_SIGNAL='@t6g_mb_lib.t6g(sch_1):pwrgd_pvddcr_soc_p1';
NODE_NAME     R8166 1
 '@T6G_MB_LIB.T6G(SCH_1):PAGE185_I23@PURE_QUANTA.Q_RES(CHIPS)':
 'A': CDS_PINID='A';
NODE_NAME     U18 A17
 '@T6G_MB_LIB.T6G(SCH_1):PAGE79_I94@PURE_QUANTA.LCMXO3LF9400C5BG484C(CHIPS)':
 'PT40A': CDS_PINID='PT40A';
NODE_NAME     C5019 2
 '@T6G_MB_LIB.T6G(SCH_1):PAGE185_I137@PURE_QUANTA.Q_CAP(CHIPS)':
 'B': CDS_PINID='B';
NET_NAME
'PWRGD_PVDDCR_SOC_P1_R'
 '@T6G_MB_LIB.T6G(SCH_1):PWRGD_PVDDCR_SOC_P1_R':
 C_SIGNAL='@t6g_mb_lib.t6g(sch_1):pwrgd_pvddcr_soc_p1_r';
NODE_NAME     R8166 2
 '@T6G_MB_LIB.T6G(SCH_1):PAGE185_I23@PURE_QUANTA.Q_RES(CHIPS)':
 'B': CDS_PINID='B';
NODE_NAME     R8165 2
 '@T6G_MB_LIB.T6G(SCH_1):PAGE185_I27@PURE_QUANTA.Q_RES(CHIPS)':
 'B': CDS_PINID='B';
NODE_NAME     C8246 1
 '@T6G_MB_LIB.T6G(SCH_1):PAGE185_I52@PURE_QUANTA.Q_CAP(CHIPS)':
 'A': CDS_PINID='A';
NODE_NAME     PU25 20
 '@T6G_MB_LIB.T6G(SCH_1):PAGE185_I133@PURE_QUANTA.RAA229620GNPHA0(CHIPS)':
 'PG1': CDS_PINID='PG1';
NET_NAME
'PWRGD_PVDDIO_P0'
 '@T6G_MB_LIB.T6G(SCH_1):PWRGD_PVDDIO_P0':
 C_SIGNAL='@t6g_mb_lib.t6g(sch_1):pwrgd_pvddio_p0';
NODE_NAME     R8066 1
 '@T6G_MB_LIB.T6G(SCH_1):PAGE175_I53@PURE_QUANTA.Q_RES(CHIPS)':
 'A': CDS_PINID='A';
NODE_NAME     R230 1
 '@T6G_MB_LIB.T6G(SCH_1):PAGE80_I67@PURE_QUANTA.Q_RES(CHIPS)':
 'A': CDS_PINID='A';
NODE_NAME     C5005 2
 '@T6G_MB_LIB.T6G(SCH_1):PAGE175_I133@PURE_QUANTA.Q_CAP(CHIPS)':
 'B': CDS_PINID='B';
NET_NAME
'PWRGD_PVDDIO_P0_R'
 '@T6G_MB_LIB.T6G(SCH_1):PWRGD_PVDDIO_P0_R':
 C_SIGNAL='@t6g_mb_lib.t6g(sch_1):pwrgd_pvddio_p0_r';
NODE_NAME     R8066 2
 '@T6G_MB_LIB.T6G(SCH_1):PAGE175_I53@PURE_QUANTA.Q_RES(CHIPS)':
 'B': CDS_PINID='B';
NODE_NAME     R8065 2
 '@T6G_MB_LIB.T6G(SCH_1):PAGE175_I54@PURE_QUANTA.Q_RES(CHIPS)':
 'B': CDS_PINID='B';
NODE_NAME     C8072 1
 '@T6G_MB_LIB.T6G(SCH_1):PAGE175_I55@PURE_QUANTA.Q_CAP(CHIPS)':
 'A': CDS_PINID='A';
NODE_NAME     PU12 20
 '@T6G_MB_LIB.T6G(SCH_1):PAGE175_I128@PURE_QUANTA.RAA229620GNPHA0(CHIPS)':
 'PG1': CDS_PINID='PG1';
NET_NAME
'PWRGD_PVDDIO_P1'
 '@T6G_MB_LIB.T6G(SCH_1):PWRGD_PVDDIO_P1':
 C_SIGNAL='@t6g_mb_lib.t6g(sch_1):pwrgd_pvddio_p1';
NODE_NAME     R283 1
 '@T6G_MB_LIB.T6G(SCH_1):PAGE80_I30@PURE_QUANTA.Q_RES(CHIPS)':
 'A': CDS_PINID='A';
NODE_NAME     R8243 1
 '@T6G_MB_LIB.T6G(SCH_1):PAGE192_I50@PURE_QUANTA.Q_RES(CHIPS)':
 'A': CDS_PINID='A';
NODE_NAME     C5006 2
 '@T6G_MB_LIB.T6G(SCH_1):PAGE192_I136@PURE_QUANTA.Q_CAP(CHIPS)':
 'B': CDS_PINID='B';
NET_NAME
'PWRGD_PVDDIO_P1_R'
 '@T6G_MB_LIB.T6G(SCH_1):PWRGD_PVDDIO_P1_R':
 C_SIGNAL='@t6g_mb_lib.t6g(sch_1):pwrgd_pvddio_p1_r';
NODE_NAME     R8243 2
 '@T6G_MB_LIB.T6G(SCH_1):PAGE192_I50@PURE_QUANTA.Q_RES(CHIPS)':
 'B': CDS_PINID='B';
NODE_NAME     R8242 2
 '@T6G_MB_LIB.T6G(SCH_1):PAGE192_I51@PURE_QUANTA.Q_RES(CHIPS)':
 'B': CDS_PINID='B';
NODE_NAME     C8362 1
 '@T6G_MB_LIB.T6G(SCH_1):PAGE192_I52@PURE_QUANTA.Q_CAP(CHIPS)':
 'A': CDS_PINID='A';
NODE_NAME     PU34 20
 '@T6G_MB_LIB.T6G(SCH_1):PAGE192_I128@PURE_QUANTA.RAA229620GNPHA0(CHIPS)':
 'PG1': CDS_PINID='PG1';
NET_NAME
'RMII_BMC_OCP_RX_ER'
 '@T6G_MB_LIB.T6G(SCH_1):RMII_BMC_OCP_RX_ER':
 C_SIGNAL='@t6g_mb_lib.t6g(sch_1):rmii_bmc_ocp_rx_er';
NODE_NAME     R87 1
 '@T6G_MB_LIB.T6G(SCH_1):PAGE336_I136@PURE_QUANTA.Q_RES(CHIPS)':
 'A': CDS_PINID='A';
NODE_NAME     J41 B23
 '@T6G_MB_LIB.T6G(SCH_1):PAGE348_I176@PURE_QUANTA.SCONN168_ME1016810202011(CHIPS)':
 'PETN2': CDS_PINID='PETN2';
NET_NAME
'RMII_BMC_OCP_TXD_0'
 '@T6G_MB_LIB.T6G(SCH_1):RMII_BMC_OCP_TXD_0':
 C_SIGNAL='@t6g_mb_lib.t6g(sch_1):rmii_bmc_ocp_txd_0';
NODE_NAME     R3214 2
 '@T6G_MB_LIB.T6G(SCH_1):PAGE307_I60@PURE_QUANTA.Q_RES(CHIPS)':
 'B': CDS_PINID='B';
NODE_NAME     R75 2
 '@T6G_MB_LIB.T6G(SCH_1):PAGE336_I103@PURE_QUANTA.Q_RES(CHIPS)':
 'B': CDS_PINID='B';
NODE_NAME     R83 1
 '@T6G_MB_LIB.T6G(SCH_1):PAGE336_I135@PURE_QUANTA.Q_RES(CHIPS)':
 'A': CDS_PINID='A';
NODE_NAME     J41 B21
 '@T6G_MB_LIB.T6G(SCH_1):PAGE348_I176@PURE_QUANTA.SCONN168_ME1016810202011(CHIPS)':
 'PETP1': CDS_PINID='PETP1';
NET_NAME
'RMII_BMC_OCP_TXD_1'
 '@T6G_MB_LIB.T6G(SCH_1):RMII_BMC_OCP_TXD_1':
 C_SIGNAL='@t6g_mb_lib.t6g(sch_1):rmii_bmc_ocp_txd_1';
NODE_NAME     R3215 2
 '@T6G_MB_LIB.T6G(SCH_1):PAGE307_I56@PURE_QUANTA.Q_RES(CHIPS)':
 'B': CDS_PINID='B';
NODE_NAME     R76 2
 '@T6G_MB_LIB.T6G(SCH_1):PAGE336_I104@PURE_QUANTA.Q_RES(CHIPS)':
 'B': CDS_PINID='B';
NODE_NAME     R84 1
 '@T6G_MB_LIB.T6G(SCH_1):PAGE336_I129@PURE_QUANTA.Q_RES(CHIPS)':
 'A': CDS_PINID='A';
NODE_NAME     J41 B22
 '@T6G_MB_LIB.T6G(SCH_1):PAGE348_I176@PURE_QUANTA.SCONN168_ME1016810202011(CHIPS)':
 'GND_B22': CDS_PINID='GND_B22';
NET_NAME
'RMII_BMC_OCP_TX_EN'
 '@T6G_MB_LIB.T6G(SCH_1):RMII_BMC_OCP_TX_EN':
 C_SIGNAL='@t6g_mb_lib.t6g(sch_1):rmii_bmc_ocp_tx_en';
NODE_NAME     R3213 2
 '@T6G_MB_LIB.T6G(SCH_1):PAGE307_I61@PURE_QUANTA.Q_RES(CHIPS)':
 'B': CDS_PINID='B';
NODE_NAME     R74 2
 '@T6G_MB_LIB.T6G(SCH_1):PAGE336_I102@PURE_QUANTA.Q_RES(CHIPS)':
 'B': CDS_PINID='B';
NODE_NAME     R82 1
 '@T6G_MB_LIB.T6G(SCH_1):PAGE336_I134@PURE_QUANTA.Q_RES(CHIPS)':
 'A': CDS_PINID='A';
NODE_NAME     J41 B20
 '@T6G_MB_LIB.T6G(SCH_1):PAGE348_I176@PURE_QUANTA.SCONN168_ME1016810202011(CHIPS)':
 'PETN1': CDS_PINID='PETN1';
NET_NAME
'RMII_OCP_BMC_CRSDV'
 '@T6G_MB_LIB.T6G(SCH_1):RMII_OCP_BMC_CRSDV':
 C_SIGNAL='@t6g_mb_lib.t6g(sch_1):rmii_ocp_bmc_crsdv';
NODE_NAME     R3210 2
 '@T6G_MB_LIB.T6G(SCH_1):PAGE307_I65@PURE_QUANTA.Q_RES(CHIPS)':
 'B': CDS_PINID='B';
NODE_NAME     R59 2
 '@T6G_MB_LIB.T6G(SCH_1):PAGE336_I99@PURE_QUANTA.Q_RES(CHIPS)':
 'B': CDS_PINID='B';
NODE_NAME     R77 1
 '@T6G_MB_LIB.T6G(SCH_1):PAGE336_I131@PURE_QUANTA.Q_RES(CHIPS)':
 'A': CDS_PINID='A';
NODE_NAME     J41 B19
 '@T6G_MB_LIB.T6G(SCH_1):PAGE348_I176@PURE_QUANTA.SCONN168_ME1016810202011(CHIPS)':
 'GND_B19': CDS_PINID='GND_B19';
NET_NAME
'RMII_OCP_BMC_RXD_0'
 '@T6G_MB_LIB.T6G(SCH_1):RMII_OCP_BMC_RXD_0':
 C_SIGNAL='@t6g_mb_lib.t6g(sch_1):rmii_ocp_bmc_rxd_0';
NODE_NAME     R3211 2
 '@T6G_MB_LIB.T6G(SCH_1):PAGE307_I63@PURE_QUANTA.Q_RES(CHIPS)':
 'B': CDS_PINID='B';
NODE_NAME     R72 2
 '@T6G_MB_LIB.T6G(SCH_1):PAGE336_I100@PURE_QUANTA.Q_RES(CHIPS)':
 'B': CDS_PINID='B';
NODE_NAME     R79 1
 '@T6G_MB_LIB.T6G(SCH_1):PAGE336_I132@PURE_QUANTA.Q_RES(CHIPS)':
 'A': CDS_PINID='A';
NODE_NAME     J41 B24
 '@T6G_MB_LIB.T6G(SCH_1):PAGE348_I176@PURE_QUANTA.SCONN168_ME1016810202011(CHIPS)':
 'PETP2': CDS_PINID='PETP2';
NET_NAME
'RMII_OCP_BMC_RXD_1'
 '@T6G_MB_LIB.T6G(SCH_1):RMII_OCP_BMC_RXD_1':
 C_SIGNAL='@t6g_mb_lib.t6g(sch_1):rmii_ocp_bmc_rxd_1';
NODE_NAME     R3212 2
 '@T6G_MB_LIB.T6G(SCH_1):PAGE307_I62@PURE_QUANTA.Q_RES(CHIPS)':
 'B': CDS_PINID='B';
NODE_NAME     R73 2
 '@T6G_MB_LIB.T6G(SCH_1):PAGE336_I101@PURE_QUANTA.Q_RES(CHIPS)':
 'B': CDS_PINID='B';
NODE_NAME     R80 1
 '@T6G_MB_LIB.T6G(SCH_1):PAGE336_I133@PURE_QUANTA.Q_RES(CHIPS)':
 'A': CDS_PINID='A';
NODE_NAME     J41 B25
 '@T6G_MB_LIB.T6G(SCH_1):PAGE348_I176@PURE_QUANTA.SCONN168_ME1016810202011(CHIPS)':
 'GND_B25': CDS_PINID='GND_B25';
NET_NAME
'ROM_LS_EN'
 '@T6G_MB_LIB.T6G(SCH_1):ROM_LS_EN':
 C_SIGNAL='@t6g_mb_lib.t6g(sch_1):rom_ls_en';
NODE_NAME     U54 12
 '@T6G_MB_LIB.T6G(SCH_1):PAGE76_I67@PURE_QUANTA.PI4ULS3V304AZMAEX(CHIPS)':
 'EN': CDS_PINID='EN';
NODE_NAME     R1567 2
 '@T6G_MB_LIB.T6G(SCH_1):PAGE76_I150@PURE_QUANTA.Q_RES(CHIPS)':
 'B': CDS_PINID='B';
NODE_NAME     R1564 2
 '@T6G_MB_LIB.T6G(SCH_1):PAGE80_I156@PURE_QUANTA.Q_RES(CHIPS)':
 'B': CDS_PINID='B';
NET_NAME
'ROM_SD_LS_OE'
 '@T6G_MB_LIB.T6G(SCH_1):ROM_SD_LS_OE':
 C_SIGNAL='@t6g_mb_lib.t6g(sch_1):rom_sd_ls_oe';
NODE_NAME     U53 9
 '@T6G_MB_LIB.T6G(SCH_1):PAGE76_I63@PURE_QUANTA.SN74AVC4T774PWR(CHIPS)':
 'OE': CDS_PINID='OE';
NODE_NAME     R1616 2
 '@T6G_MB_LIB.T6G(SCH_1):PAGE80_I157@PURE_QUANTA.Q_RES(CHIPS)':
 'B': CDS_PINID='B';
NET_NAME
'RST_BMC_FROM_SWB'
 '@T6G_MB_LIB.T6G(SCH_1):RST_BMC_FROM_SWB':
 C_SIGNAL='@t6g_mb_lib.t6g(sch_1):rst_bmc_from_swb';
NODE_NAME     R2834 2
 '@T6G_MB_LIB.T6G(SCH_1):PAGE333_I18@PURE_QUANTA.Q_RES(CHIPS)':
 'B': CDS_PINID='B';
NODE_NAME     Q69 5
 '@T6G_MB_LIB.T6G(SCH_1):PAGE333_I88@PURE_QUANTA.MOSFET_NCH_DUAL(CHIPS)':
 'G2': CDS_PINID='G2';
NODE_NAME     Q69 6
 '@T6G_MB_LIB.T6G(SCH_1):PAGE333_I117@PURE_QUANTA.MOSFET_NCH_DUAL(CHIPS)':
 'D1': CDS_PINID='D1';
NET_NAME
'RST_BMC_FROM_SWB_ISO_N'
 '@T6G_MB_LIB.T6G(SCH_1):RST_BMC_FROM_SWB_ISO_N':
 C_SIGNAL='@t6g_mb_lib.t6g(sch_1):rst_bmc_from_swb_iso_n';
NODE_NAME     Q69 3
 '@T6G_MB_LIB.T6G(SCH_1):PAGE333_I88@PURE_QUANTA.MOSFET_NCH_DUAL(CHIPS)':
 'D2': CDS_PINID='D2';
NODE_NAME     R2919 2
 '@T6G_MB_LIB.T6G(SCH_1):PAGE333_I91@PURE_QUANTA.Q_RES(CHIPS)':
 'B': CDS_PINID='B';
NODE_NAME     C1772 1
 '@T6G_MB_LIB.T6G(SCH_1):PAGE333_I116@PURE_QUANTA.Q_CAP(CHIPS)':
 'A': CDS_PINID='A';
NODE_NAME     R2847 2
 '@T6G_MB_LIB.T6G(SCH_1):PAGE80_I266@PURE_QUANTA.Q_RES(CHIPS)':
 'B': CDS_PINID='B';
NET_NAME
'RST_BMC_FROM_SWB_ISO_R_N'
 '@T6G_MB_LIB.T6G(SCH_1):RST_BMC_FROM_SWB_ISO_R_N':
 C_SIGNAL='@t6g_mb_lib.t6g(sch_1):rst_bmc_from_swb_iso_r_n';
NODE_NAME     U18 U15
 '@T6G_MB_LIB.T6G(SCH_1):PAGE80_I216@PURE_QUANTA.LCMXO3LF9400C5BG484C(CHIPS)':
 'PB38D': CDS_PINID='PB38D';
NODE_NAME     R2847 1
 '@T6G_MB_LIB.T6G(SCH_1):PAGE80_I266@PURE_QUANTA.Q_RES(CHIPS)':
 'A': CDS_PINID='A';
NET_NAME
'RST_BMC_FROM_SWB_N'
 '@T6G_MB_LIB.T6G(SCH_1):RST_BMC_FROM_SWB_N':
 C_SIGNAL='@t6g_mb_lib.t6g(sch_1):rst_bmc_from_swb_n';
NODE_NAME     R2829 1
 '@T6G_MB_LIB.T6G(SCH_1):PAGE333_I58@PURE_QUANTA.Q_RES(CHIPS)':
 'A': CDS_PINID='A';
NODE_NAME     R2828 2
 '@T6G_MB_LIB.T6G(SCH_1):PAGE333_I66@PURE_QUANTA.Q_RES(CHIPS)':
 'B': CDS_PINID='B';
NODE_NAME     Q69 2
 '@T6G_MB_LIB.T6G(SCH_1):PAGE333_I117@PURE_QUANTA.MOSFET_NCH_DUAL(CHIPS)':
 'G1': CDS_PINID='G1';
NODE_NAME     J105 N8
 '@T6G_MB_LIB.T6G(SCH_1):PAGE326_I76@PURE_QUANTA.CONN112_10137002101LF(CHIPS)':
 'N8': CDS_PINID='N8';
NET_NAME
'RST_CPU0_KBRST_N'
 '@T6G_MB_LIB.T6G(SCH_1):RST_CPU0_KBRST_N':
 C_SIGNAL='@t6g_mb_lib.t6g(sch_1):rst_cpu0_kbrst_n';
NODE_NAME     R463 2
 '@T6G_MB_LIB.T6G(SCH_1):PAGE80_I112@PURE_QUANTA.Q_RES(CHIPS)':
 'B': CDS_PINID='B';
NODE_NAME     U18 G17
 '@T6G_MB_LIB.T6G(SCH_1):PAGE80_I217@PURE_QUANTA.LCMXO3LF9400C5BG484C(CHIPS)':
 'PR7C': CDS_PINID='PR7C';
NET_NAME
'RST_CPU0_KBRST_R_N'
 '@T6G_MB_LIB.T6G(SCH_1):RST_CPU0_KBRST_R_N':
 C_SIGNAL='@t6g_mb_lib.t6g(sch_1):rst_cpu0_kbrst_r_n';
NODE_NAME     U25 DJ26
 '@T6G_MB_LIB.T6G(SCH_1):PAGE29_I287@PURE_QUANTA.GENOA_SP5(CHIPS)':
 'ESPI_RSTIN_L||KBRST_L||AGPIO129': CDS_PINID='\espi_rstin_l||kbrst_l||agpio129\';
NODE_NAME     R463 1
 '@T6G_MB_LIB.T6G(SCH_1):PAGE80_I112@PURE_QUANTA.Q_RES(CHIPS)':
 'A': CDS_PINID='A';
NODE_NAME     R1351 1
 '@T6G_MB_LIB.T6G(SCH_1):PAGE82_I72@PURE_QUANTA.Q_RES(CHIPS)':
 'A': CDS_PINID='A';
NET_NAME
'RST_CPU0_PERST0_N'
 '@T6G_MB_LIB.T6G(SCH_1):RST_CPU0_PERST0_N':
 C_SIGNAL='@t6g_mb_lib.t6g(sch_1):rst_cpu0_perst0_n';
NODE_NAME     R254 1
 '@T6G_MB_LIB.T6G(SCH_1):PAGE80_I123@PURE_QUANTA.Q_RES(CHIPS)':
 'A': CDS_PINID='A';
NODE_NAME     R16 1
 '@T6G_MB_LIB.T6G(SCH_1):PAGE82_I124@PURE_QUANTA.Q_RES(CHIPS)':
 'A': CDS_PINID='A';
NODE_NAME     U25 D18
 '@T6G_MB_LIB.T6G(SCH_1):PAGE28_I188@PURE_QUANTA.GENOA_SP5(CHIPS)':
 'PCIE_RST0_L||AGPIO266': CDS_PINID='\pcie_rst0_l||agpio266\';
NET_NAME
'RST_CPU0_PERST0_R_N'
 '@T6G_MB_LIB.T6G(SCH_1):RST_CPU0_PERST0_R_N':
 C_SIGNAL='@t6g_mb_lib.t6g(sch_1):rst_cpu0_perst0_r_n';
NODE_NAME     R254 2
 '@T6G_MB_LIB.T6G(SCH_1):PAGE80_I123@PURE_QUANTA.Q_RES(CHIPS)':
 'B': CDS_PINID='B';
NODE_NAME     U18 F17
 '@T6G_MB_LIB.T6G(SCH_1):PAGE80_I217@PURE_QUANTA.LCMXO3LF9400C5BG484C(CHIPS)':
 'PR2C': CDS_PINID='PR2C';
NET_NAME
'RST_CPU0_PERST1_N'
 '@T6G_MB_LIB.T6G(SCH_1):RST_CPU0_PERST1_N':
 C_SIGNAL='@t6g_mb_lib.t6g(sch_1):rst_cpu0_perst1_n';
NODE_NAME     R255 1
 '@T6G_MB_LIB.T6G(SCH_1):PAGE80_I121@PURE_QUANTA.Q_RES(CHIPS)':
 'A': CDS_PINID='A';
NODE_NAME     R17 1
 '@T6G_MB_LIB.T6G(SCH_1):PAGE82_I125@PURE_QUANTA.Q_RES(CHIPS)':
 'A': CDS_PINID='A';
NODE_NAME     U25 DG36
 '@T6G_MB_LIB.T6G(SCH_1):PAGE28_I188@PURE_QUANTA.GENOA_SP5(CHIPS)':
 'PCIE_RST1_L||AGPIO26': CDS_PINID='\pcie_rst1_l||agpio26\';
NET_NAME
'RST_CPU0_PERST1_R_N'
 '@T6G_MB_LIB.T6G(SCH_1):RST_CPU0_PERST1_R_N':
 C_SIGNAL='@t6g_mb_lib.t6g(sch_1):rst_cpu0_perst1_r_n';
NODE_NAME     R255 2
 '@T6G_MB_LIB.T6G(SCH_1):PAGE80_I121@PURE_QUANTA.Q_RES(CHIPS)':
 'B': CDS_PINID='B';
NODE_NAME     U18 D20
 '@T6G_MB_LIB.T6G(SCH_1):PAGE80_I217@PURE_QUANTA.LCMXO3LF9400C5BG484C(CHIPS)':
 'PR3D': CDS_PINID='PR3D';
NET_NAME
'RST_CPU0_RESETL_N'
 '@T6G_MB_LIB.T6G(SCH_1):RST_CPU0_RESETL_N':
 C_SIGNAL='@t6g_mb_lib.t6g(sch_1):rst_cpu0_resetl_n';
NODE_NAME     R241 1
 '@T6G_MB_LIB.T6G(SCH_1):PAGE80_I114@PURE_QUANTA.Q_RES(CHIPS)':
 'A': CDS_PINID='A';
NODE_NAME     R530 1
 '@T6G_MB_LIB.T6G(SCH_1):PAGE84_I27@PURE_QUANTA.Q_RES(CHIPS)':
 'A': CDS_PINID='A';
NODE_NAME     R442 1
 '@T6G_MB_LIB.T6G(SCH_1):PAGE28_I56@PURE_QUANTA.Q_RES(CHIPS)':
 'A': CDS_PINID='A';
NODE_NAME     U25 B67
 '@T6G_MB_LIB.T6G(SCH_1):PAGE28_I188@PURE_QUANTA.GENOA_SP5(CHIPS)':
 'RESET_L': CDS_PINID='RESET_L';
NET_NAME
'RST_CPU0_RSMRST_N'
 '@T6G_MB_LIB.T6G(SCH_1):RST_CPU0_RSMRST_N':
 C_SIGNAL='@t6g_mb_lib.t6g(sch_1):rst_cpu0_rsmrst_n';
NODE_NAME     R217 1
 '@T6G_MB_LIB.T6G(SCH_1):PAGE80_I118@PURE_QUANTA.Q_RES(CHIPS)':
 'A': CDS_PINID='A';
NODE_NAME     R582 2
 '@T6G_MB_LIB.T6G(SCH_1):PAGE28_I33@PURE_QUANTA.Q_RES(CHIPS)':
 'B': CDS_PINID='B';
NODE_NAME     R581 1
 '@T6G_MB_LIB.T6G(SCH_1):PAGE28_I34@PURE_QUANTA.Q_RES(CHIPS)':
 'A': CDS_PINID='A';
NODE_NAME     U25 DG10
 '@T6G_MB_LIB.T6G(SCH_1):PAGE28_I188@PURE_QUANTA.GENOA_SP5(CHIPS)':
 'RSMRST_L': CDS_PINID='RSMRST_L';
NODE_NAME     C5023 1
 '@T6G_MB_LIB.T6G(SCH_1):PAGE28_I194@PURE_QUANTA.Q_CAP(CHIPS)':
 'A': CDS_PINID='A';
NODE_NAME     Q87 2
 '@T6G_MB_LIB.T6G(SCH_1):PAGE254_I38@PURE_QUANTA.MOSFET_NCH_DUAL(CHIPS)':
 'G1': CDS_PINID='G1';
NET_NAME
'RST_CPU0_SYS_N'
 '@T6G_MB_LIB.T6G(SCH_1):RST_CPU0_SYS_N':
 C_SIGNAL='@t6g_mb_lib.t6g(sch_1):rst_cpu0_sys_n';
NODE_NAME     R216 1
 '@T6G_MB_LIB.T6G(SCH_1):PAGE80_I117@PURE_QUANTA.Q_RES(CHIPS)':
 'A': CDS_PINID='A';
NODE_NAME     J6 3
 '@T6G_MB_LIB.T6G(SCH_1):PAGE28_I28@PURE_QUANTA.CONN6_HBC1031L200D8H(CHIPS)':
 '3': CDS_PINID='\3\';
NODE_NAME     R422 2
 '@T6G_MB_LIB.T6G(SCH_1):PAGE28_I29@PURE_QUANTA.Q_RES(CHIPS)':
 'B': CDS_PINID='B';
NODE_NAME     U25 DH6
 '@T6G_MB_LIB.T6G(SCH_1):PAGE28_I188@PURE_QUANTA.GENOA_SP5(CHIPS)':
 'SYS_RESET_L||AGPIO1': CDS_PINID='\sys_reset_l||agpio1\';
NET_NAME
'RST_CPU1_PERST0_N'
 '@T6G_MB_LIB.T6G(SCH_1):RST_CPU1_PERST0_N':
 C_SIGNAL='@t6g_mb_lib.t6g(sch_1):rst_cpu1_perst0_n';
NODE_NAME     U26 D18
 '@T6G_MB_LIB.T6G(SCH_1):PAGE55_I182@PURE_QUANTA.GENOA_SP5(CHIPS)':
 'PCIE_RST0_L||AGPIO266': CDS_PINID='\pcie_rst0_l||agpio266\';
NODE_NAME     R197 1
 '@T6G_MB_LIB.T6G(SCH_1):PAGE80_I120@PURE_QUANTA.Q_RES(CHIPS)':
 'A': CDS_PINID='A';
NODE_NAME     R18 1
 '@T6G_MB_LIB.T6G(SCH_1):PAGE82_I126@PURE_QUANTA.Q_RES(CHIPS)':
 'A': CDS_PINID='A';
NET_NAME
'RST_CPU1_PERST0_R_N'
 '@T6G_MB_LIB.T6G(SCH_1):RST_CPU1_PERST0_R_N':
 C_SIGNAL='@t6g_mb_lib.t6g(sch_1):rst_cpu1_perst0_r_n';
NODE_NAME     R197 2
 '@T6G_MB_LIB.T6G(SCH_1):PAGE80_I120@PURE_QUANTA.Q_RES(CHIPS)':
 'B': CDS_PINID='B';
NODE_NAME     U18 E19
 '@T6G_MB_LIB.T6G(SCH_1):PAGE80_I217@PURE_QUANTA.LCMXO3LF9400C5BG484C(CHIPS)':
 'PR4C': CDS_PINID='PR4C';
NET_NAME
'RST_CPU1_PERST1_N'
 '@T6G_MB_LIB.T6G(SCH_1):RST_CPU1_PERST1_N':
 C_SIGNAL='@t6g_mb_lib.t6g(sch_1):rst_cpu1_perst1_n';
NODE_NAME     U26 DG36
 '@T6G_MB_LIB.T6G(SCH_1):PAGE55_I182@PURE_QUANTA.GENOA_SP5(CHIPS)':
 'PCIE_RST1_L||AGPIO26': CDS_PINID='\pcie_rst1_l||agpio26\';
NODE_NAME     R198 1
 '@T6G_MB_LIB.T6G(SCH_1):PAGE80_I122@PURE_QUANTA.Q_RES(CHIPS)':
 'A': CDS_PINID='A';
NODE_NAME     R19 1
 '@T6G_MB_LIB.T6G(SCH_1):PAGE82_I128@PURE_QUANTA.Q_RES(CHIPS)':
 'A': CDS_PINID='A';
NET_NAME
'RST_CPU1_PERST1_R_N'
 '@T6G_MB_LIB.T6G(SCH_1):RST_CPU1_PERST1_R_N':
 C_SIGNAL='@t6g_mb_lib.t6g(sch_1):rst_cpu1_perst1_r_n';
NODE_NAME     R198 2
 '@T6G_MB_LIB.T6G(SCH_1):PAGE80_I122@PURE_QUANTA.Q_RES(CHIPS)':
 'B': CDS_PINID='B';
NODE_NAME     U18 G16
 '@T6G_MB_LIB.T6G(SCH_1):PAGE80_I217@PURE_QUANTA.LCMXO3LF9400C5BG484C(CHIPS)':
 'PR2D': CDS_PINID='PR2D';
NET_NAME
'RST_CPU1_RESETL_N'
 '@T6G_MB_LIB.T6G(SCH_1):RST_CPU1_RESETL_N':
 C_SIGNAL='@t6g_mb_lib.t6g(sch_1):rst_cpu1_resetl_n';
NODE_NAME     U26 B67
 '@T6G_MB_LIB.T6G(SCH_1):PAGE55_I182@PURE_QUANTA.GENOA_SP5(CHIPS)':
 'RESET_L': CDS_PINID='RESET_L';
NODE_NAME     R57 1
 '@T6G_MB_LIB.T6G(SCH_1):PAGE80_I113@PURE_QUANTA.Q_RES(CHIPS)':
 'A': CDS_PINID='A';
NODE_NAME     R556 2
 '@T6G_MB_LIB.T6G(SCH_1):PAGE55_I357@PURE_QUANTA.Q_RES(CHIPS)':
 'B': CDS_PINID='B';
NODE_NAME     R530 2
 '@T6G_MB_LIB.T6G(SCH_1):PAGE84_I27@PURE_QUANTA.Q_RES(CHIPS)':
 'B': CDS_PINID='B';
NET_NAME
'RST_CPU1_RSMRST_N'
 '@T6G_MB_LIB.T6G(SCH_1):RST_CPU1_RSMRST_N':
 C_SIGNAL='@t6g_mb_lib.t6g(sch_1):rst_cpu1_rsmrst_n';
NODE_NAME     U26 DG10
 '@T6G_MB_LIB.T6G(SCH_1):PAGE55_I182@PURE_QUANTA.GENOA_SP5(CHIPS)':
 'RSMRST_L': CDS_PINID='RSMRST_L';
NODE_NAME     R273 1
 '@T6G_MB_LIB.T6G(SCH_1):PAGE80_I119@PURE_QUANTA.Q_RES(CHIPS)':
 'A': CDS_PINID='A';
NODE_NAME     R584 2
 '@T6G_MB_LIB.T6G(SCH_1):PAGE55_I341@PURE_QUANTA.Q_RES(CHIPS)':
 'B': CDS_PINID='B';
NODE_NAME     R583 1
 '@T6G_MB_LIB.T6G(SCH_1):PAGE55_I342@PURE_QUANTA.Q_RES(CHIPS)':
 'A': CDS_PINID='A';
NODE_NAME     C5024 1
 '@T6G_MB_LIB.T6G(SCH_1):PAGE55_I388@PURE_QUANTA.Q_CAP(CHIPS)':
 'A': CDS_PINID='A';
NET_NAME
'RST_CPU1_SYS_N'
 '@T6G_MB_LIB.T6G(SCH_1):RST_CPU1_SYS_N':
 C_SIGNAL='@t6g_mb_lib.t6g(sch_1):rst_cpu1_sys_n';
NODE_NAME     U26 DH6
 '@T6G_MB_LIB.T6G(SCH_1):PAGE55_I182@PURE_QUANTA.GENOA_SP5(CHIPS)':
 'SYS_RESET_L||AGPIO1': CDS_PINID='\sys_reset_l||agpio1\';
NODE_NAME     R272 1
 '@T6G_MB_LIB.T6G(SCH_1):PAGE80_I115@PURE_QUANTA.Q_RES(CHIPS)':
 'A': CDS_PINID='A';
NODE_NAME     R559 2
 '@T6G_MB_LIB.T6G(SCH_1):PAGE55_I356@PURE_QUANTA.Q_RES(CHIPS)':
 'B': CDS_PINID='B';
NET_NAME
'RST_ESPI_CPU0_RSTOUT_N'
 '@T6G_MB_LIB.T6G(SCH_1):RST_ESPI_CPU0_RSTOUT_N':
 C_SIGNAL='@t6g_mb_lib.t6g(sch_1):rst_espi_cpu0_rstout_n';
NODE_NAME     R457 2
 '@T6G_MB_LIB.T6G(SCH_1):PAGE29_I282@PURE_QUANTA.Q_RES(CHIPS)':
 'B': CDS_PINID='B';
NODE_NAME     R474 1
 '@T6G_MB_LIB.T6G(SCH_1):PAGE29_I332@PURE_QUANTA.Q_RES(CHIPS)':
 'A': CDS_PINID='A';
NODE_NAME     J41 B4
 '@T6G_MB_LIB.T6G(SCH_1):PAGE348_I176@PURE_QUANTA.SCONN168_ME1016810202011(CHIPS)':
 '+12V_EDGE_B4': CDS_PINID='\+12v_edge_b4\';
NODE_NAME     R1558 2
 '@T6G_MB_LIB.T6G(SCH_1):PAGE80_I172@PURE_QUANTA.Q_RES(CHIPS)':
 'B': CDS_PINID='B';
NET_NAME
'RST_ESPI_CPU0_RSTOUT_R_N'
 '@T6G_MB_LIB.T6G(SCH_1):RST_ESPI_CPU0_RSTOUT_R_N':
 C_SIGNAL='@t6g_mb_lib.t6g(sch_1):rst_espi_cpu0_rstout_r_n';
NODE_NAME     R1558 1
 '@T6G_MB_LIB.T6G(SCH_1):PAGE80_I172@PURE_QUANTA.Q_RES(CHIPS)':
 'A': CDS_PINID='A';
NODE_NAME     U18 T22
 '@T6G_MB_LIB.T6G(SCH_1):PAGE80_I217@PURE_QUANTA.LCMXO3LF9400C5BG484C(CHIPS)':
 'PR21A': CDS_PINID='PR21A';
NET_NAME
'RST_ESPI_CPU0_R_RSTOUT_N'
 '@T6G_MB_LIB.T6G(SCH_1):RST_ESPI_CPU0_R_RSTOUT_N':
 C_SIGNAL='@t6g_mb_lib.t6g(sch_1):rst_espi_cpu0_r_rstout_n';
NODE_NAME     U25 DE27
 '@T6G_MB_LIB.T6G(SCH_1):PAGE29_I287@PURE_QUANTA.GENOA_SP5(CHIPS)':
 'ESPI_RSTOUT_L||AGPIO23': CDS_PINID='\espi_rstout_l||agpio23\';
NODE_NAME     R474 2
 '@T6G_MB_LIB.T6G(SCH_1):PAGE29_I332@PURE_QUANTA.Q_RES(CHIPS)':
 'B': CDS_PINID='B';
NET_NAME
'RST_HP_OCP_SFF_R_N'
 '@T6G_MB_LIB.T6G(SCH_1):RST_HP_OCP_SFF_R_N':
 C_SIGNAL='@t6g_mb_lib.t6g(sch_1):rst_hp_ocp_sff_r_n';
NODE_NAME     R3232 1
 '@T6G_MB_LIB.T6G(SCH_1):PAGE336_I152@PURE_QUANTA.Q_RES(CHIPS)':
 'A': CDS_PINID='A';
NODE_NAME     R3233 1
 '@T6G_MB_LIB.T6G(SCH_1):PAGE336_I153@PURE_QUANTA.Q_RES(CHIPS)':
 'A': CDS_PINID='A';
NODE_NAME     U224 4
 '@T6G_MB_LIB.T6G(SCH_1):PAGE336_I159@PURE_QUANTA.74LVC1G126SE7(CHIPS)':
 'Y': CDS_PINID='Y';
NET_NAME
'RST_HP_OCP_V3_2_R_N'
 '@T6G_MB_LIB.T6G(SCH_1):RST_HP_OCP_V3_2_R_N':
 C_SIGNAL='@t6g_mb_lib.t6g(sch_1):rst_hp_ocp_v3_2_r_n';
NODE_NAME     R3235 1
 '@T6G_MB_LIB.T6G(SCH_1):PAGE342_I24@PURE_QUANTA.Q_RES(CHIPS)':
 'A': CDS_PINID='A';
NODE_NAME     U225 4
 '@T6G_MB_LIB.T6G(SCH_1):PAGE342_I9@PURE_QUANTA.74LVC1G126SE7(CHIPS)':
 'Y': CDS_PINID='Y';
NODE_NAME     R3236 1
 '@T6G_MB_LIB.T6G(SCH_1):PAGE342_I25@PURE_QUANTA.Q_RES(CHIPS)':
 'A': CDS_PINID='A';
NET_NAME
'RST_MB_STBY_N'
 '@T6G_MB_LIB.T6G(SCH_1):RST_MB_STBY_N':
 C_SIGNAL='@t6g_mb_lib.t6g(sch_1):rst_mb_stby_n';
NODE_NAME     R6033 1
 '@T6G_MB_LIB.T6G(SCH_1):PAGE348_I30@PURE_QUANTA.Q_RES(CHIPS)':
 'A': CDS_PINID='A';
NODE_NAME     R1546 2
 '@T6G_MB_LIB.T6G(SCH_1):PAGE349_I30@PURE_QUANTA.Q_RES(CHIPS)':
 'B': CDS_PINID='B';
NODE_NAME     U18 D13
 '@T6G_MB_LIB.T6G(SCH_1):PAGE79_I94@PURE_QUANTA.LCMXO3LF9400C5BG484C(CHIPS)':
 'PT29D': CDS_PINID='PT29D';
NET_NAME
'RST_MB_STBY_R_N'
 '@T6G_MB_LIB.T6G(SCH_1):RST_MB_STBY_R_N':
 C_SIGNAL='@t6g_mb_lib.t6g(sch_1):rst_mb_stby_r_n';
NODE_NAME     R6033 2
 '@T6G_MB_LIB.T6G(SCH_1):PAGE348_I30@PURE_QUANTA.Q_RES(CHIPS)':
 'B': CDS_PINID='B';
NODE_NAME     J41 A46
 '@T6G_MB_LIB.T6G(SCH_1):PAGE348_I176@PURE_QUANTA.SCONN168_ME1016810202011(CHIPS)':
 'GND_A46': CDS_PINID='GND_A46';
NET_NAME
'RST_PCIE_E1S_PERST_N'
 '@T6G_MB_LIB.T6G(SCH_1):RST_PCIE_E1S_PERST_N':
 C_SIGNAL='@t6g_mb_lib.t6g(sch_1):rst_pcie_e1s_perst_n';
NODE_NAME     R3779 2
 '@T6G_MB_LIB.T6G(SCH_1):PAGE297_I30@PURE_QUANTA.Q_RES(CHIPS)':
 'B': CDS_PINID='B';
NODE_NAME     J90 B10
 '@T6G_MB_LIB.T6G(SCH_1):PAGE297_I90@PURE_QUANTA.SCONN56_123276793(CHIPS)':
 'PERST0#': CDS_PINID='\perst0#\';
NET_NAME
'RST_PERST0_OCP_SFF_N'
 '@T6G_MB_LIB.T6G(SCH_1):RST_PERST0_OCP_SFF_N':
 C_SIGNAL='@t6g_mb_lib.t6g(sch_1):rst_perst0_ocp_sff_n';
NODE_NAME     J38 B10
 '@T6G_MB_LIB.T6G(SCH_1):PAGE335_I168@PURE_QUANTA.SCONN168_ME1016810202011(CHIPS)':
 'PERST0#': CDS_PINID='\perst0#\';
NODE_NAME     R877 2
 '@T6G_MB_LIB.T6G(SCH_1):PAGE337_I79@PURE_QUANTA.Q_RES(CHIPS)':
 'B': CDS_PINID='B';
NET_NAME
'RST_PERST0_OCP_V3_2_N'
 '@T6G_MB_LIB.T6G(SCH_1):RST_PERST0_OCP_V3_2_N':
 C_SIGNAL='@t6g_mb_lib.t6g(sch_1):rst_perst0_ocp_v3_2_n';
NODE_NAME     J35 B10
 '@T6G_MB_LIB.T6G(SCH_1):PAGE341_I168@PURE_QUANTA.SCONN168_ME1016810202011(CHIPS)':
 'PERST0#': CDS_PINID='\perst0#\';
NODE_NAME     R6056 2
 '@T6G_MB_LIB.T6G(SCH_1):PAGE342_I72@PURE_QUANTA.Q_RES(CHIPS)':
 'B': CDS_PINID='B';
NET_NAME
'RST_PERST1_OCP_SFF_N'
 '@T6G_MB_LIB.T6G(SCH_1):RST_PERST1_OCP_SFF_N':
 C_SIGNAL='@t6g_mb_lib.t6g(sch_1):rst_perst1_ocp_sff_n';
NODE_NAME     J38 A11
 '@T6G_MB_LIB.T6G(SCH_1):PAGE335_I168@PURE_QUANTA.SCONN168_ME1016810202011(CHIPS)':
 'PERST1#': CDS_PINID='\perst1#\';
NODE_NAME     R899 2
 '@T6G_MB_LIB.T6G(SCH_1):PAGE337_I78@PURE_QUANTA.Q_RES(CHIPS)':
 'B': CDS_PINID='B';
NET_NAME
'RST_PERST1_OCP_V3_2_N'
 '@T6G_MB_LIB.T6G(SCH_1):RST_PERST1_OCP_V3_2_N':
 C_SIGNAL='@t6g_mb_lib.t6g(sch_1):rst_perst1_ocp_v3_2_n';
NODE_NAME     J35 A11
 '@T6G_MB_LIB.T6G(SCH_1):PAGE341_I168@PURE_QUANTA.SCONN168_ME1016810202011(CHIPS)':
 'PERST1#': CDS_PINID='\perst1#\';
NODE_NAME     R6057 2
 '@T6G_MB_LIB.T6G(SCH_1):PAGE342_I73@PURE_QUANTA.Q_RES(CHIPS)':
 'B': CDS_PINID='B';
NET_NAME
'RST_PERST2_OCP_SFF_N'
 '@T6G_MB_LIB.T6G(SCH_1):RST_PERST2_OCP_SFF_N':
 C_SIGNAL='@t6g_mb_lib.t6g(sch_1):rst_perst2_ocp_sff_n';
NODE_NAME     J38 OA1
 '@T6G_MB_LIB.T6G(SCH_1):PAGE335_I168@PURE_QUANTA.SCONN168_ME1016810202011(CHIPS)':
 'PERST2#': CDS_PINID='\perst2#\';
NODE_NAME     R905 2
 '@T6G_MB_LIB.T6G(SCH_1):PAGE337_I80@PURE_QUANTA.Q_RES(CHIPS)':
 'B': CDS_PINID='B';
NET_NAME
'RST_PERST2_OCP_V3_2_N'
 '@T6G_MB_LIB.T6G(SCH_1):RST_PERST2_OCP_V3_2_N':
 C_SIGNAL='@t6g_mb_lib.t6g(sch_1):rst_perst2_ocp_v3_2_n';
NODE_NAME     J35 OA1
 '@T6G_MB_LIB.T6G(SCH_1):PAGE341_I168@PURE_QUANTA.SCONN168_ME1016810202011(CHIPS)':
 'PERST2#': CDS_PINID='\perst2#\';
NODE_NAME     R6058 2
 '@T6G_MB_LIB.T6G(SCH_1):PAGE342_I74@PURE_QUANTA.Q_RES(CHIPS)':
 'B': CDS_PINID='B';
NET_NAME
'RST_PERST3_OCP_SFF_N'
 '@T6G_MB_LIB.T6G(SCH_1):RST_PERST3_OCP_SFF_N':
 C_SIGNAL='@t6g_mb_lib.t6g(sch_1):rst_perst3_ocp_sff_n';
NODE_NAME     J38 OA2
 '@T6G_MB_LIB.T6G(SCH_1):PAGE335_I168@PURE_QUANTA.SCONN168_ME1016810202011(CHIPS)':
 'PERST3#': CDS_PINID='\perst3#\';
NODE_NAME     R956 2
 '@T6G_MB_LIB.T6G(SCH_1):PAGE337_I81@PURE_QUANTA.Q_RES(CHIPS)':
 'B': CDS_PINID='B';
NET_NAME
'RST_PERST3_OCP_V3_2_N'
 '@T6G_MB_LIB.T6G(SCH_1):RST_PERST3_OCP_V3_2_N':
 C_SIGNAL='@t6g_mb_lib.t6g(sch_1):rst_perst3_ocp_v3_2_n';
NODE_NAME     J35 OA2
 '@T6G_MB_LIB.T6G(SCH_1):PAGE341_I168@PURE_QUANTA.SCONN168_ME1016810202011(CHIPS)':
 'PERST3#': CDS_PINID='\perst3#\';
NODE_NAME     R6059 2
 '@T6G_MB_LIB.T6G(SCH_1):PAGE342_I75@PURE_QUANTA.Q_RES(CHIPS)':
 'B': CDS_PINID='B';
NET_NAME
'RST_PERST_0_SWB_BUF_N'
 '@T6G_MB_LIB.T6G(SCH_1):RST_PERST_0_SWB_BUF_N':
 C_SIGNAL='@t6g_mb_lib.t6g(sch_1):rst_perst_0_swb_buf_n';
NODE_NAME     R3469 2
 '@T6G_MB_LIB.T6G(SCH_1):PAGE334_I180@PURE_QUANTA.Q_RES(CHIPS)':
 'B': CDS_PINID='B';
NODE_NAME     J112 T8
 '@T6G_MB_LIB.T6G(SCH_1):PAGE329_I7@PURE_QUANTA.CONN160_10131762101LF(CHIPS)':
 'T8': CDS_PINID='T8';
NET_NAME
'RST_PERST_0_SWB_BUF_R_N'
 '@T6G_MB_LIB.T6G(SCH_1):RST_PERST_0_SWB_BUF_R_N':
 C_SIGNAL='@t6g_mb_lib.t6g(sch_1):rst_perst_0_swb_buf_r_n';
NODE_NAME     U252 6
 '@T6G_MB_LIB.T6G(SCH_1):PAGE334_I153@PURE_QUANTA.74LVC2G17GW(CHIPS)':
 'B0': CDS_PINID='B0';
NODE_NAME     R3469 1
 '@T6G_MB_LIB.T6G(SCH_1):PAGE334_I180@PURE_QUANTA.Q_RES(CHIPS)':
 'A': CDS_PINID='A';
NODE_NAME     R3467 1
 '@T6G_MB_LIB.T6G(SCH_1):PAGE334_I181@PURE_QUANTA.Q_RES(CHIPS)':
 'A': CDS_PINID='A';
NET_NAME
'RST_PERST_1_SWB_BUF_N'
 '@T6G_MB_LIB.T6G(SCH_1):RST_PERST_1_SWB_BUF_N':
 C_SIGNAL='@t6g_mb_lib.t6g(sch_1):rst_perst_1_swb_buf_n';
NODE_NAME     R3468 2
 '@T6G_MB_LIB.T6G(SCH_1):PAGE334_I183@PURE_QUANTA.Q_RES(CHIPS)':
 'B': CDS_PINID='B';
NODE_NAME     J112 A5
 '@T6G_MB_LIB.T6G(SCH_1):PAGE329_I7@PURE_QUANTA.CONN160_10131762101LF(CHIPS)':
 'A5': CDS_PINID='A5';
NET_NAME
'RST_PERST_1_SWB_BUF_R_N'
 '@T6G_MB_LIB.T6G(SCH_1):RST_PERST_1_SWB_BUF_R_N':
 C_SIGNAL='@t6g_mb_lib.t6g(sch_1):rst_perst_1_swb_buf_r_n';
NODE_NAME     U256 6
 '@T6G_MB_LIB.T6G(SCH_1):PAGE334_I173@PURE_QUANTA.74LVC2G17GW(CHIPS)':
 'B0': CDS_PINID='B0';
NODE_NAME     R3468 1
 '@T6G_MB_LIB.T6G(SCH_1):PAGE334_I183@PURE_QUANTA.Q_RES(CHIPS)':
 'A': CDS_PINID='A';
NODE_NAME     R3466 1
 '@T6G_MB_LIB.T6G(SCH_1):PAGE334_I184@PURE_QUANTA.Q_RES(CHIPS)':
 'A': CDS_PINID='A';
NET_NAME
'RST_PERST_2_SWB_BUF_N'
 '@T6G_MB_LIB.T6G(SCH_1):RST_PERST_2_SWB_BUF_N':
 C_SIGNAL='@t6g_mb_lib.t6g(sch_1):rst_perst_2_swb_buf_n';
NODE_NAME     R3391 2
 '@T6G_MB_LIB.T6G(SCH_1):PAGE334_I140@PURE_QUANTA.Q_RES(CHIPS)':
 'B': CDS_PINID='B';
NODE_NAME     J112 A1
 '@T6G_MB_LIB.T6G(SCH_1):PAGE329_I102@PURE_QUANTA.CONN160_10131762101LF(CHIPS)':
 'A1': CDS_PINID='A1';
NET_NAME
'RST_PERST_2_SWB_BUF_R_N'
 '@T6G_MB_LIB.T6G(SCH_1):RST_PERST_2_SWB_BUF_R_N':
 C_SIGNAL='@t6g_mb_lib.t6g(sch_1):rst_perst_2_swb_buf_r_n';
NODE_NAME     R3455 1
 '@T6G_MB_LIB.T6G(SCH_1):PAGE334_I139@PURE_QUANTA.Q_RES(CHIPS)':
 'A': CDS_PINID='A';
NODE_NAME     R3391 1
 '@T6G_MB_LIB.T6G(SCH_1):PAGE334_I140@PURE_QUANTA.Q_RES(CHIPS)':
 'A': CDS_PINID='A';
NODE_NAME     U252 4
 '@T6G_MB_LIB.T6G(SCH_1):PAGE334_I153@PURE_QUANTA.74LVC2G17GW(CHIPS)':
 'B1': CDS_PINID='B1';
NET_NAME
'RST_PERST_BUF_M2_0_N'
 '@T6G_MB_LIB.T6G(SCH_1):RST_PERST_BUF_M2_0_N':
 C_SIGNAL='@t6g_mb_lib.t6g(sch_1):rst_perst_buf_m2_0_n';
NODE_NAME     U259 4
 '@T6G_MB_LIB.T6G(SCH_1):PAGE345_I5@PURE_QUANTA.SN74LVC2G07DCKR(CHIPS)':
 '2Y': CDS_PINID='\2y\';
NODE_NAME     R2121 2
 '@T6G_MB_LIB.T6G(SCH_1):PAGE345_I10@PURE_QUANTA.Q_RES(CHIPS)':
 'B': CDS_PINID='B';
NODE_NAME     R2113 1
 '@T6G_MB_LIB.T6G(SCH_1):PAGE345_I12@PURE_QUANTA.Q_RES(CHIPS)':
 'A': CDS_PINID='A';
NET_NAME
'RST_PERST_BUF_M2_0_R_N'
 '@T6G_MB_LIB.T6G(SCH_1):RST_PERST_BUF_M2_0_R_N':
 C_SIGNAL='@t6g_mb_lib.t6g(sch_1):rst_perst_buf_m2_0_r_n';
NODE_NAME     J59 50
 '@T6G_MB_LIB.T6G(SCH_1):PAGE345_I88@PURE_QUANTA.SCONN75K_APCI0155P004A(CHIPS)':
 'PERST#': CDS_PINID='\perst#\';
NODE_NAME     R2113 2
 '@T6G_MB_LIB.T6G(SCH_1):PAGE345_I12@PURE_QUANTA.Q_RES(CHIPS)':
 'B': CDS_PINID='B';
NET_NAME
'RST_PERST_CPU0_SWB_N'
 '@T6G_MB_LIB.T6G(SCH_1):RST_PERST_CPU0_SWB_N':
 C_SIGNAL='@t6g_mb_lib.t6g(sch_1):rst_perst_cpu0_swb_n';
NODE_NAME     U18 T14
 '@T6G_MB_LIB.T6G(SCH_1):PAGE80_I216@PURE_QUANTA.LCMXO3LF9400C5BG484C(CHIPS)':
 'PB32B': CDS_PINID='PB32B';
NODE_NAME     R6114 1
 '@T6G_MB_LIB.T6G(SCH_1):PAGE82_I137@PURE_QUANTA.Q_RES(CHIPS)':
 'A': CDS_PINID='A';
NODE_NAME     R6112 1
 '@T6G_MB_LIB.T6G(SCH_1):PAGE84_I91@PURE_QUANTA.Q_RES(CHIPS)':
 'A': CDS_PINID='A';
NET_NAME
'RST_PERST_CPU0_SWB_R_N'
 '@T6G_MB_LIB.T6G(SCH_1):RST_PERST_CPU0_SWB_R_N':
 C_SIGNAL='@t6g_mb_lib.t6g(sch_1):rst_perst_cpu0_swb_r_n';
NODE_NAME     U256 1
 '@T6G_MB_LIB.T6G(SCH_1):PAGE334_I173@PURE_QUANTA.74LVC2G17GW(CHIPS)':
 'A0': CDS_PINID='A0';
NODE_NAME     R6112 2
 '@T6G_MB_LIB.T6G(SCH_1):PAGE84_I91@PURE_QUANTA.Q_RES(CHIPS)':
 'B': CDS_PINID='B';
NET_NAME
'RST_PERST_CPU1_SWB_1_N'
 '@T6G_MB_LIB.T6G(SCH_1):RST_PERST_CPU1_SWB_1_N':
 C_SIGNAL='@t6g_mb_lib.t6g(sch_1):rst_perst_cpu1_swb_1_n';
NODE_NAME     U18 V11
 '@T6G_MB_LIB.T6G(SCH_1):PAGE80_I216@PURE_QUANTA.LCMXO3LF9400C5BG484C(CHIPS)':
 'PB24C': CDS_PINID='PB24C';
NODE_NAME     R2 1
 '@T6G_MB_LIB.T6G(SCH_1):PAGE84_I94@PURE_QUANTA.Q_RES(CHIPS)':
 'A': CDS_PINID='A';
NODE_NAME     R3 1
 '@T6G_MB_LIB.T6G(SCH_1):PAGE82_I154@PURE_QUANTA.Q_RES(CHIPS)':
 'A': CDS_PINID='A';
NET_NAME
'RST_PERST_CPU1_SWB_1_R_N'
 '@T6G_MB_LIB.T6G(SCH_1):RST_PERST_CPU1_SWB_1_R_N':
 C_SIGNAL='@t6g_mb_lib.t6g(sch_1):rst_perst_cpu1_swb_1_r_n';
NODE_NAME     U252 3
 '@T6G_MB_LIB.T6G(SCH_1):PAGE334_I153@PURE_QUANTA.74LVC2G17GW(CHIPS)':
 'A1': CDS_PINID='A1';
NODE_NAME     R2 2
 '@T6G_MB_LIB.T6G(SCH_1):PAGE84_I94@PURE_QUANTA.Q_RES(CHIPS)':
 'B': CDS_PINID='B';
NET_NAME
'RST_PERST_CPU1_SWB_N'
 '@T6G_MB_LIB.T6G(SCH_1):RST_PERST_CPU1_SWB_N':
 C_SIGNAL='@t6g_mb_lib.t6g(sch_1):rst_perst_cpu1_swb_n';
NODE_NAME     U18 U14
 '@T6G_MB_LIB.T6G(SCH_1):PAGE80_I216@PURE_QUANTA.LCMXO3LF9400C5BG484C(CHIPS)':
 'PB32C': CDS_PINID='PB32C';
NODE_NAME     R6113 1
 '@T6G_MB_LIB.T6G(SCH_1):PAGE84_I75@PURE_QUANTA.Q_RES(CHIPS)':
 'A': CDS_PINID='A';
NODE_NAME     R6115 1
 '@T6G_MB_LIB.T6G(SCH_1):PAGE82_I141@PURE_QUANTA.Q_RES(CHIPS)':
 'A': CDS_PINID='A';
NET_NAME
'RST_PERST_CPU1_SWB_R_N'
 '@T6G_MB_LIB.T6G(SCH_1):RST_PERST_CPU1_SWB_R_N':
 C_SIGNAL='@t6g_mb_lib.t6g(sch_1):rst_perst_cpu1_swb_r_n';
NODE_NAME     U252 1
 '@T6G_MB_LIB.T6G(SCH_1):PAGE334_I153@PURE_QUANTA.74LVC2G17GW(CHIPS)':
 'A0': CDS_PINID='A0';
NODE_NAME     R6113 2
 '@T6G_MB_LIB.T6G(SCH_1):PAGE84_I75@PURE_QUANTA.Q_RES(CHIPS)':
 'B': CDS_PINID='B';
NET_NAME
'RST_PERST_E1S_0_N'
 '@T6G_MB_LIB.T6G(SCH_1):RST_PERST_E1S_0_N':
 C_SIGNAL='@t6g_mb_lib.t6g(sch_1):rst_perst_e1s_0_n';
NODE_NAME     R3779 1
 '@T6G_MB_LIB.T6G(SCH_1):PAGE297_I30@PURE_QUANTA.Q_RES(CHIPS)':
 'A': CDS_PINID='A';
NODE_NAME     R685 2
 '@T6G_MB_LIB.T6G(SCH_1):PAGE80_I131@PURE_QUANTA.Q_RES(CHIPS)':
 'B': CDS_PINID='B';
NODE_NAME     R800 1
 '@T6G_MB_LIB.T6G(SCH_1):PAGE82_I118@PURE_QUANTA.Q_RES(CHIPS)':
 'A': CDS_PINID='A';
NET_NAME
'RST_PERST_E1S_0_R_N'
 '@T6G_MB_LIB.T6G(SCH_1):RST_PERST_E1S_0_R_N':
 C_SIGNAL='@t6g_mb_lib.t6g(sch_1):rst_perst_e1s_0_r_n';
NODE_NAME     R685 1
 '@T6G_MB_LIB.T6G(SCH_1):PAGE80_I131@PURE_QUANTA.Q_RES(CHIPS)':
 'A': CDS_PINID='A';
NODE_NAME     U18 AA13
 '@T6G_MB_LIB.T6G(SCH_1):PAGE80_I216@PURE_QUANTA.LCMXO3LF9400C5BG484C(CHIPS)':
 'PB30B': CDS_PINID='PB30B';
NET_NAME
'RST_PERST_M2_0_N'
 '@T6G_MB_LIB.T6G(SCH_1):RST_PERST_M2_0_N':
 C_SIGNAL='@t6g_mb_lib.t6g(sch_1):rst_perst_m2_0_n';
NODE_NAME     R798 2
 '@T6G_MB_LIB.T6G(SCH_1):PAGE80_I125@PURE_QUANTA.Q_RES(CHIPS)':
 'B': CDS_PINID='B';
NODE_NAME     U259 3
 '@T6G_MB_LIB.T6G(SCH_1):PAGE345_I5@PURE_QUANTA.SN74LVC2G07DCKR(CHIPS)':
 '2A': CDS_PINID='\2a\';
NODE_NAME     R804 1
 '@T6G_MB_LIB.T6G(SCH_1):PAGE82_I120@PURE_QUANTA.Q_RES(CHIPS)':
 'A': CDS_PINID='A';
NET_NAME
'RST_PERST_M2_0_R_N'
 '@T6G_MB_LIB.T6G(SCH_1):RST_PERST_M2_0_R_N':
 C_SIGNAL='@t6g_mb_lib.t6g(sch_1):rst_perst_m2_0_r_n';
NODE_NAME     R798 1
 '@T6G_MB_LIB.T6G(SCH_1):PAGE80_I125@PURE_QUANTA.Q_RES(CHIPS)':
 'A': CDS_PINID='A';
NODE_NAME     U18 V16
 '@T6G_MB_LIB.T6G(SCH_1):PAGE80_I216@PURE_QUANTA.LCMXO3LF9400C5BG484C(CHIPS)':
 'PB40D': CDS_PINID='PB40D';
NET_NAME
'RST_PERST_OCP_SFF_BUF2_N'
 '@T6G_MB_LIB.T6G(SCH_1):RST_PERST_OCP_SFF_BUF2_N':
 C_SIGNAL='@t6g_mb_lib.t6g(sch_1):rst_perst_ocp_sff_buf2_n';
NODE_NAME     U75 4
 '@T6G_MB_LIB.T6G(SCH_1):PAGE337_I64@PURE_QUANTA.74LVC1G17GW(CHIPS)':
 'Y': CDS_PINID='Y';
NODE_NAME     R899 1
 '@T6G_MB_LIB.T6G(SCH_1):PAGE337_I78@PURE_QUANTA.Q_RES(CHIPS)':
 'A': CDS_PINID='A';
NODE_NAME     R877 1
 '@T6G_MB_LIB.T6G(SCH_1):PAGE337_I79@PURE_QUANTA.Q_RES(CHIPS)':
 'A': CDS_PINID='A';
NODE_NAME     R905 1
 '@T6G_MB_LIB.T6G(SCH_1):PAGE337_I80@PURE_QUANTA.Q_RES(CHIPS)':
 'A': CDS_PINID='A';
NODE_NAME     R956 1
 '@T6G_MB_LIB.T6G(SCH_1):PAGE337_I81@PURE_QUANTA.Q_RES(CHIPS)':
 'A': CDS_PINID='A';
NET_NAME
'RST_PERST_OCP_SFF_BUF_N'
 '@T6G_MB_LIB.T6G(SCH_1):RST_PERST_OCP_SFF_BUF_N':
 C_SIGNAL='@t6g_mb_lib.t6g(sch_1):rst_perst_ocp_sff_buf_n';
NODE_NAME     U75 2
 '@T6G_MB_LIB.T6G(SCH_1):PAGE337_I64@PURE_QUANTA.74LVC1G17GW(CHIPS)':
 'A': CDS_PINID='A';
NODE_NAME     R9033 2
 '@T6G_MB_LIB.T6G(SCH_1):PAGE340_I29@PURE_QUANTA.Q_RES(CHIPS)':
 'B': CDS_PINID='B';
NET_NAME
'RST_PERST_OCP_SFF_BUF_R_N'
 '@T6G_MB_LIB.T6G(SCH_1):RST_PERST_OCP_SFF_BUF_R_N':
 C_SIGNAL='@t6g_mb_lib.t6g(sch_1):rst_perst_ocp_sff_buf_r_n';
NODE_NAME     U9001 4
 '@T6G_MB_LIB.T6G(SCH_1):PAGE340_I25@PURE_QUANTA.74LVC1G08W57(CHIPS)':
 'Y': CDS_PINID='Y';
NODE_NAME     R9033 1
 '@T6G_MB_LIB.T6G(SCH_1):PAGE340_I29@PURE_QUANTA.Q_RES(CHIPS)':
 'A': CDS_PINID='A';
NET_NAME
'RST_PERST_OCP_SFF_N'
 '@T6G_MB_LIB.T6G(SCH_1):RST_PERST_OCP_SFF_N':
 C_SIGNAL='@t6g_mb_lib.t6g(sch_1):rst_perst_ocp_sff_n';
NODE_NAME     U18 W17
 '@T6G_MB_LIB.T6G(SCH_1):PAGE80_I216@PURE_QUANTA.LCMXO3LF9400C5BG484C(CHIPS)':
 'PB41D': CDS_PINID='PB41D';
NODE_NAME     R9023 1
 '@T6G_MB_LIB.T6G(SCH_1):PAGE340_I14@PURE_QUANTA.Q_RES(CHIPS)':
 'A': CDS_PINID='A';
NET_NAME
'RST_PERST_OCP_SFF_R_N'
 '@T6G_MB_LIB.T6G(SCH_1):RST_PERST_OCP_SFF_R_N':
 C_SIGNAL='@t6g_mb_lib.t6g(sch_1):rst_perst_ocp_sff_r_n';
NODE_NAME     R9023 2
 '@T6G_MB_LIB.T6G(SCH_1):PAGE340_I14@PURE_QUANTA.Q_RES(CHIPS)':
 'B': CDS_PINID='B';
NODE_NAME     U9001 1
 '@T6G_MB_LIB.T6G(SCH_1):PAGE340_I25@PURE_QUANTA.74LVC1G08W57(CHIPS)':
 'A': CDS_PINID='A';
NET_NAME
'RST_PERST_OCP_V3_2_BUF2_N'
 '@T6G_MB_LIB.T6G(SCH_1):RST_PERST_OCP_V3_2_BUF2_N':
 C_SIGNAL='@t6g_mb_lib.t6g(sch_1):rst_perst_ocp_v3_2_buf2_n';
NODE_NAME     U207 4
 '@T6G_MB_LIB.T6G(SCH_1):PAGE342_I58@PURE_QUANTA.74LVC1G17GW(CHIPS)':
 'Y': CDS_PINID='Y';
NODE_NAME     R6056 1
 '@T6G_MB_LIB.T6G(SCH_1):PAGE342_I72@PURE_QUANTA.Q_RES(CHIPS)':
 'A': CDS_PINID='A';
NODE_NAME     R6057 1
 '@T6G_MB_LIB.T6G(SCH_1):PAGE342_I73@PURE_QUANTA.Q_RES(CHIPS)':
 'A': CDS_PINID='A';
NODE_NAME     R6058 1
 '@T6G_MB_LIB.T6G(SCH_1):PAGE342_I74@PURE_QUANTA.Q_RES(CHIPS)':
 'A': CDS_PINID='A';
NODE_NAME     R6059 1
 '@T6G_MB_LIB.T6G(SCH_1):PAGE342_I75@PURE_QUANTA.Q_RES(CHIPS)':
 'A': CDS_PINID='A';
NET_NAME
'RST_PERST_OCP_V3_2_BUF_N'
 '@T6G_MB_LIB.T6G(SCH_1):RST_PERST_OCP_V3_2_BUF_N':
 C_SIGNAL='@t6g_mb_lib.t6g(sch_1):rst_perst_ocp_v3_2_buf_n';
NODE_NAME     U207 2
 '@T6G_MB_LIB.T6G(SCH_1):PAGE342_I58@PURE_QUANTA.74LVC1G17GW(CHIPS)':
 'A': CDS_PINID='A';
NODE_NAME     R1177 2
 '@T6G_MB_LIB.T6G(SCH_1):PAGE257_I49@PURE_QUANTA.Q_RES(CHIPS)':
 'B': CDS_PINID='B';
NET_NAME
'RST_PERST_OCP_V3_2_BUF_R_N'
 '@T6G_MB_LIB.T6G(SCH_1):RST_PERST_OCP_V3_2_BUF_R_N':
 C_SIGNAL='@t6g_mb_lib.t6g(sch_1):rst_perst_ocp_v3_2_buf_r_n';
NODE_NAME     R1177 1
 '@T6G_MB_LIB.T6G(SCH_1):PAGE257_I49@PURE_QUANTA.Q_RES(CHIPS)':
 'A': CDS_PINID='A';
NODE_NAME     U35 4
 '@T6G_MB_LIB.T6G(SCH_1):PAGE257_I63@PURE_QUANTA.74LVC1G08W57(CHIPS)':
 'Y': CDS_PINID='Y';
NET_NAME
'RST_PERST_OCP_V3_2_N'
 '@T6G_MB_LIB.T6G(SCH_1):RST_PERST_OCP_V3_2_N':
 C_SIGNAL='@t6g_mb_lib.t6g(sch_1):rst_perst_ocp_v3_2_n';
NODE_NAME     U18 AA19
 '@T6G_MB_LIB.T6G(SCH_1):PAGE80_I216@PURE_QUANTA.LCMXO3LF9400C5BG484C(CHIPS)':
 'PB43B': CDS_PINID='PB43B';
NODE_NAME     R1174 1
 '@T6G_MB_LIB.T6G(SCH_1):PAGE257_I17@PURE_QUANTA.Q_RES(CHIPS)':
 'A': CDS_PINID='A';
NET_NAME
'RST_PERST_OCP_V3_2_R_N'
 '@T6G_MB_LIB.T6G(SCH_1):RST_PERST_OCP_V3_2_R_N':
 C_SIGNAL='@t6g_mb_lib.t6g(sch_1):rst_perst_ocp_v3_2_r_n';
NODE_NAME     R1174 2
 '@T6G_MB_LIB.T6G(SCH_1):PAGE257_I17@PURE_QUANTA.Q_RES(CHIPS)':
 'B': CDS_PINID='B';
NODE_NAME     U35 1
 '@T6G_MB_LIB.T6G(SCH_1):PAGE257_I63@PURE_QUANTA.74LVC1G08W57(CHIPS)':
 'A': CDS_PINID='A';
NET_NAME
'RST_RT_CPU0_P0_PERST_N'
 '@T6G_MB_LIB.T6G(SCH_1):RST_RT_CPU0_P0_PERST_N':
 C_SIGNAL='@t6g_mb_lib.t6g(sch_1):rst_rt_cpu0_p0_perst_n';
NODE_NAME     U6010 F2
 '@T6G_MB_LIB.T6G(SCH_1):PAGE385_I53@PURE_QUANTA.PT5161LRS(CHIPS)':
 'PERST_N': CDS_PINID='PERST_N';
NODE_NAME     R953 1
 '@T6G_MB_LIB.T6G(SCH_1):PAGE385_I76@PURE_QUANTA.Q_RES(CHIPS)':
 'A': CDS_PINID='A';
NET_NAME
'RST_RT_CPU0_P0_PERST_R2_N'
 '@T6G_MB_LIB.T6G(SCH_1):RST_RT_CPU0_P0_PERST_R2_N':
 C_SIGNAL='@t6g_mb_lib.t6g(sch_1):rst_rt_cpu0_p0_perst_r2_n';
NODE_NAME     U18 K22
 '@T6G_MB_LIB.T6G(SCH_1):PAGE80_I217@PURE_QUANTA.LCMXO3LF9400C5BG484C(CHIPS)':
 'PR16A': CDS_PINID='PR16A';
NODE_NAME     R6804 2
 '@T6G_MB_LIB.T6G(SCH_1):PAGE80_I342@PURE_QUANTA.Q_RES(CHIPS)':
 'B': CDS_PINID='B';
NET_NAME
'RST_RT_CPU0_P0_PERST_R_N'
 '@T6G_MB_LIB.T6G(SCH_1):RST_RT_CPU0_P0_PERST_R_N':
 C_SIGNAL='@t6g_mb_lib.t6g(sch_1):rst_rt_cpu0_p0_perst_r_n';
NODE_NAME     R953 2
 '@T6G_MB_LIB.T6G(SCH_1):PAGE385_I76@PURE_QUANTA.Q_RES(CHIPS)':
 'B': CDS_PINID='B';
NODE_NAME     R970 1
 '@T6G_MB_LIB.T6G(SCH_1):PAGE385_I97@PURE_QUANTA.Q_RES(CHIPS)':
 'A': CDS_PINID='A';
NODE_NAME     R6804 1
 '@T6G_MB_LIB.T6G(SCH_1):PAGE80_I342@PURE_QUANTA.Q_RES(CHIPS)':
 'A': CDS_PINID='A';
NET_NAME
'RST_RT_CPU0_P0_RESET_N'
 '@T6G_MB_LIB.T6G(SCH_1):RST_RT_CPU0_P0_RESET_N':
 C_SIGNAL='@t6g_mb_lib.t6g(sch_1):rst_rt_cpu0_p0_reset_n';
NODE_NAME     U6010 FF11
 '@T6G_MB_LIB.T6G(SCH_1):PAGE385_I53@PURE_QUANTA.PT5161LRS(CHIPS)':
 'RESET_N': CDS_PINID='RESET_N';
NODE_NAME     R963 1
 '@T6G_MB_LIB.T6G(SCH_1):PAGE385_I77@PURE_QUANTA.Q_RES(CHIPS)':
 'A': CDS_PINID='A';
NET_NAME
'RST_RT_CPU0_P0_RESET_R2_N'
 '@T6G_MB_LIB.T6G(SCH_1):RST_RT_CPU0_P0_RESET_R2_N':
 C_SIGNAL='@t6g_mb_lib.t6g(sch_1):rst_rt_cpu0_p0_reset_r2_n';
NODE_NAME     U18 L21
 '@T6G_MB_LIB.T6G(SCH_1):PAGE80_I217@PURE_QUANTA.LCMXO3LF9400C5BG484C(CHIPS)':
 'PR16B': CDS_PINID='PR16B';
NODE_NAME     R6805 2
 '@T6G_MB_LIB.T6G(SCH_1):PAGE80_I343@PURE_QUANTA.Q_RES(CHIPS)':
 'B': CDS_PINID='B';
NET_NAME
'RST_RT_CPU0_P0_RESET_R_N'
 '@T6G_MB_LIB.T6G(SCH_1):RST_RT_CPU0_P0_RESET_R_N':
 C_SIGNAL='@t6g_mb_lib.t6g(sch_1):rst_rt_cpu0_p0_reset_r_n';
NODE_NAME     R963 2
 '@T6G_MB_LIB.T6G(SCH_1):PAGE385_I77@PURE_QUANTA.Q_RES(CHIPS)':
 'B': CDS_PINID='B';
NODE_NAME     R971 1
 '@T6G_MB_LIB.T6G(SCH_1):PAGE385_I96@PURE_QUANTA.Q_RES(CHIPS)':
 'A': CDS_PINID='A';
NODE_NAME     R974 2
 '@T6G_MB_LIB.T6G(SCH_1):PAGE385_I98@PURE_QUANTA.Q_RES(CHIPS)':
 'B': CDS_PINID='B';
NODE_NAME     R6805 1
 '@T6G_MB_LIB.T6G(SCH_1):PAGE80_I343@PURE_QUANTA.Q_RES(CHIPS)':
 'A': CDS_PINID='A';
NET_NAME
'RST_RT_CPU0_P1_PERST_N'
 '@T6G_MB_LIB.T6G(SCH_1):RST_RT_CPU0_P1_PERST_N':
 C_SIGNAL='@t6g_mb_lib.t6g(sch_1):rst_rt_cpu0_p1_perst_n';
NODE_NAME     R1004 1
 '@T6G_MB_LIB.T6G(SCH_1):PAGE408_I56@PURE_QUANTA.Q_RES(CHIPS)':
 'A': CDS_PINID='A';
NODE_NAME     U6011 F2
 '@T6G_MB_LIB.T6G(SCH_1):PAGE408_I83@PURE_QUANTA.PT5161LRS(CHIPS)':
 'PERST_N': CDS_PINID='PERST_N';
NET_NAME
'RST_RT_CPU0_P1_PERST_R2_N'
 '@T6G_MB_LIB.T6G(SCH_1):RST_RT_CPU0_P1_PERST_R2_N':
 C_SIGNAL='@t6g_mb_lib.t6g(sch_1):rst_rt_cpu0_p1_perst_r2_n';
NODE_NAME     U18 L22
 '@T6G_MB_LIB.T6G(SCH_1):PAGE80_I217@PURE_QUANTA.LCMXO3LF9400C5BG484C(CHIPS)':
 'PR16C': CDS_PINID='PR16C';
NODE_NAME     R6806 2
 '@T6G_MB_LIB.T6G(SCH_1):PAGE80_I344@PURE_QUANTA.Q_RES(CHIPS)':
 'B': CDS_PINID='B';
NET_NAME
'RST_RT_CPU0_P1_PERST_R_N'
 '@T6G_MB_LIB.T6G(SCH_1):RST_RT_CPU0_P1_PERST_R_N':
 C_SIGNAL='@t6g_mb_lib.t6g(sch_1):rst_rt_cpu0_p1_perst_r_n';
NODE_NAME     R6806 1
 '@T6G_MB_LIB.T6G(SCH_1):PAGE80_I344@PURE_QUANTA.Q_RES(CHIPS)':
 'A': CDS_PINID='A';
NODE_NAME     R1004 2
 '@T6G_MB_LIB.T6G(SCH_1):PAGE408_I56@PURE_QUANTA.Q_RES(CHIPS)':
 'B': CDS_PINID='B';
NODE_NAME     R1019 1
 '@T6G_MB_LIB.T6G(SCH_1):PAGE408_I73@PURE_QUANTA.Q_RES(CHIPS)':
 'A': CDS_PINID='A';
NET_NAME
'RST_RT_CPU0_P1_RESET_N'
 '@T6G_MB_LIB.T6G(SCH_1):RST_RT_CPU0_P1_RESET_N':
 C_SIGNAL='@t6g_mb_lib.t6g(sch_1):rst_rt_cpu0_p1_reset_n';
NODE_NAME     R1012 1
 '@T6G_MB_LIB.T6G(SCH_1):PAGE408_I55@PURE_QUANTA.Q_RES(CHIPS)':
 'A': CDS_PINID='A';
NODE_NAME     U6011 FF11
 '@T6G_MB_LIB.T6G(SCH_1):PAGE408_I83@PURE_QUANTA.PT5161LRS(CHIPS)':
 'RESET_N': CDS_PINID='RESET_N';
NET_NAME
'RST_RT_CPU0_P1_RESET_R2_N'
 '@T6G_MB_LIB.T6G(SCH_1):RST_RT_CPU0_P1_RESET_R2_N':
 C_SIGNAL='@t6g_mb_lib.t6g(sch_1):rst_rt_cpu0_p1_reset_r2_n';
NODE_NAME     U18 M17
 '@T6G_MB_LIB.T6G(SCH_1):PAGE80_I217@PURE_QUANTA.LCMXO3LF9400C5BG484C(CHIPS)':
 'PR16D': CDS_PINID='PR16D';
NODE_NAME     R6807 2
 '@T6G_MB_LIB.T6G(SCH_1):PAGE80_I345@PURE_QUANTA.Q_RES(CHIPS)':
 'B': CDS_PINID='B';
NET_NAME
'RST_RT_CPU0_P1_RESET_R_N'
 '@T6G_MB_LIB.T6G(SCH_1):RST_RT_CPU0_P1_RESET_R_N':
 C_SIGNAL='@t6g_mb_lib.t6g(sch_1):rst_rt_cpu0_p1_reset_r_n';
NODE_NAME     R6807 1
 '@T6G_MB_LIB.T6G(SCH_1):PAGE80_I345@PURE_QUANTA.Q_RES(CHIPS)':
 'A': CDS_PINID='A';
NODE_NAME     R1012 2
 '@T6G_MB_LIB.T6G(SCH_1):PAGE408_I55@PURE_QUANTA.Q_RES(CHIPS)':
 'B': CDS_PINID='B';
NODE_NAME     R1020 1
 '@T6G_MB_LIB.T6G(SCH_1):PAGE408_I74@PURE_QUANTA.Q_RES(CHIPS)':
 'A': CDS_PINID='A';
NODE_NAME     R1023 2
 '@T6G_MB_LIB.T6G(SCH_1):PAGE408_I78@PURE_QUANTA.Q_RES(CHIPS)':
 'B': CDS_PINID='B';
NET_NAME
'RST_RT_CPU0_P2_PERST_N'
 '@T6G_MB_LIB.T6G(SCH_1):RST_RT_CPU0_P2_PERST_N':
 C_SIGNAL='@t6g_mb_lib.t6g(sch_1):rst_rt_cpu0_p2_perst_n';
NODE_NAME     R1047 1
 '@T6G_MB_LIB.T6G(SCH_1):PAGE419_I56@PURE_QUANTA.Q_RES(CHIPS)':
 'A': CDS_PINID='A';
NODE_NAME     U6012 F2
 '@T6G_MB_LIB.T6G(SCH_1):PAGE419_I83@PURE_QUANTA.PT5161LRS(CHIPS)':
 'PERST_N': CDS_PINID='PERST_N';
NET_NAME
'RST_RT_CPU0_P2_PERST_R2_N'
 '@T6G_MB_LIB.T6G(SCH_1):RST_RT_CPU0_P2_PERST_R2_N':
 C_SIGNAL='@t6g_mb_lib.t6g(sch_1):rst_rt_cpu0_p2_perst_r2_n';
NODE_NAME     U18 N18
 '@T6G_MB_LIB.T6G(SCH_1):PAGE80_I217@PURE_QUANTA.LCMXO3LF9400C5BG484C(CHIPS)':
 'PR18D': CDS_PINID='PR18D';
NODE_NAME     R6823 1
 '@T6G_MB_LIB.T6G(SCH_1):PAGE80_I350@PURE_QUANTA.Q_RES(CHIPS)':
 'A': CDS_PINID='A';
NET_NAME
'RST_RT_CPU0_P2_PERST_R_N'
 '@T6G_MB_LIB.T6G(SCH_1):RST_RT_CPU0_P2_PERST_R_N':
 C_SIGNAL='@t6g_mb_lib.t6g(sch_1):rst_rt_cpu0_p2_perst_r_n';
NODE_NAME     R1047 2
 '@T6G_MB_LIB.T6G(SCH_1):PAGE419_I56@PURE_QUANTA.Q_RES(CHIPS)':
 'B': CDS_PINID='B';
NODE_NAME     R1061 1
 '@T6G_MB_LIB.T6G(SCH_1):PAGE419_I77@PURE_QUANTA.Q_RES(CHIPS)':
 'A': CDS_PINID='A';
NODE_NAME     R6823 2
 '@T6G_MB_LIB.T6G(SCH_1):PAGE80_I350@PURE_QUANTA.Q_RES(CHIPS)':
 'B': CDS_PINID='B';
NET_NAME
'RST_RT_CPU0_P2_RESET_N'
 '@T6G_MB_LIB.T6G(SCH_1):RST_RT_CPU0_P2_RESET_N':
 C_SIGNAL='@t6g_mb_lib.t6g(sch_1):rst_rt_cpu0_p2_reset_n';
NODE_NAME     R1054 1
 '@T6G_MB_LIB.T6G(SCH_1):PAGE419_I55@PURE_QUANTA.Q_RES(CHIPS)':
 'A': CDS_PINID='A';
NODE_NAME     U6012 FF11
 '@T6G_MB_LIB.T6G(SCH_1):PAGE419_I83@PURE_QUANTA.PT5161LRS(CHIPS)':
 'RESET_N': CDS_PINID='RESET_N';
NET_NAME
'RST_RT_CPU0_P2_RESET_R2_N'
 '@T6G_MB_LIB.T6G(SCH_1):RST_RT_CPU0_P2_RESET_R2_N':
 C_SIGNAL='@t6g_mb_lib.t6g(sch_1):rst_rt_cpu0_p2_reset_r2_n';
NODE_NAME     U18 R20
 '@T6G_MB_LIB.T6G(SCH_1):PAGE80_I217@PURE_QUANTA.LCMXO3LF9400C5BG484C(CHIPS)':
 'PR25C': CDS_PINID='PR25C';
NODE_NAME     R6824 1
 '@T6G_MB_LIB.T6G(SCH_1):PAGE80_I351@PURE_QUANTA.Q_RES(CHIPS)':
 'A': CDS_PINID='A';
NET_NAME
'RST_RT_CPU0_P2_RESET_R_N'
 '@T6G_MB_LIB.T6G(SCH_1):RST_RT_CPU0_P2_RESET_R_N':
 C_SIGNAL='@t6g_mb_lib.t6g(sch_1):rst_rt_cpu0_p2_reset_r_n';
NODE_NAME     R1054 2
 '@T6G_MB_LIB.T6G(SCH_1):PAGE419_I55@PURE_QUANTA.Q_RES(CHIPS)':
 'B': CDS_PINID='B';
NODE_NAME     R1062 1
 '@T6G_MB_LIB.T6G(SCH_1):PAGE419_I76@PURE_QUANTA.Q_RES(CHIPS)':
 'A': CDS_PINID='A';
NODE_NAME     R1065 2
 '@T6G_MB_LIB.T6G(SCH_1):PAGE419_I78@PURE_QUANTA.Q_RES(CHIPS)':
 'B': CDS_PINID='B';
NODE_NAME     R6824 2
 '@T6G_MB_LIB.T6G(SCH_1):PAGE80_I351@PURE_QUANTA.Q_RES(CHIPS)':
 'B': CDS_PINID='B';
NET_NAME
'RST_RT_CPU0_P3_PERST_N'
 '@T6G_MB_LIB.T6G(SCH_1):RST_RT_CPU0_P3_PERST_N':
 C_SIGNAL='@t6g_mb_lib.t6g(sch_1):rst_rt_cpu0_p3_perst_n';
NODE_NAME     R1088 1
 '@T6G_MB_LIB.T6G(SCH_1):PAGE430_I56@PURE_QUANTA.Q_RES(CHIPS)':
 'A': CDS_PINID='A';
NODE_NAME     U6013 F2
 '@T6G_MB_LIB.T6G(SCH_1):PAGE430_I83@PURE_QUANTA.PT5161LRS(CHIPS)':
 'PERST_N': CDS_PINID='PERST_N';
NET_NAME
'RST_RT_CPU0_P3_PERST_R2_N'
 '@T6G_MB_LIB.T6G(SCH_1):RST_RT_CPU0_P3_PERST_R2_N':
 C_SIGNAL='@t6g_mb_lib.t6g(sch_1):rst_rt_cpu0_p3_perst_r2_n';
NODE_NAME     U18 T19
 '@T6G_MB_LIB.T6G(SCH_1):PAGE80_I217@PURE_QUANTA.LCMXO3LF9400C5BG484C(CHIPS)':
 'PR27A': CDS_PINID='PR27A';
NODE_NAME     R6825 1
 '@T6G_MB_LIB.T6G(SCH_1):PAGE80_I352@PURE_QUANTA.Q_RES(CHIPS)':
 'A': CDS_PINID='A';
NET_NAME
'RST_RT_CPU0_P3_PERST_R_N'
 '@T6G_MB_LIB.T6G(SCH_1):RST_RT_CPU0_P3_PERST_R_N':
 C_SIGNAL='@t6g_mb_lib.t6g(sch_1):rst_rt_cpu0_p3_perst_r_n';
NODE_NAME     R6825 2
 '@T6G_MB_LIB.T6G(SCH_1):PAGE80_I352@PURE_QUANTA.Q_RES(CHIPS)':
 'B': CDS_PINID='B';
NODE_NAME     R1088 2
 '@T6G_MB_LIB.T6G(SCH_1):PAGE430_I56@PURE_QUANTA.Q_RES(CHIPS)':
 'B': CDS_PINID='B';
NODE_NAME     R1103 1
 '@T6G_MB_LIB.T6G(SCH_1):PAGE430_I74@PURE_QUANTA.Q_RES(CHIPS)':
 'A': CDS_PINID='A';
NET_NAME
'RST_RT_CPU0_P3_RESET_N'
 '@T6G_MB_LIB.T6G(SCH_1):RST_RT_CPU0_P3_RESET_N':
 C_SIGNAL='@t6g_mb_lib.t6g(sch_1):rst_rt_cpu0_p3_reset_n';
NODE_NAME     R1096 1
 '@T6G_MB_LIB.T6G(SCH_1):PAGE430_I55@PURE_QUANTA.Q_RES(CHIPS)':
 'A': CDS_PINID='A';
NODE_NAME     U6013 FF11
 '@T6G_MB_LIB.T6G(SCH_1):PAGE430_I83@PURE_QUANTA.PT5161LRS(CHIPS)':
 'RESET_N': CDS_PINID='RESET_N';
NET_NAME
'RST_RT_CPU0_P3_RESET_R2_N'
 '@T6G_MB_LIB.T6G(SCH_1):RST_RT_CPU0_P3_RESET_R2_N':
 C_SIGNAL='@t6g_mb_lib.t6g(sch_1):rst_rt_cpu0_p3_reset_r2_n';
NODE_NAME     U18 T17
 '@T6G_MB_LIB.T6G(SCH_1):PAGE80_I217@PURE_QUANTA.LCMXO3LF9400C5BG484C(CHIPS)':
 'PR27C': CDS_PINID='PR27C';
NODE_NAME     R6826 1
 '@T6G_MB_LIB.T6G(SCH_1):PAGE80_I353@PURE_QUANTA.Q_RES(CHIPS)':
 'A': CDS_PINID='A';
NET_NAME
'RST_RT_CPU0_P3_RESET_R_N'
 '@T6G_MB_LIB.T6G(SCH_1):RST_RT_CPU0_P3_RESET_R_N':
 C_SIGNAL='@t6g_mb_lib.t6g(sch_1):rst_rt_cpu0_p3_reset_r_n';
NODE_NAME     R6826 2
 '@T6G_MB_LIB.T6G(SCH_1):PAGE80_I353@PURE_QUANTA.Q_RES(CHIPS)':
 'B': CDS_PINID='B';
NODE_NAME     R1096 2
 '@T6G_MB_LIB.T6G(SCH_1):PAGE430_I55@PURE_QUANTA.Q_RES(CHIPS)':
 'B': CDS_PINID='B';
NODE_NAME     R1104 1
 '@T6G_MB_LIB.T6G(SCH_1):PAGE430_I75@PURE_QUANTA.Q_RES(CHIPS)':
 'A': CDS_PINID='A';
NODE_NAME     R1107 2
 '@T6G_MB_LIB.T6G(SCH_1):PAGE430_I79@PURE_QUANTA.Q_RES(CHIPS)':
 'B': CDS_PINID='B';
NET_NAME
'RST_RT_CPU1_P0_PERST_N'
 '@T6G_MB_LIB.T6G(SCH_1):RST_RT_CPU1_P0_PERST_N':
 C_SIGNAL='@t6g_mb_lib.t6g(sch_1):rst_rt_cpu1_p0_perst_n';
NODE_NAME     U6014 F2
 '@T6G_MB_LIB.T6G(SCH_1):PAGE401_I1@PURE_QUANTA.PT5161LRS(CHIPS)':
 'PERST_N': CDS_PINID='PERST_N';
NODE_NAME     R6708 1
 '@T6G_MB_LIB.T6G(SCH_1):PAGE401_I62@PURE_QUANTA.Q_RES(CHIPS)':
 'A': CDS_PINID='A';
NET_NAME
'RST_RT_CPU1_P0_PERST_R2_N'
 '@T6G_MB_LIB.T6G(SCH_1):RST_RT_CPU1_P0_PERST_R2_N':
 C_SIGNAL='@t6g_mb_lib.t6g(sch_1):rst_rt_cpu1_p0_perst_r2_n';
NODE_NAME     U18 E22
 '@T6G_MB_LIB.T6G(SCH_1):PAGE80_I217@PURE_QUANTA.LCMXO3LF9400C5BG484C(CHIPS)':
 'PR4A': CDS_PINID='PR4A';
NODE_NAME     R6710 2
 '@T6G_MB_LIB.T6G(SCH_1):PAGE80_I322@PURE_QUANTA.Q_RES(CHIPS)':
 'B': CDS_PINID='B';
NET_NAME
'RST_RT_CPU1_P0_PERST_R_N'
 '@T6G_MB_LIB.T6G(SCH_1):RST_RT_CPU1_P0_PERST_R_N':
 C_SIGNAL='@t6g_mb_lib.t6g(sch_1):rst_rt_cpu1_p0_perst_r_n';
NODE_NAME     R6708 2
 '@T6G_MB_LIB.T6G(SCH_1):PAGE401_I62@PURE_QUANTA.Q_RES(CHIPS)':
 'B': CDS_PINID='B';
NODE_NAME     R6710 1
 '@T6G_MB_LIB.T6G(SCH_1):PAGE80_I322@PURE_QUANTA.Q_RES(CHIPS)':
 'A': CDS_PINID='A';
NODE_NAME     R6720 1
 '@T6G_MB_LIB.T6G(SCH_1):PAGE401_I97@PURE_QUANTA.Q_RES(CHIPS)':
 'A': CDS_PINID='A';
NET_NAME
'RST_RT_CPU1_P0_RESET_N'
 '@T6G_MB_LIB.T6G(SCH_1):RST_RT_CPU1_P0_RESET_N':
 C_SIGNAL='@t6g_mb_lib.t6g(sch_1):rst_rt_cpu1_p0_reset_n';
NODE_NAME     U6014 FF11
 '@T6G_MB_LIB.T6G(SCH_1):PAGE401_I1@PURE_QUANTA.PT5161LRS(CHIPS)':
 'RESET_N': CDS_PINID='RESET_N';
NODE_NAME     R6709 1
 '@T6G_MB_LIB.T6G(SCH_1):PAGE401_I65@PURE_QUANTA.Q_RES(CHIPS)':
 'A': CDS_PINID='A';
NET_NAME
'RST_RT_CPU1_P0_RESET_R2_N'
 '@T6G_MB_LIB.T6G(SCH_1):RST_RT_CPU1_P0_RESET_R2_N':
 C_SIGNAL='@t6g_mb_lib.t6g(sch_1):rst_rt_cpu1_p0_reset_r2_n';
NODE_NAME     U18 E21
 '@T6G_MB_LIB.T6G(SCH_1):PAGE80_I217@PURE_QUANTA.LCMXO3LF9400C5BG484C(CHIPS)':
 'PR4B': CDS_PINID='PR4B';
NODE_NAME     R6711 2
 '@T6G_MB_LIB.T6G(SCH_1):PAGE80_I324@PURE_QUANTA.Q_RES(CHIPS)':
 'B': CDS_PINID='B';
NET_NAME
'RST_RT_CPU1_P0_RESET_R_N'
 '@T6G_MB_LIB.T6G(SCH_1):RST_RT_CPU1_P0_RESET_R_N':
 C_SIGNAL='@t6g_mb_lib.t6g(sch_1):rst_rt_cpu1_p0_reset_r_n';
NODE_NAME     R6709 2
 '@T6G_MB_LIB.T6G(SCH_1):PAGE401_I65@PURE_QUANTA.Q_RES(CHIPS)':
 'B': CDS_PINID='B';
NODE_NAME     R6711 1
 '@T6G_MB_LIB.T6G(SCH_1):PAGE80_I324@PURE_QUANTA.Q_RES(CHIPS)':
 'A': CDS_PINID='A';
NODE_NAME     R6721 1
 '@T6G_MB_LIB.T6G(SCH_1):PAGE401_I96@PURE_QUANTA.Q_RES(CHIPS)':
 'A': CDS_PINID='A';
NODE_NAME     R6724 2
 '@T6G_MB_LIB.T6G(SCH_1):PAGE401_I101@PURE_QUANTA.Q_RES(CHIPS)':
 'B': CDS_PINID='B';
NET_NAME
'RST_RT_CPU1_P1_PERST_N'
 '@T6G_MB_LIB.T6G(SCH_1):RST_RT_CPU1_P1_PERST_N':
 C_SIGNAL='@t6g_mb_lib.t6g(sch_1):rst_rt_cpu1_p1_perst_n';
NODE_NAME     U6015 F2
 '@T6G_MB_LIB.T6G(SCH_1):PAGE392_I47@PURE_QUANTA.PT5161LRS(CHIPS)':
 'PERST_N': CDS_PINID='PERST_N';
NODE_NAME     R731 1
 '@T6G_MB_LIB.T6G(SCH_1):PAGE392_I70@PURE_QUANTA.Q_RES(CHIPS)':
 'A': CDS_PINID='A';
NET_NAME
'RST_RT_CPU1_P1_PERST_R2_N'
 '@T6G_MB_LIB.T6G(SCH_1):RST_RT_CPU1_P1_PERST_R2_N':
 C_SIGNAL='@t6g_mb_lib.t6g(sch_1):rst_rt_cpu1_p1_perst_r2_n';
NODE_NAME     U18 G19
 '@T6G_MB_LIB.T6G(SCH_1):PAGE80_I217@PURE_QUANTA.LCMXO3LF9400C5BG484C(CHIPS)':
 'PR6C': CDS_PINID='PR6C';
NODE_NAME     R6740 2
 '@T6G_MB_LIB.T6G(SCH_1):PAGE80_I326@PURE_QUANTA.Q_RES(CHIPS)':
 'B': CDS_PINID='B';
NET_NAME
'RST_RT_CPU1_P1_PERST_R_N'
 '@T6G_MB_LIB.T6G(SCH_1):RST_RT_CPU1_P1_PERST_R_N':
 C_SIGNAL='@t6g_mb_lib.t6g(sch_1):rst_rt_cpu1_p1_perst_r_n';
NODE_NAME     R731 2
 '@T6G_MB_LIB.T6G(SCH_1):PAGE392_I70@PURE_QUANTA.Q_RES(CHIPS)':
 'B': CDS_PINID='B';
NODE_NAME     R749 1
 '@T6G_MB_LIB.T6G(SCH_1):PAGE392_I93@PURE_QUANTA.Q_RES(CHIPS)':
 'A': CDS_PINID='A';
NODE_NAME     R6740 1
 '@T6G_MB_LIB.T6G(SCH_1):PAGE80_I326@PURE_QUANTA.Q_RES(CHIPS)':
 'A': CDS_PINID='A';
NET_NAME
'RST_RT_CPU1_P1_RESET_N'
 '@T6G_MB_LIB.T6G(SCH_1):RST_RT_CPU1_P1_RESET_N':
 C_SIGNAL='@t6g_mb_lib.t6g(sch_1):rst_rt_cpu1_p1_reset_n';
NODE_NAME     U6015 FF11
 '@T6G_MB_LIB.T6G(SCH_1):PAGE392_I47@PURE_QUANTA.PT5161LRS(CHIPS)':
 'RESET_N': CDS_PINID='RESET_N';
NODE_NAME     R732 1
 '@T6G_MB_LIB.T6G(SCH_1):PAGE392_I71@PURE_QUANTA.Q_RES(CHIPS)':
 'A': CDS_PINID='A';
NET_NAME
'RST_RT_CPU1_P1_RESET_R2_N'
 '@T6G_MB_LIB.T6G(SCH_1):RST_RT_CPU1_P1_RESET_R2_N':
 C_SIGNAL='@t6g_mb_lib.t6g(sch_1):rst_rt_cpu1_p1_reset_r2_n';
NODE_NAME     U18 G18
 '@T6G_MB_LIB.T6G(SCH_1):PAGE80_I217@PURE_QUANTA.LCMXO3LF9400C5BG484C(CHIPS)':
 'PR6D': CDS_PINID='PR6D';
NODE_NAME     R6741 2
 '@T6G_MB_LIB.T6G(SCH_1):PAGE80_I327@PURE_QUANTA.Q_RES(CHIPS)':
 'B': CDS_PINID='B';
NET_NAME
'RST_RT_CPU1_P1_RESET_R_N'
 '@T6G_MB_LIB.T6G(SCH_1):RST_RT_CPU1_P1_RESET_R_N':
 C_SIGNAL='@t6g_mb_lib.t6g(sch_1):rst_rt_cpu1_p1_reset_r_n';
NODE_NAME     R732 2
 '@T6G_MB_LIB.T6G(SCH_1):PAGE392_I71@PURE_QUANTA.Q_RES(CHIPS)':
 'B': CDS_PINID='B';
NODE_NAME     R752 1
 '@T6G_MB_LIB.T6G(SCH_1):PAGE392_I92@PURE_QUANTA.Q_RES(CHIPS)':
 'A': CDS_PINID='A';
NODE_NAME     R758 2
 '@T6G_MB_LIB.T6G(SCH_1):PAGE392_I94@PURE_QUANTA.Q_RES(CHIPS)':
 'B': CDS_PINID='B';
NODE_NAME     R6741 1
 '@T6G_MB_LIB.T6G(SCH_1):PAGE80_I327@PURE_QUANTA.Q_RES(CHIPS)':
 'A': CDS_PINID='A';
NET_NAME
'RST_RT_CPU1_P2_PERST_N'
 '@T6G_MB_LIB.T6G(SCH_1):RST_RT_CPU1_P2_PERST_N':
 C_SIGNAL='@t6g_mb_lib.t6g(sch_1):rst_rt_cpu1_p2_perst_n';
NODE_NAME     R854 1
 '@T6G_MB_LIB.T6G(SCH_1):PAGE451_I63@PURE_QUANTA.Q_RES(CHIPS)':
 'A': CDS_PINID='A';
NODE_NAME     U6016 F2
 '@T6G_MB_LIB.T6G(SCH_1):PAGE451_I97@PURE_QUANTA.PT5161LRS(CHIPS)':
 'PERST_N': CDS_PINID='PERST_N';
NET_NAME
'RST_RT_CPU1_P2_PERST_R2_N'
 '@T6G_MB_LIB.T6G(SCH_1):RST_RT_CPU1_P2_PERST_R2_N':
 C_SIGNAL='@t6g_mb_lib.t6g(sch_1):rst_rt_cpu1_p2_perst_r2_n';
NODE_NAME     U18 K20
 '@T6G_MB_LIB.T6G(SCH_1):PAGE80_I217@PURE_QUANTA.LCMXO3LF9400C5BG484C(CHIPS)':
 'PR12D': CDS_PINID='PR12D';
NODE_NAME     R6792 2
 '@T6G_MB_LIB.T6G(SCH_1):PAGE80_I334@PURE_QUANTA.Q_RES(CHIPS)':
 'B': CDS_PINID='B';
NET_NAME
'RST_RT_CPU1_P2_PERST_R_N'
 '@T6G_MB_LIB.T6G(SCH_1):RST_RT_CPU1_P2_PERST_R_N':
 C_SIGNAL='@t6g_mb_lib.t6g(sch_1):rst_rt_cpu1_p2_perst_r_n';
NODE_NAME     R854 2
 '@T6G_MB_LIB.T6G(SCH_1):PAGE451_I63@PURE_QUANTA.Q_RES(CHIPS)':
 'B': CDS_PINID='B';
NODE_NAME     R866 1
 '@T6G_MB_LIB.T6G(SCH_1):PAGE451_I82@PURE_QUANTA.Q_RES(CHIPS)':
 'A': CDS_PINID='A';
NODE_NAME     R6792 1
 '@T6G_MB_LIB.T6G(SCH_1):PAGE80_I334@PURE_QUANTA.Q_RES(CHIPS)':
 'A': CDS_PINID='A';
NET_NAME
'RST_RT_CPU1_P2_RESET_N'
 '@T6G_MB_LIB.T6G(SCH_1):RST_RT_CPU1_P2_RESET_N':
 C_SIGNAL='@t6g_mb_lib.t6g(sch_1):rst_rt_cpu1_p2_reset_n';
NODE_NAME     R860 1
 '@T6G_MB_LIB.T6G(SCH_1):PAGE451_I62@PURE_QUANTA.Q_RES(CHIPS)':
 'A': CDS_PINID='A';
NODE_NAME     U6016 FF11
 '@T6G_MB_LIB.T6G(SCH_1):PAGE451_I97@PURE_QUANTA.PT5161LRS(CHIPS)':
 'RESET_N': CDS_PINID='RESET_N';
NET_NAME
'RST_RT_CPU1_P2_RESET_R2_N'
 '@T6G_MB_LIB.T6G(SCH_1):RST_RT_CPU1_P2_RESET_R2_N':
 C_SIGNAL='@t6g_mb_lib.t6g(sch_1):rst_rt_cpu1_p2_reset_r2_n';
NODE_NAME     U18 K19
 '@T6G_MB_LIB.T6G(SCH_1):PAGE80_I217@PURE_QUANTA.LCMXO3LF9400C5BG484C(CHIPS)':
 'PR13A': CDS_PINID='PR13A';
NODE_NAME     R6793 2
 '@T6G_MB_LIB.T6G(SCH_1):PAGE80_I335@PURE_QUANTA.Q_RES(CHIPS)':
 'B': CDS_PINID='B';
NET_NAME
'RST_RT_CPU1_P2_RESET_R_N'
 '@T6G_MB_LIB.T6G(SCH_1):RST_RT_CPU1_P2_RESET_R_N':
 C_SIGNAL='@t6g_mb_lib.t6g(sch_1):rst_rt_cpu1_p2_reset_r_n';
NODE_NAME     R860 2
 '@T6G_MB_LIB.T6G(SCH_1):PAGE451_I62@PURE_QUANTA.Q_RES(CHIPS)':
 'B': CDS_PINID='B';
NODE_NAME     R867 1
 '@T6G_MB_LIB.T6G(SCH_1):PAGE451_I80@PURE_QUANTA.Q_RES(CHIPS)':
 'A': CDS_PINID='A';
NODE_NAME     R870 2
 '@T6G_MB_LIB.T6G(SCH_1):PAGE451_I86@PURE_QUANTA.Q_RES(CHIPS)':
 'B': CDS_PINID='B';
NODE_NAME     R6793 1
 '@T6G_MB_LIB.T6G(SCH_1):PAGE80_I335@PURE_QUANTA.Q_RES(CHIPS)':
 'A': CDS_PINID='A';
NET_NAME
'RST_RT_CPU1_P3_PERST_N'
 '@T6G_MB_LIB.T6G(SCH_1):RST_RT_CPU1_P3_PERST_N':
 C_SIGNAL='@t6g_mb_lib.t6g(sch_1):rst_rt_cpu1_p3_perst_n';
NODE_NAME     R895 1
 '@T6G_MB_LIB.T6G(SCH_1):PAGE462_I69@PURE_QUANTA.Q_RES(CHIPS)':
 'A': CDS_PINID='A';
NODE_NAME     U6017 F2
 '@T6G_MB_LIB.T6G(SCH_1):PAGE462_I97@PURE_QUANTA.PT5161LRS(CHIPS)':
 'PERST_N': CDS_PINID='PERST_N';
NET_NAME
'RST_RT_CPU1_P3_PERST_R2_N'
 '@T6G_MB_LIB.T6G(SCH_1):RST_RT_CPU1_P3_PERST_R2_N':
 C_SIGNAL='@t6g_mb_lib.t6g(sch_1):rst_rt_cpu1_p3_perst_r2_n';
NODE_NAME     U18 L19
 '@T6G_MB_LIB.T6G(SCH_1):PAGE80_I217@PURE_QUANTA.LCMXO3LF9400C5BG484C(CHIPS)':
 'PR14C': CDS_PINID='PR14C';
NODE_NAME     R6798 2
 '@T6G_MB_LIB.T6G(SCH_1):PAGE80_I338@PURE_QUANTA.Q_RES(CHIPS)':
 'B': CDS_PINID='B';
NET_NAME
'RST_RT_CPU1_P3_PERST_R_N'
 '@T6G_MB_LIB.T6G(SCH_1):RST_RT_CPU1_P3_PERST_R_N':
 C_SIGNAL='@t6g_mb_lib.t6g(sch_1):rst_rt_cpu1_p3_perst_r_n';
NODE_NAME     R895 2
 '@T6G_MB_LIB.T6G(SCH_1):PAGE462_I69@PURE_QUANTA.Q_RES(CHIPS)':
 'B': CDS_PINID='B';
NODE_NAME     R907 1
 '@T6G_MB_LIB.T6G(SCH_1):PAGE462_I92@PURE_QUANTA.Q_RES(CHIPS)':
 'A': CDS_PINID='A';
NODE_NAME     R6798 1
 '@T6G_MB_LIB.T6G(SCH_1):PAGE80_I338@PURE_QUANTA.Q_RES(CHIPS)':
 'A': CDS_PINID='A';
NET_NAME
'RST_RT_CPU1_P3_RESET_N'
 '@T6G_MB_LIB.T6G(SCH_1):RST_RT_CPU1_P3_RESET_N':
 C_SIGNAL='@t6g_mb_lib.t6g(sch_1):rst_rt_cpu1_p3_reset_n';
NODE_NAME     R901 1
 '@T6G_MB_LIB.T6G(SCH_1):PAGE462_I70@PURE_QUANTA.Q_RES(CHIPS)':
 'A': CDS_PINID='A';
NODE_NAME     U6017 FF11
 '@T6G_MB_LIB.T6G(SCH_1):PAGE462_I97@PURE_QUANTA.PT5161LRS(CHIPS)':
 'RESET_N': CDS_PINID='RESET_N';
NET_NAME
'RST_RT_CPU1_P3_RESET_R2_N'
 '@T6G_MB_LIB.T6G(SCH_1):RST_RT_CPU1_P3_RESET_R2_N':
 C_SIGNAL='@t6g_mb_lib.t6g(sch_1):rst_rt_cpu1_p3_reset_r2_n';
NODE_NAME     U18 L20
 '@T6G_MB_LIB.T6G(SCH_1):PAGE80_I217@PURE_QUANTA.LCMXO3LF9400C5BG484C(CHIPS)':
 'PR14D': CDS_PINID='PR14D';
NODE_NAME     R6799 2
 '@T6G_MB_LIB.T6G(SCH_1):PAGE80_I339@PURE_QUANTA.Q_RES(CHIPS)':
 'B': CDS_PINID='B';
NET_NAME
'RST_RT_CPU1_P3_RESET_R_N'
 '@T6G_MB_LIB.T6G(SCH_1):RST_RT_CPU1_P3_RESET_R_N':
 C_SIGNAL='@t6g_mb_lib.t6g(sch_1):rst_rt_cpu1_p3_reset_r_n';
NODE_NAME     R901 2
 '@T6G_MB_LIB.T6G(SCH_1):PAGE462_I70@PURE_QUANTA.Q_RES(CHIPS)':
 'B': CDS_PINID='B';
NODE_NAME     R908 1
 '@T6G_MB_LIB.T6G(SCH_1):PAGE462_I90@PURE_QUANTA.Q_RES(CHIPS)':
 'A': CDS_PINID='A';
NODE_NAME     R911 2
 '@T6G_MB_LIB.T6G(SCH_1):PAGE462_I93@PURE_QUANTA.Q_RES(CHIPS)':
 'B': CDS_PINID='B';
NODE_NAME     R6799 1
 '@T6G_MB_LIB.T6G(SCH_1):PAGE80_I339@PURE_QUANTA.Q_RES(CHIPS)':
 'A': CDS_PINID='A';
NET_NAME
'RST_SMB_BUF_E1S_0_N'
 '@T6G_MB_LIB.T6G(SCH_1):RST_SMB_BUF_E1S_0_N':
 C_SIGNAL='@t6g_mb_lib.t6g(sch_1):rst_smb_buf_e1s_0_n';
NODE_NAME     U134 6
 '@T6G_MB_LIB.T6G(SCH_1):PAGE297_I4@PURE_QUANTA.74LVC2G07DW7(CHIPS)':
 '1Y': CDS_PINID='\1y\';
NODE_NAME     R3772 1
 '@T6G_MB_LIB.T6G(SCH_1):PAGE297_I38@PURE_QUANTA.Q_RES(CHIPS)':
 'A': CDS_PINID='A';
NET_NAME
'RST_SMB_E1S_0_N'
 '@T6G_MB_LIB.T6G(SCH_1):RST_SMB_E1S_0_N':
 C_SIGNAL='@t6g_mb_lib.t6g(sch_1):rst_smb_e1s_0_n';
NODE_NAME     R3772 2
 '@T6G_MB_LIB.T6G(SCH_1):PAGE297_I38@PURE_QUANTA.Q_RES(CHIPS)':
 'B': CDS_PINID='B';
NODE_NAME     J90 A9
 '@T6G_MB_LIB.T6G(SCH_1):PAGE297_I90@PURE_QUANTA.SCONN56_123276793(CHIPS)':
 'SMBRST#': CDS_PINID='\smbrst#\';
NODE_NAME     R1673 2
 '@T6G_MB_LIB.T6G(SCH_1):PAGE297_I105@PURE_QUANTA.Q_RES(CHIPS)':
 'B': CDS_PINID='B';
NODE_NAME     R3773 2
 '@T6G_MB_LIB.T6G(SCH_1):PAGE297_I106@PURE_QUANTA.Q_RES(CHIPS)':
 'B': CDS_PINID='B';
NET_NAME
'RST_SMB_E1S_N'
 '@T6G_MB_LIB.T6G(SCH_1):RST_SMB_E1S_N':
 C_SIGNAL='@t6g_mb_lib.t6g(sch_1):rst_smb_e1s_n';
NODE_NAME     R3775 2
 '@T6G_MB_LIB.T6G(SCH_1):PAGE297_I2@PURE_QUANTA.Q_RES(CHIPS)':
 'B': CDS_PINID='B';
NODE_NAME     U134 1
 '@T6G_MB_LIB.T6G(SCH_1):PAGE297_I4@PURE_QUANTA.74LVC2G07DW7(CHIPS)':
 '1A': CDS_PINID='\1a\';
NODE_NAME     U134 3
 '@T6G_MB_LIB.T6G(SCH_1):PAGE297_I4@PURE_QUANTA.74LVC2G07DW7(CHIPS)':
 '2A': CDS_PINID='\2a\';
NET_NAME
'RST_SMB_OCP_SFF_N'
 '@T6G_MB_LIB.T6G(SCH_1):RST_SMB_OCP_SFF_N':
 C_SIGNAL='@t6g_mb_lib.t6g(sch_1):rst_smb_ocp_sff_n';
NODE_NAME     J38 A9
 '@T6G_MB_LIB.T6G(SCH_1):PAGE335_I168@PURE_QUANTA.SCONN168_ME1016810202011(CHIPS)':
 'SMRST#': CDS_PINID='\smrst#\';
NODE_NAME     R3233 2
 '@T6G_MB_LIB.T6G(SCH_1):PAGE336_I153@PURE_QUANTA.Q_RES(CHIPS)':
 'B': CDS_PINID='B';
NET_NAME
'RST_SMB_OCP_V3_2_N'
 '@T6G_MB_LIB.T6G(SCH_1):RST_SMB_OCP_V3_2_N':
 C_SIGNAL='@t6g_mb_lib.t6g(sch_1):rst_smb_ocp_v3_2_n';
NODE_NAME     J35 A9
 '@T6G_MB_LIB.T6G(SCH_1):PAGE341_I168@PURE_QUANTA.SCONN168_ME1016810202011(CHIPS)':
 'SMRST#': CDS_PINID='\smrst#\';
NODE_NAME     R3236 2
 '@T6G_MB_LIB.T6G(SCH_1):PAGE342_I25@PURE_QUANTA.Q_RES(CHIPS)':
 'B': CDS_PINID='B';
NET_NAME
'RST_SMB_RT_N'
 '@T6G_MB_LIB.T6G(SCH_1):RST_SMB_RT_N':
 C_SIGNAL='@t6g_mb_lib.t6g(sch_1):rst_smb_rt_n';
NODE_NAME     U6020 3
 '@T6G_MB_LIB.T6G(SCH_1):PAGE378_I1@PURE_QUANTA.TCA9548APWR(CHIPS)':
 'RESET#': CDS_PINID='\reset#\';
NODE_NAME     R6776 2
 '@T6G_MB_LIB.T6G(SCH_1):PAGE378_I104@PURE_QUANTA.Q_RES(CHIPS)':
 'B': CDS_PINID='B';
NET_NAME
'RST_SMB_RT_R1_N'
 '@T6G_MB_LIB.T6G(SCH_1):RST_SMB_RT_R1_N':
 C_SIGNAL='@t6g_mb_lib.t6g(sch_1):rst_smb_rt_r1_n';
NODE_NAME     R6776 1
 '@T6G_MB_LIB.T6G(SCH_1):PAGE378_I104@PURE_QUANTA.Q_RES(CHIPS)':
 'A': CDS_PINID='A';
NODE_NAME     R6777 2
 '@T6G_MB_LIB.T6G(SCH_1):PAGE80_I330@PURE_QUANTA.Q_RES(CHIPS)':
 'B': CDS_PINID='B';
NODE_NAME     R6778 1
 '@T6G_MB_LIB.T6G(SCH_1):PAGE378_I107@PURE_QUANTA.Q_RES(CHIPS)':
 'A': CDS_PINID='A';
NET_NAME
'RST_SMB_RT_R2_N'
 '@T6G_MB_LIB.T6G(SCH_1):RST_SMB_RT_R2_N':
 C_SIGNAL='@t6g_mb_lib.t6g(sch_1):rst_smb_rt_r2_n';
NODE_NAME     U18 Y20
 '@T6G_MB_LIB.T6G(SCH_1):PAGE80_I217@PURE_QUANTA.LCMXO3LF9400C5BG484C(CHIPS)':
 'PR30D': CDS_PINID='PR30D';
NODE_NAME     R6777 1
 '@T6G_MB_LIB.T6G(SCH_1):PAGE80_I330@PURE_QUANTA.Q_RES(CHIPS)':
 'A': CDS_PINID='A';
NET_NAME
'RST_SMB_RT_ROM_N'
 '@T6G_MB_LIB.T6G(SCH_1):RST_SMB_RT_ROM_N':
 C_SIGNAL='@t6g_mb_lib.t6g(sch_1):rst_smb_rt_rom_n';
NODE_NAME     R848 2
 '@T6G_MB_LIB.T6G(SCH_1):PAGE377_I42@PURE_QUANTA.Q_RES(CHIPS)':
 'B': CDS_PINID='B';
NODE_NAME     U22 3
 '@T6G_MB_LIB.T6G(SCH_1):PAGE377_I94@PURE_QUANTA.TCA9548APWR(CHIPS)':
 'RESET#': CDS_PINID='\reset#\';
NET_NAME
'RST_SMB_RT_ROM_R1_N'
 '@T6G_MB_LIB.T6G(SCH_1):RST_SMB_RT_ROM_R1_N':
 C_SIGNAL='@t6g_mb_lib.t6g(sch_1):rst_smb_rt_rom_r1_n';
NODE_NAME     R849 1
 '@T6G_MB_LIB.T6G(SCH_1):PAGE377_I16@PURE_QUANTA.Q_RES(CHIPS)':
 'A': CDS_PINID='A';
NODE_NAME     R848 1
 '@T6G_MB_LIB.T6G(SCH_1):PAGE377_I42@PURE_QUANTA.Q_RES(CHIPS)':
 'A': CDS_PINID='A';
NODE_NAME     R6781 2
 '@T6G_MB_LIB.T6G(SCH_1):PAGE80_I332@PURE_QUANTA.Q_RES(CHIPS)':
 'B': CDS_PINID='B';
NODE_NAME     R1201 1
 '@T6G_MB_LIB.T6G(SCH_1):PAGE376_I30@PURE_QUANTA.Q_RES(CHIPS)':
 'A': CDS_PINID='A';
NODE_NAME     R1199 1
 '@T6G_MB_LIB.T6G(SCH_1):PAGE376_I40@PURE_QUANTA.Q_RES(CHIPS)':
 'A': CDS_PINID='A';
NODE_NAME     R1198 1
 '@T6G_MB_LIB.T6G(SCH_1):PAGE376_I53@PURE_QUANTA.Q_RES(CHIPS)':
 'A': CDS_PINID='A';
NODE_NAME     R1200 1
 '@T6G_MB_LIB.T6G(SCH_1):PAGE376_I68@PURE_QUANTA.Q_RES(CHIPS)':
 'A': CDS_PINID='A';
NODE_NAME     R1211 1
 '@T6G_MB_LIB.T6G(SCH_1):PAGE376_I86@PURE_QUANTA.Q_RES(CHIPS)':
 'A': CDS_PINID='A';
NODE_NAME     R1210 1
 '@T6G_MB_LIB.T6G(SCH_1):PAGE376_I109@PURE_QUANTA.Q_RES(CHIPS)':
 'A': CDS_PINID='A';
NODE_NAME     R1206 1
 '@T6G_MB_LIB.T6G(SCH_1):PAGE376_I115@PURE_QUANTA.Q_RES(CHIPS)':
 'A': CDS_PINID='A';
NODE_NAME     R1209 1
 '@T6G_MB_LIB.T6G(SCH_1):PAGE376_I123@PURE_QUANTA.Q_RES(CHIPS)':
 'A': CDS_PINID='A';
NET_NAME
'RST_SMB_RT_ROM_R2_N'
 '@T6G_MB_LIB.T6G(SCH_1):RST_SMB_RT_ROM_R2_N':
 C_SIGNAL='@t6g_mb_lib.t6g(sch_1):rst_smb_rt_rom_r2_n';
NODE_NAME     U18 V18
 '@T6G_MB_LIB.T6G(SCH_1):PAGE80_I217@PURE_QUANTA.LCMXO3LF9400C5BG484C(CHIPS)':
 'PR30A': CDS_PINID='PR30A';
NODE_NAME     R6781 1
 '@T6G_MB_LIB.T6G(SCH_1):PAGE80_I332@PURE_QUANTA.Q_RES(CHIPS)':
 'A': CDS_PINID='A';
NET_NAME
'RST_SMB_SWITCH_N'
 '@T6G_MB_LIB.T6G(SCH_1):RST_SMB_SWITCH_N':
 C_SIGNAL='@t6g_mb_lib.t6g(sch_1):rst_smb_switch_n';
NODE_NAME     U224 2
 '@T6G_MB_LIB.T6G(SCH_1):PAGE336_I159@PURE_QUANTA.74LVC1G126SE7(CHIPS)':
 'A': CDS_PINID='A';
NODE_NAME     R2905 1
 '@T6G_MB_LIB.T6G(SCH_1):PAGE363_I441@PURE_QUANTA.Q_RES(CHIPS)':
 'A': CDS_PINID='A';
NODE_NAME     R2921 2
 '@T6G_MB_LIB.T6G(SCH_1):PAGE246_I35@PURE_QUANTA.Q_RES(CHIPS)':
 'B': CDS_PINID='B';
NODE_NAME     R3705 2
 '@T6G_MB_LIB.T6G(SCH_1):PAGE251_I27@PURE_QUANTA.Q_RES(CHIPS)':
 'B': CDS_PINID='B';
NODE_NAME     R3710 1
 '@T6G_MB_LIB.T6G(SCH_1):PAGE251_I29@PURE_QUANTA.Q_RES(CHIPS)':
 'A': CDS_PINID='A';
NODE_NAME     R1822 2
 '@T6G_MB_LIB.T6G(SCH_1):PAGE252_I21@PURE_QUANTA.Q_RES(CHIPS)':
 'B': CDS_PINID='B';
NODE_NAME     R2268 1
 '@T6G_MB_LIB.T6G(SCH_1):PAGE252_I28@PURE_QUANTA.Q_RES(CHIPS)':
 'A': CDS_PINID='A';
NODE_NAME     U18 D17
 '@T6G_MB_LIB.T6G(SCH_1):PAGE79_I94@PURE_QUANTA.LCMXO3LF9400C5BG484C(CHIPS)':
 'PT40D': CDS_PINID='PT40D';
NODE_NAME     U225 2
 '@T6G_MB_LIB.T6G(SCH_1):PAGE342_I9@PURE_QUANTA.74LVC1G126SE7(CHIPS)':
 'A': CDS_PINID='A';
NODE_NAME     R2922 1
 '@T6G_MB_LIB.T6G(SCH_1):PAGE246_I31@PURE_QUANTA.Q_RES(CHIPS)':
 'A': CDS_PINID='A';
NET_NAME
'RST_SMB_SWITCH_R_N'
 '@T6G_MB_LIB.T6G(SCH_1):RST_SMB_SWITCH_R_N':
 C_SIGNAL='@t6g_mb_lib.t6g(sch_1):rst_smb_switch_r_n';
NODE_NAME     R2905 2
 '@T6G_MB_LIB.T6G(SCH_1):PAGE363_I441@PURE_QUANTA.Q_RES(CHIPS)':
 'B': CDS_PINID='B';
NODE_NAME     C74 1
 '@T6G_MB_LIB.T6G(SCH_1):PAGE363_I452@PURE_QUANTA.Q_CAP(CHIPS)':
 'A': CDS_PINID='A';
NODE_NAME     J45 B1
 '@T6G_MB_LIB.T6G(SCH_1):PAGE363_I466@PURE_QUANTA.CONN60_101062636003K02LF(CHIPS)':
 'B1': CDS_PINID='B1';
NET_NAME
'RST_SRST_PLD_BMC_N'
 '@T6G_MB_LIB.T6G(SCH_1):RST_SRST_PLD_BMC_N':
 C_SIGNAL='@t6g_mb_lib.t6g(sch_1):rst_srst_pld_bmc_n';
NODE_NAME     J41 OB11
 '@T6G_MB_LIB.T6G(SCH_1):PAGE348_I176@PURE_QUANTA.SCONN168_ME1016810202011(CHIPS)':
 'REFCLKN2': CDS_PINID='REFCLKN2';
NODE_NAME     R419 1
 '@T6G_MB_LIB.T6G(SCH_1):PAGE79_I141@PURE_QUANTA.Q_RES(CHIPS)':
 'A': CDS_PINID='A';
NET_NAME
'RST_SRST_PLD_BMC_R_N'
 '@T6G_MB_LIB.T6G(SCH_1):RST_SRST_PLD_BMC_R_N':
 C_SIGNAL='@t6g_mb_lib.t6g(sch_1):rst_srst_pld_bmc_r_n';
NODE_NAME     U18 C17
 '@T6G_MB_LIB.T6G(SCH_1):PAGE79_I94@PURE_QUANTA.LCMXO3LF9400C5BG484C(CHIPS)':
 'PT39C': CDS_PINID='PT39C';
NODE_NAME     R419 2
 '@T6G_MB_LIB.T6G(SCH_1):PAGE79_I141@PURE_QUANTA.Q_RES(CHIPS)':
 'B': CDS_PINID='B';
NET_NAME
'RST_SWB_BIC_BUF_N'
 '@T6G_MB_LIB.T6G(SCH_1):RST_SWB_BIC_BUF_N':
 C_SIGNAL='@t6g_mb_lib.t6g(sch_1):rst_swb_bic_buf_n';
NODE_NAME     R2924 2
 '@T6G_MB_LIB.T6G(SCH_1):PAGE256_I155@PURE_QUANTA.Q_RES(CHIPS)':
 'B': CDS_PINID='B';
NODE_NAME     J105 N6
 '@T6G_MB_LIB.T6G(SCH_1):PAGE326_I76@PURE_QUANTA.CONN112_10137002101LF(CHIPS)':
 'N6': CDS_PINID='N6';
NET_NAME
'RST_SWB_BIC_BUF_R_N'
 '@T6G_MB_LIB.T6G(SCH_1):RST_SWB_BIC_BUF_R_N':
 C_SIGNAL='@t6g_mb_lib.t6g(sch_1):rst_swb_bic_buf_r_n';
NODE_NAME     U195 4
 '@T6G_MB_LIB.T6G(SCH_1):PAGE256_I65@PURE_QUANTA.74LVC2G17GW(CHIPS)':
 'B1': CDS_PINID='B1';
NODE_NAME     R2911 2
 '@T6G_MB_LIB.T6G(SCH_1):PAGE256_I153@PURE_QUANTA.Q_RES(CHIPS)':
 'B': CDS_PINID='B';
NODE_NAME     R2924 1
 '@T6G_MB_LIB.T6G(SCH_1):PAGE256_I155@PURE_QUANTA.Q_RES(CHIPS)':
 'A': CDS_PINID='A';
NODE_NAME     R2927 1
 '@T6G_MB_LIB.T6G(SCH_1):PAGE256_I203@PURE_QUANTA.Q_RES(CHIPS)':
 'A': CDS_PINID='A';
NET_NAME
'RST_SWB_BIC_N'
 '@T6G_MB_LIB.T6G(SCH_1):RST_SWB_BIC_N':
 C_SIGNAL='@t6g_mb_lib.t6g(sch_1):rst_swb_bic_n';
NODE_NAME     R2848 1
 '@T6G_MB_LIB.T6G(SCH_1):PAGE246_I59@PURE_QUANTA.Q_RES(CHIPS)':
 'A': CDS_PINID='A';
NODE_NAME     U181 5
 '@T6G_MB_LIB.T6G(SCH_1):PAGE246_I83@PURE_QUANTA.PCA9539RPW(CHIPS)':
 'IO0_1': CDS_PINID='IO0_1';
NET_NAME
'RST_SWB_BIC_R_N'
 '@T6G_MB_LIB.T6G(SCH_1):RST_SWB_BIC_R_N':
 C_SIGNAL='@t6g_mb_lib.t6g(sch_1):rst_swb_bic_r_n';
NODE_NAME     U195 3
 '@T6G_MB_LIB.T6G(SCH_1):PAGE256_I65@PURE_QUANTA.74LVC2G17GW(CHIPS)':
 'A1': CDS_PINID='A1';
NODE_NAME     R2916 1
 '@T6G_MB_LIB.T6G(SCH_1):PAGE256_I93@PURE_QUANTA.Q_RES(CHIPS)':
 'A': CDS_PINID='A';
NODE_NAME     R2909 2
 '@T6G_MB_LIB.T6G(SCH_1):PAGE256_I198@PURE_QUANTA.Q_RES(CHIPS)':
 'B': CDS_PINID='B';
NODE_NAME     R2848 2
 '@T6G_MB_LIB.T6G(SCH_1):PAGE246_I59@PURE_QUANTA.Q_RES(CHIPS)':
 'B': CDS_PINID='B';
NET_NAME
'RST_USB_CPU0_HUB1_R_N'
 '@T6G_MB_LIB.T6G(SCH_1):RST_USB_CPU0_HUB1_R_N':
 C_SIGNAL='@t6g_mb_lib.t6g(sch_1):rst_usb_cpu0_hub1_r_n';
NODE_NAME     U6001 31
 '@T6G_MB_LIB.T6G(SCH_1):PAGE153_I1@PURE_QUANTA.CYUSB330468LTXI(CHIPS)':
 'RESET#': CDS_PINID='\reset#\';
NODE_NAME     R4451 2
 '@T6G_MB_LIB.T6G(SCH_1):PAGE153_I20@PURE_QUANTA.Q_RES(CHIPS)':
 'B': CDS_PINID='B';
NODE_NAME     R4453 1
 '@T6G_MB_LIB.T6G(SCH_1):PAGE153_I23@PURE_QUANTA.Q_RES(CHIPS)':
 'A': CDS_PINID='A';
NODE_NAME     C2317 1
 '@T6G_MB_LIB.T6G(SCH_1):PAGE153_I25@PURE_QUANTA.Q_CAP(CHIPS)':
 'A': CDS_PINID='A';
NODE_NAME     R4452 2
 '@T6G_MB_LIB.T6G(SCH_1):PAGE153_I93@PURE_QUANTA.Q_RES(CHIPS)':
 'B': CDS_PINID='B';
NET_NAME
'RST_USB_HUB_N'
 '@T6G_MB_LIB.T6G(SCH_1):RST_USB_HUB_N':
 C_SIGNAL='@t6g_mb_lib.t6g(sch_1):rst_usb_hub_n';
NODE_NAME     R3654 1
 '@T6G_MB_LIB.T6G(SCH_1):PAGE358_I155@PURE_QUANTA.Q_RES(CHIPS)':
 'A': CDS_PINID='A';
NODE_NAME     R4451 1
 '@T6G_MB_LIB.T6G(SCH_1):PAGE153_I20@PURE_QUANTA.Q_RES(CHIPS)':
 'A': CDS_PINID='A';
NODE_NAME     R6328 1
 '@T6G_MB_LIB.T6G(SCH_1):PAGE155_I114@PURE_QUANTA.Q_RES(CHIPS)':
 'A': CDS_PINID='A';
NODE_NAME     R6322 1
 '@T6G_MB_LIB.T6G(SCH_1):PAGE155_I131@PURE_QUANTA.Q_RES(CHIPS)':
 'A': CDS_PINID='A';
NODE_NAME     U181 4
 '@T6G_MB_LIB.T6G(SCH_1):PAGE246_I83@PURE_QUANTA.PCA9539RPW(CHIPS)':
 'IO0_0': CDS_PINID='IO0_0';
NET_NAME
'RST_USB_HUB_R_N'
 '@T6G_MB_LIB.T6G(SCH_1):RST_USB_HUB_R_N':
 C_SIGNAL='@t6g_mb_lib.t6g(sch_1):rst_usb_hub_r_n';
NODE_NAME     U268 17
 '@T6G_MB_LIB.T6G(SCH_1):PAGE358_I100@PURE_QUANTA.GL852GOHY60(CHIPS)':
 'RESET#': CDS_PINID='\reset#\';
NODE_NAME     R3654 2
 '@T6G_MB_LIB.T6G(SCH_1):PAGE358_I155@PURE_QUANTA.Q_RES(CHIPS)':
 'B': CDS_PINID='B';
NODE_NAME     C2041 1
 '@T6G_MB_LIB.T6G(SCH_1):PAGE358_I158@PURE_QUANTA.Q_CAP(CHIPS)':
 'A': CDS_PINID='A';
NODE_NAME     R3660 2
 '@T6G_MB_LIB.T6G(SCH_1):PAGE358_I159@PURE_QUANTA.Q_RES(CHIPS)':
 'B': CDS_PINID='B';
NODE_NAME     R3661 2
 '@T6G_MB_LIB.T6G(SCH_1):PAGE358_I201@PURE_QUANTA.Q_RES(CHIPS)':
 'B': CDS_PINID='B';
NET_NAME
'RT_BOARD_ID_ID0'
 '@T6G_MB_LIB.T6G(SCH_1):RT_BOARD_ID_ID0':
 C_SIGNAL='@t6g_mb_lib.t6g(sch_1):rt_board_id_id0';
NODE_NAME     U18 J4
 '@T6G_MB_LIB.T6G(SCH_1):PAGE81_I143@PURE_QUANTA.LCMXO3LF9400C5BG484C(CHIPS)':
 'PL11C': CDS_PINID='PL11C';
NODE_NAME     R6745 1
 '@T6G_MB_LIB.T6G(SCH_1):PAGE467_I4@PURE_QUANTA.Q_RES(CHIPS)':
 'A': CDS_PINID='A';
NODE_NAME     R6743 2
 '@T6G_MB_LIB.T6G(SCH_1):PAGE467_I6@PURE_QUANTA.Q_RES(CHIPS)':
 'B': CDS_PINID='B';
NET_NAME
'RT_BOARD_ID_ID1'
 '@T6G_MB_LIB.T6G(SCH_1):RT_BOARD_ID_ID1':
 C_SIGNAL='@t6g_mb_lib.t6g(sch_1):rt_board_id_id1';
NODE_NAME     U18 H1
 '@T6G_MB_LIB.T6G(SCH_1):PAGE81_I143@PURE_QUANTA.LCMXO3LF9400C5BG484C(CHIPS)':
 'PL10B': CDS_PINID='PL10B';
NODE_NAME     R6744 1
 '@T6G_MB_LIB.T6G(SCH_1):PAGE467_I2@PURE_QUANTA.Q_RES(CHIPS)':
 'A': CDS_PINID='A';
NODE_NAME     R6742 2
 '@T6G_MB_LIB.T6G(SCH_1):PAGE467_I5@PURE_QUANTA.Q_RES(CHIPS)':
 'B': CDS_PINID='B';
NET_NAME
'RT_CPU0_P0_ADDR1'
 '@T6G_MB_LIB.T6G(SCH_1):RT_CPU0_P0_ADDR1':
 C_SIGNAL='@t6g_mb_lib.t6g(sch_1):rt_cpu0_p0_addr1';
NODE_NAME     U6010 F34
 '@T6G_MB_LIB.T6G(SCH_1):PAGE385_I53@PURE_QUANTA.PT5161LRS(CHIPS)':
 'SMB_ADDR1': CDS_PINID='SMB_ADDR1';
NODE_NAME     R969 1
 '@T6G_MB_LIB.T6G(SCH_1):PAGE385_I90@PURE_QUANTA.Q_RES(CHIPS)':
 'A': CDS_PINID='A';
NODE_NAME     R968 2
 '@T6G_MB_LIB.T6G(SCH_1):PAGE385_I91@PURE_QUANTA.Q_RES(CHIPS)':
 'B': CDS_PINID='B';
NET_NAME
'RT_CPU0_P0_ADDR2'
 '@T6G_MB_LIB.T6G(SCH_1):RT_CPU0_P0_ADDR2':
 C_SIGNAL='@t6g_mb_lib.t6g(sch_1):rt_cpu0_p0_addr2';
NODE_NAME     U6010 B23
 '@T6G_MB_LIB.T6G(SCH_1):PAGE385_I53@PURE_QUANTA.PT5161LRS(CHIPS)':
 'SMB_ADDR2': CDS_PINID='SMB_ADDR2';
NODE_NAME     R967 1
 '@T6G_MB_LIB.T6G(SCH_1):PAGE385_I87@PURE_QUANTA.Q_RES(CHIPS)':
 'A': CDS_PINID='A';
NODE_NAME     R966 2
 '@T6G_MB_LIB.T6G(SCH_1):PAGE385_I89@PURE_QUANTA.Q_RES(CHIPS)':
 'B': CDS_PINID='B';
NET_NAME
'RT_CPU0_P0_ADDR3'
 '@T6G_MB_LIB.T6G(SCH_1):RT_CPU0_P0_ADDR3':
 C_SIGNAL='@t6g_mb_lib.t6g(sch_1):rt_cpu0_p0_addr3';
NODE_NAME     U6010 B25
 '@T6G_MB_LIB.T6G(SCH_1):PAGE385_I53@PURE_QUANTA.PT5161LRS(CHIPS)':
 'SMB_ADDR3': CDS_PINID='SMB_ADDR3';
NODE_NAME     R965 1
 '@T6G_MB_LIB.T6G(SCH_1):PAGE385_I86@PURE_QUANTA.Q_RES(CHIPS)':
 'A': CDS_PINID='A';
NODE_NAME     R964 2
 '@T6G_MB_LIB.T6G(SCH_1):PAGE385_I88@PURE_QUANTA.Q_RES(CHIPS)':
 'B': CDS_PINID='B';
NET_NAME
'RT_CPU0_P0_SCAN_MODE'
 '@T6G_MB_LIB.T6G(SCH_1):RT_CPU0_P0_SCAN_MODE':
 C_SIGNAL='@t6g_mb_lib.t6g(sch_1):rt_cpu0_p0_scan_mode';
NODE_NAME     R972 2
 '@T6G_MB_LIB.T6G(SCH_1):PAGE385_I25@PURE_QUANTA.Q_RES(CHIPS)':
 'B': CDS_PINID='B';
NODE_NAME     U6010 FF33
 '@T6G_MB_LIB.T6G(SCH_1):PAGE385_I53@PURE_QUANTA.PT5161LRS(CHIPS)':
 'SCAN_MODE': CDS_PINID='SCAN_MODE';
NODE_NAME     R973 1
 '@T6G_MB_LIB.T6G(SCH_1):PAGE385_I121@PURE_QUANTA.Q_RES(CHIPS)':
 'A': CDS_PINID='A';
NET_NAME
'RT_CPU0_P0_VQPS'
 '@T6G_MB_LIB.T6G(SCH_1):RT_CPU0_P0_VQPS':
 C_SIGNAL='@t6g_mb_lib.t6g(sch_1):rt_cpu0_p0_vqps';
NODE_NAME     U6010 G1
 '@T6G_MB_LIB.T6G(SCH_1):PAGE386_I3@PURE_QUANTA.PT5161LRS(CHIPS)':
 'VQPS': CDS_PINID='VQPS';
NODE_NAME     R6809 1
 '@T6G_MB_LIB.T6G(SCH_1):PAGE386_I18@PURE_QUANTA.Q_RES(CHIPS)':
 'A': CDS_PINID='A';
NODE_NAME     R6808 2
 '@T6G_MB_LIB.T6G(SCH_1):PAGE386_I19@PURE_QUANTA.Q_RES(CHIPS)':
 'B': CDS_PINID='B';
NET_NAME
'RT_CPU0_P1_ADDR1'
 '@T6G_MB_LIB.T6G(SCH_1):RT_CPU0_P1_ADDR1':
 C_SIGNAL='@t6g_mb_lib.t6g(sch_1):rt_cpu0_p1_addr1';
NODE_NAME     R1018 1
 '@T6G_MB_LIB.T6G(SCH_1):PAGE408_I68@PURE_QUANTA.Q_RES(CHIPS)':
 'A': CDS_PINID='A';
NODE_NAME     R1017 2
 '@T6G_MB_LIB.T6G(SCH_1):PAGE408_I69@PURE_QUANTA.Q_RES(CHIPS)':
 'B': CDS_PINID='B';
NODE_NAME     U6011 F34
 '@T6G_MB_LIB.T6G(SCH_1):PAGE408_I83@PURE_QUANTA.PT5161LRS(CHIPS)':
 'SMB_ADDR1': CDS_PINID='SMB_ADDR1';
NET_NAME
'RT_CPU0_P1_ADDR2'
 '@T6G_MB_LIB.T6G(SCH_1):RT_CPU0_P1_ADDR2':
 C_SIGNAL='@t6g_mb_lib.t6g(sch_1):rt_cpu0_p1_addr2';
NODE_NAME     R1016 1
 '@T6G_MB_LIB.T6G(SCH_1):PAGE408_I65@PURE_QUANTA.Q_RES(CHIPS)':
 'A': CDS_PINID='A';
NODE_NAME     R1015 2
 '@T6G_MB_LIB.T6G(SCH_1):PAGE408_I67@PURE_QUANTA.Q_RES(CHIPS)':
 'B': CDS_PINID='B';
NODE_NAME     U6011 B23
 '@T6G_MB_LIB.T6G(SCH_1):PAGE408_I83@PURE_QUANTA.PT5161LRS(CHIPS)':
 'SMB_ADDR2': CDS_PINID='SMB_ADDR2';
NET_NAME
'RT_CPU0_P1_ADDR3'
 '@T6G_MB_LIB.T6G(SCH_1):RT_CPU0_P1_ADDR3':
 C_SIGNAL='@t6g_mb_lib.t6g(sch_1):rt_cpu0_p1_addr3';
NODE_NAME     R1014 1
 '@T6G_MB_LIB.T6G(SCH_1):PAGE408_I64@PURE_QUANTA.Q_RES(CHIPS)':
 'A': CDS_PINID='A';
NODE_NAME     R1013 2
 '@T6G_MB_LIB.T6G(SCH_1):PAGE408_I66@PURE_QUANTA.Q_RES(CHIPS)':
 'B': CDS_PINID='B';
NODE_NAME     U6011 B25
 '@T6G_MB_LIB.T6G(SCH_1):PAGE408_I83@PURE_QUANTA.PT5161LRS(CHIPS)':
 'SMB_ADDR3': CDS_PINID='SMB_ADDR3';
NET_NAME
'RT_CPU0_P1_SCAN_MODE'
 '@T6G_MB_LIB.T6G(SCH_1):RT_CPU0_P1_SCAN_MODE':
 C_SIGNAL='@t6g_mb_lib.t6g(sch_1):rt_cpu0_p1_scan_mode';
NODE_NAME     R1021 2
 '@T6G_MB_LIB.T6G(SCH_1):PAGE408_I5@PURE_QUANTA.Q_RES(CHIPS)':
 'B': CDS_PINID='B';
NODE_NAME     U6011 FF33
 '@T6G_MB_LIB.T6G(SCH_1):PAGE408_I83@PURE_QUANTA.PT5161LRS(CHIPS)':
 'SCAN_MODE': CDS_PINID='SCAN_MODE';
NODE_NAME     R1022 1
 '@T6G_MB_LIB.T6G(SCH_1):PAGE408_I102@PURE_QUANTA.Q_RES(CHIPS)':
 'A': CDS_PINID='A';
NET_NAME
'RT_CPU0_P1_VQPS'
 '@T6G_MB_LIB.T6G(SCH_1):RT_CPU0_P1_VQPS':
 C_SIGNAL='@t6g_mb_lib.t6g(sch_1):rt_cpu0_p1_vqps';
NODE_NAME     U6011 G1
 '@T6G_MB_LIB.T6G(SCH_1):PAGE409_I5@PURE_QUANTA.PT5161LRS(CHIPS)':
 'VQPS': CDS_PINID='VQPS';
NODE_NAME     R1041 1
 '@T6G_MB_LIB.T6G(SCH_1):PAGE409_I18@PURE_QUANTA.Q_RES(CHIPS)':
 'A': CDS_PINID='A';
NODE_NAME     R1040 2
 '@T6G_MB_LIB.T6G(SCH_1):PAGE409_I19@PURE_QUANTA.Q_RES(CHIPS)':
 'B': CDS_PINID='B';
NET_NAME
'RT_CPU0_P2_ADDR1'
 '@T6G_MB_LIB.T6G(SCH_1):RT_CPU0_P2_ADDR1':
 C_SIGNAL='@t6g_mb_lib.t6g(sch_1):rt_cpu0_p2_addr1';
NODE_NAME     R1060 1
 '@T6G_MB_LIB.T6G(SCH_1):PAGE419_I69@PURE_QUANTA.Q_RES(CHIPS)':
 'A': CDS_PINID='A';
NODE_NAME     R1059 2
 '@T6G_MB_LIB.T6G(SCH_1):PAGE419_I70@PURE_QUANTA.Q_RES(CHIPS)':
 'B': CDS_PINID='B';
NODE_NAME     U6012 F34
 '@T6G_MB_LIB.T6G(SCH_1):PAGE419_I83@PURE_QUANTA.PT5161LRS(CHIPS)':
 'SMB_ADDR1': CDS_PINID='SMB_ADDR1';
NET_NAME
'RT_CPU0_P2_ADDR2'
 '@T6G_MB_LIB.T6G(SCH_1):RT_CPU0_P2_ADDR2':
 C_SIGNAL='@t6g_mb_lib.t6g(sch_1):rt_cpu0_p2_addr2';
NODE_NAME     R1058 1
 '@T6G_MB_LIB.T6G(SCH_1):PAGE419_I66@PURE_QUANTA.Q_RES(CHIPS)':
 'A': CDS_PINID='A';
NODE_NAME     R1057 2
 '@T6G_MB_LIB.T6G(SCH_1):PAGE419_I68@PURE_QUANTA.Q_RES(CHIPS)':
 'B': CDS_PINID='B';
NODE_NAME     U6012 B23
 '@T6G_MB_LIB.T6G(SCH_1):PAGE419_I83@PURE_QUANTA.PT5161LRS(CHIPS)':
 'SMB_ADDR2': CDS_PINID='SMB_ADDR2';
NET_NAME
'RT_CPU0_P2_ADDR3'
 '@T6G_MB_LIB.T6G(SCH_1):RT_CPU0_P2_ADDR3':
 C_SIGNAL='@t6g_mb_lib.t6g(sch_1):rt_cpu0_p2_addr3';
NODE_NAME     R1056 1
 '@T6G_MB_LIB.T6G(SCH_1):PAGE419_I65@PURE_QUANTA.Q_RES(CHIPS)':
 'A': CDS_PINID='A';
NODE_NAME     R1055 2
 '@T6G_MB_LIB.T6G(SCH_1):PAGE419_I67@PURE_QUANTA.Q_RES(CHIPS)':
 'B': CDS_PINID='B';
NODE_NAME     U6012 B25
 '@T6G_MB_LIB.T6G(SCH_1):PAGE419_I83@PURE_QUANTA.PT5161LRS(CHIPS)':
 'SMB_ADDR3': CDS_PINID='SMB_ADDR3';
NET_NAME
'RT_CPU0_P2_SCAN_MODE'
 '@T6G_MB_LIB.T6G(SCH_1):RT_CPU0_P2_SCAN_MODE':
 C_SIGNAL='@t6g_mb_lib.t6g(sch_1):rt_cpu0_p2_scan_mode';
NODE_NAME     R1063 2
 '@T6G_MB_LIB.T6G(SCH_1):PAGE419_I5@PURE_QUANTA.Q_RES(CHIPS)':
 'B': CDS_PINID='B';
NODE_NAME     U6012 FF33
 '@T6G_MB_LIB.T6G(SCH_1):PAGE419_I83@PURE_QUANTA.PT5161LRS(CHIPS)':
 'SCAN_MODE': CDS_PINID='SCAN_MODE';
NODE_NAME     R1064 1
 '@T6G_MB_LIB.T6G(SCH_1):PAGE419_I102@PURE_QUANTA.Q_RES(CHIPS)':
 'A': CDS_PINID='A';
NET_NAME
'RT_CPU0_P2_VQPS'
 '@T6G_MB_LIB.T6G(SCH_1):RT_CPU0_P2_VQPS':
 C_SIGNAL='@t6g_mb_lib.t6g(sch_1):rt_cpu0_p2_vqps';
NODE_NAME     U6012 G1
 '@T6G_MB_LIB.T6G(SCH_1):PAGE420_I6@PURE_QUANTA.PT5161LRS(CHIPS)':
 'VQPS': CDS_PINID='VQPS';
NODE_NAME     R1082 1
 '@T6G_MB_LIB.T6G(SCH_1):PAGE420_I18@PURE_QUANTA.Q_RES(CHIPS)':
 'A': CDS_PINID='A';
NODE_NAME     R1081 2
 '@T6G_MB_LIB.T6G(SCH_1):PAGE420_I19@PURE_QUANTA.Q_RES(CHIPS)':
 'B': CDS_PINID='B';
NET_NAME
'RT_CPU0_P3_ADDR1'
 '@T6G_MB_LIB.T6G(SCH_1):RT_CPU0_P3_ADDR1':
 C_SIGNAL='@t6g_mb_lib.t6g(sch_1):rt_cpu0_p3_addr1';
NODE_NAME     R1102 1
 '@T6G_MB_LIB.T6G(SCH_1):PAGE430_I69@PURE_QUANTA.Q_RES(CHIPS)':
 'A': CDS_PINID='A';
NODE_NAME     R1101 2
 '@T6G_MB_LIB.T6G(SCH_1):PAGE430_I70@PURE_QUANTA.Q_RES(CHIPS)':
 'B': CDS_PINID='B';
NODE_NAME     U6013 F34
 '@T6G_MB_LIB.T6G(SCH_1):PAGE430_I83@PURE_QUANTA.PT5161LRS(CHIPS)':
 'SMB_ADDR1': CDS_PINID='SMB_ADDR1';
NET_NAME
'RT_CPU0_P3_ADDR2'
 '@T6G_MB_LIB.T6G(SCH_1):RT_CPU0_P3_ADDR2':
 C_SIGNAL='@t6g_mb_lib.t6g(sch_1):rt_cpu0_p3_addr2';
NODE_NAME     R1100 1
 '@T6G_MB_LIB.T6G(SCH_1):PAGE430_I66@PURE_QUANTA.Q_RES(CHIPS)':
 'A': CDS_PINID='A';
NODE_NAME     R1099 2
 '@T6G_MB_LIB.T6G(SCH_1):PAGE430_I68@PURE_QUANTA.Q_RES(CHIPS)':
 'B': CDS_PINID='B';
NODE_NAME     U6013 B23
 '@T6G_MB_LIB.T6G(SCH_1):PAGE430_I83@PURE_QUANTA.PT5161LRS(CHIPS)':
 'SMB_ADDR2': CDS_PINID='SMB_ADDR2';
NET_NAME
'RT_CPU0_P3_ADDR3'
 '@T6G_MB_LIB.T6G(SCH_1):RT_CPU0_P3_ADDR3':
 C_SIGNAL='@t6g_mb_lib.t6g(sch_1):rt_cpu0_p3_addr3';
NODE_NAME     R1098 1
 '@T6G_MB_LIB.T6G(SCH_1):PAGE430_I65@PURE_QUANTA.Q_RES(CHIPS)':
 'A': CDS_PINID='A';
NODE_NAME     R1097 2
 '@T6G_MB_LIB.T6G(SCH_1):PAGE430_I67@PURE_QUANTA.Q_RES(CHIPS)':
 'B': CDS_PINID='B';
NODE_NAME     U6013 B25
 '@T6G_MB_LIB.T6G(SCH_1):PAGE430_I83@PURE_QUANTA.PT5161LRS(CHIPS)':
 'SMB_ADDR3': CDS_PINID='SMB_ADDR3';
NET_NAME
'RT_CPU0_P3_SCAN_MODE'
 '@T6G_MB_LIB.T6G(SCH_1):RT_CPU0_P3_SCAN_MODE':
 C_SIGNAL='@t6g_mb_lib.t6g(sch_1):rt_cpu0_p3_scan_mode';
NODE_NAME     R1105 2
 '@T6G_MB_LIB.T6G(SCH_1):PAGE430_I5@PURE_QUANTA.Q_RES(CHIPS)':
 'B': CDS_PINID='B';
NODE_NAME     U6013 FF33
 '@T6G_MB_LIB.T6G(SCH_1):PAGE430_I83@PURE_QUANTA.PT5161LRS(CHIPS)':
 'SCAN_MODE': CDS_PINID='SCAN_MODE';
NODE_NAME     R1106 1
 '@T6G_MB_LIB.T6G(SCH_1):PAGE430_I102@PURE_QUANTA.Q_RES(CHIPS)':
 'A': CDS_PINID='A';
NET_NAME
'RT_CPU0_P3_VQPS'
 '@T6G_MB_LIB.T6G(SCH_1):RT_CPU0_P3_VQPS':
 C_SIGNAL='@t6g_mb_lib.t6g(sch_1):rt_cpu0_p3_vqps';
NODE_NAME     U6013 G1
 '@T6G_MB_LIB.T6G(SCH_1):PAGE431_I6@PURE_QUANTA.PT5161LRS(CHIPS)':
 'VQPS': CDS_PINID='VQPS';
NODE_NAME     R1124 1
 '@T6G_MB_LIB.T6G(SCH_1):PAGE431_I18@PURE_QUANTA.Q_RES(CHIPS)':
 'A': CDS_PINID='A';
NODE_NAME     R1123 2
 '@T6G_MB_LIB.T6G(SCH_1):PAGE431_I19@PURE_QUANTA.Q_RES(CHIPS)':
 'B': CDS_PINID='B';
NET_NAME
'RT_CPU1_P0_ADDR1'
 '@T6G_MB_LIB.T6G(SCH_1):RT_CPU1_P0_ADDR1':
 C_SIGNAL='@t6g_mb_lib.t6g(sch_1):rt_cpu1_p0_addr1';
NODE_NAME     U6014 F34
 '@T6G_MB_LIB.T6G(SCH_1):PAGE401_I1@PURE_QUANTA.PT5161LRS(CHIPS)':
 'SMB_ADDR1': CDS_PINID='SMB_ADDR1';
NODE_NAME     R6717 1
 '@T6G_MB_LIB.T6G(SCH_1):PAGE401_I106@PURE_QUANTA.Q_RES(CHIPS)':
 'A': CDS_PINID='A';
NODE_NAME     R6716 2
 '@T6G_MB_LIB.T6G(SCH_1):PAGE401_I107@PURE_QUANTA.Q_RES(CHIPS)':
 'B': CDS_PINID='B';
NET_NAME
'RT_CPU1_P0_ADDR2'
 '@T6G_MB_LIB.T6G(SCH_1):RT_CPU1_P0_ADDR2':
 C_SIGNAL='@t6g_mb_lib.t6g(sch_1):rt_cpu1_p0_addr2';
NODE_NAME     U6014 B23
 '@T6G_MB_LIB.T6G(SCH_1):PAGE401_I1@PURE_QUANTA.PT5161LRS(CHIPS)':
 'SMB_ADDR2': CDS_PINID='SMB_ADDR2';
NODE_NAME     R6714 2
 '@T6G_MB_LIB.T6G(SCH_1):PAGE401_I104@PURE_QUANTA.Q_RES(CHIPS)':
 'B': CDS_PINID='B';
NODE_NAME     R6715 1
 '@T6G_MB_LIB.T6G(SCH_1):PAGE401_I105@PURE_QUANTA.Q_RES(CHIPS)':
 'A': CDS_PINID='A';
NET_NAME
'RT_CPU1_P0_ADDR3'
 '@T6G_MB_LIB.T6G(SCH_1):RT_CPU1_P0_ADDR3':
 C_SIGNAL='@t6g_mb_lib.t6g(sch_1):rt_cpu1_p0_addr3';
NODE_NAME     U6014 B25
 '@T6G_MB_LIB.T6G(SCH_1):PAGE401_I1@PURE_QUANTA.PT5161LRS(CHIPS)':
 'SMB_ADDR3': CDS_PINID='SMB_ADDR3';
NODE_NAME     R6712 2
 '@T6G_MB_LIB.T6G(SCH_1):PAGE401_I102@PURE_QUANTA.Q_RES(CHIPS)':
 'B': CDS_PINID='B';
NODE_NAME     R6713 1
 '@T6G_MB_LIB.T6G(SCH_1):PAGE401_I103@PURE_QUANTA.Q_RES(CHIPS)':
 'A': CDS_PINID='A';
NET_NAME
'RT_CPU1_P0_SCAN_MODE'
 '@T6G_MB_LIB.T6G(SCH_1):RT_CPU1_P0_SCAN_MODE':
 C_SIGNAL='@t6g_mb_lib.t6g(sch_1):rt_cpu1_p0_scan_mode';
NODE_NAME     U6014 FF33
 '@T6G_MB_LIB.T6G(SCH_1):PAGE401_I1@PURE_QUANTA.PT5161LRS(CHIPS)':
 'SCAN_MODE': CDS_PINID='SCAN_MODE';
NODE_NAME     R6722 2
 '@T6G_MB_LIB.T6G(SCH_1):PAGE401_I85@PURE_QUANTA.Q_RES(CHIPS)':
 'B': CDS_PINID='B';
NODE_NAME     R6723 1
 '@T6G_MB_LIB.T6G(SCH_1):PAGE401_I128@PURE_QUANTA.Q_RES(CHIPS)':
 'A': CDS_PINID='A';
NET_NAME
'RT_CPU1_P0_VQPS'
 '@T6G_MB_LIB.T6G(SCH_1):RT_CPU1_P0_VQPS':
 C_SIGNAL='@t6g_mb_lib.t6g(sch_1):rt_cpu1_p0_vqps';
NODE_NAME     U6014 G1
 '@T6G_MB_LIB.T6G(SCH_1):PAGE400_I1@PURE_QUANTA.PT5161LRS(CHIPS)':
 'VQPS': CDS_PINID='VQPS';
NODE_NAME     R701 1
 '@T6G_MB_LIB.T6G(SCH_1):PAGE400_I105@PURE_QUANTA.Q_RES(CHIPS)':
 'A': CDS_PINID='A';
NODE_NAME     R699 2
 '@T6G_MB_LIB.T6G(SCH_1):PAGE400_I106@PURE_QUANTA.Q_RES(CHIPS)':
 'B': CDS_PINID='B';
NET_NAME
'RT_CPU1_P1_ADDR1'
 '@T6G_MB_LIB.T6G(SCH_1):RT_CPU1_P1_ADDR1':
 C_SIGNAL='@t6g_mb_lib.t6g(sch_1):rt_cpu1_p1_addr1';
NODE_NAME     U6015 F34
 '@T6G_MB_LIB.T6G(SCH_1):PAGE392_I47@PURE_QUANTA.PT5161LRS(CHIPS)':
 'SMB_ADDR1': CDS_PINID='SMB_ADDR1';
NODE_NAME     R796 1
 '@T6G_MB_LIB.T6G(SCH_1):PAGE392_I105@PURE_QUANTA.Q_RES(CHIPS)':
 'A': CDS_PINID='A';
NODE_NAME     R795 2
 '@T6G_MB_LIB.T6G(SCH_1):PAGE392_I110@PURE_QUANTA.Q_RES(CHIPS)':
 'B': CDS_PINID='B';
NET_NAME
'RT_CPU1_P1_ADDR2'
 '@T6G_MB_LIB.T6G(SCH_1):RT_CPU1_P1_ADDR2':
 C_SIGNAL='@t6g_mb_lib.t6g(sch_1):rt_cpu1_p1_addr2';
NODE_NAME     U6015 B23
 '@T6G_MB_LIB.T6G(SCH_1):PAGE392_I47@PURE_QUANTA.PT5161LRS(CHIPS)':
 'SMB_ADDR2': CDS_PINID='SMB_ADDR2';
NODE_NAME     R746 1
 '@T6G_MB_LIB.T6G(SCH_1):PAGE392_I102@PURE_QUANTA.Q_RES(CHIPS)':
 'A': CDS_PINID='A';
NODE_NAME     R745 2
 '@T6G_MB_LIB.T6G(SCH_1):PAGE392_I104@PURE_QUANTA.Q_RES(CHIPS)':
 'B': CDS_PINID='B';
NET_NAME
'RT_CPU1_P1_ADDR3'
 '@T6G_MB_LIB.T6G(SCH_1):RT_CPU1_P1_ADDR3':
 C_SIGNAL='@t6g_mb_lib.t6g(sch_1):rt_cpu1_p1_addr3';
NODE_NAME     U6015 B25
 '@T6G_MB_LIB.T6G(SCH_1):PAGE392_I47@PURE_QUANTA.PT5161LRS(CHIPS)':
 'SMB_ADDR3': CDS_PINID='SMB_ADDR3';
NODE_NAME     R741 1
 '@T6G_MB_LIB.T6G(SCH_1):PAGE392_I101@PURE_QUANTA.Q_RES(CHIPS)':
 'A': CDS_PINID='A';
NODE_NAME     R735 2
 '@T6G_MB_LIB.T6G(SCH_1):PAGE392_I103@PURE_QUANTA.Q_RES(CHIPS)':
 'B': CDS_PINID='B';
NET_NAME
'RT_CPU1_P1_SCAN_MODE'
 '@T6G_MB_LIB.T6G(SCH_1):RT_CPU1_P1_SCAN_MODE':
 C_SIGNAL='@t6g_mb_lib.t6g(sch_1):rt_cpu1_p1_scan_mode';
NODE_NAME     R755 2
 '@T6G_MB_LIB.T6G(SCH_1):PAGE392_I19@PURE_QUANTA.Q_RES(CHIPS)':
 'B': CDS_PINID='B';
NODE_NAME     U6015 FF33
 '@T6G_MB_LIB.T6G(SCH_1):PAGE392_I47@PURE_QUANTA.PT5161LRS(CHIPS)':
 'SCAN_MODE': CDS_PINID='SCAN_MODE';
NODE_NAME     R756 1
 '@T6G_MB_LIB.T6G(SCH_1):PAGE392_I132@PURE_QUANTA.Q_RES(CHIPS)':
 'A': CDS_PINID='A';
NET_NAME
'RT_CPU1_P1_VQPS'
 '@T6G_MB_LIB.T6G(SCH_1):RT_CPU1_P1_VQPS':
 C_SIGNAL='@t6g_mb_lib.t6g(sch_1):rt_cpu1_p1_vqps';
NODE_NAME     U6015 G1
 '@T6G_MB_LIB.T6G(SCH_1):PAGE391_I5@PURE_QUANTA.PT5161LRS(CHIPS)':
 'VQPS': CDS_PINID='VQPS';
NODE_NAME     R6731 1
 '@T6G_MB_LIB.T6G(SCH_1):PAGE391_I20@PURE_QUANTA.Q_RES(CHIPS)':
 'A': CDS_PINID='A';
NODE_NAME     R6730 2
 '@T6G_MB_LIB.T6G(SCH_1):PAGE391_I21@PURE_QUANTA.Q_RES(CHIPS)':
 'B': CDS_PINID='B';
NET_NAME
'RT_CPU1_P2_ADDR1'
 '@T6G_MB_LIB.T6G(SCH_1):RT_CPU1_P2_ADDR1':
 C_SIGNAL='@t6g_mb_lib.t6g(sch_1):rt_cpu1_p2_addr1';
NODE_NAME     R892 1
 '@T6G_MB_LIB.T6G(SCH_1):PAGE451_I76@PURE_QUANTA.Q_RES(CHIPS)':
 'A': CDS_PINID='A';
NODE_NAME     R887 2
 '@T6G_MB_LIB.T6G(SCH_1):PAGE451_I77@PURE_QUANTA.Q_RES(CHIPS)':
 'B': CDS_PINID='B';
NODE_NAME     U6016 F34
 '@T6G_MB_LIB.T6G(SCH_1):PAGE451_I97@PURE_QUANTA.PT5161LRS(CHIPS)':
 'SMB_ADDR1': CDS_PINID='SMB_ADDR1';
NET_NAME
'RT_CPU1_P2_ADDR2'
 '@T6G_MB_LIB.T6G(SCH_1):RT_CPU1_P2_ADDR2':
 C_SIGNAL='@t6g_mb_lib.t6g(sch_1):rt_cpu1_p2_addr2';
NODE_NAME     R865 1
 '@T6G_MB_LIB.T6G(SCH_1):PAGE451_I72@PURE_QUANTA.Q_RES(CHIPS)':
 'A': CDS_PINID='A';
NODE_NAME     R864 2
 '@T6G_MB_LIB.T6G(SCH_1):PAGE451_I75@PURE_QUANTA.Q_RES(CHIPS)':
 'B': CDS_PINID='B';
NODE_NAME     U6016 B23
 '@T6G_MB_LIB.T6G(SCH_1):PAGE451_I97@PURE_QUANTA.PT5161LRS(CHIPS)':
 'SMB_ADDR2': CDS_PINID='SMB_ADDR2';
NET_NAME
'RT_CPU1_P2_ADDR3'
 '@T6G_MB_LIB.T6G(SCH_1):RT_CPU1_P2_ADDR3':
 C_SIGNAL='@t6g_mb_lib.t6g(sch_1):rt_cpu1_p2_addr3';
NODE_NAME     R863 1
 '@T6G_MB_LIB.T6G(SCH_1):PAGE451_I71@PURE_QUANTA.Q_RES(CHIPS)':
 'A': CDS_PINID='A';
NODE_NAME     R861 2
 '@T6G_MB_LIB.T6G(SCH_1):PAGE451_I74@PURE_QUANTA.Q_RES(CHIPS)':
 'B': CDS_PINID='B';
NODE_NAME     U6016 B25
 '@T6G_MB_LIB.T6G(SCH_1):PAGE451_I97@PURE_QUANTA.PT5161LRS(CHIPS)':
 'SMB_ADDR3': CDS_PINID='SMB_ADDR3';
NET_NAME
'RT_CPU1_P2_SCAN_MODE'
 '@T6G_MB_LIB.T6G(SCH_1):RT_CPU1_P2_SCAN_MODE':
 C_SIGNAL='@t6g_mb_lib.t6g(sch_1):rt_cpu1_p2_scan_mode';
NODE_NAME     R868 2
 '@T6G_MB_LIB.T6G(SCH_1):PAGE451_I17@PURE_QUANTA.Q_RES(CHIPS)':
 'B': CDS_PINID='B';
NODE_NAME     U6016 FF33
 '@T6G_MB_LIB.T6G(SCH_1):PAGE451_I97@PURE_QUANTA.PT5161LRS(CHIPS)':
 'SCAN_MODE': CDS_PINID='SCAN_MODE';
NODE_NAME     R869 1
 '@T6G_MB_LIB.T6G(SCH_1):PAGE451_I119@PURE_QUANTA.Q_RES(CHIPS)':
 'A': CDS_PINID='A';
NET_NAME
'RT_CPU1_P2_VQPS'
 '@T6G_MB_LIB.T6G(SCH_1):RT_CPU1_P2_VQPS':
 C_SIGNAL='@t6g_mb_lib.t6g(sch_1):rt_cpu1_p2_vqps';
NODE_NAME     U6016 G1
 '@T6G_MB_LIB.T6G(SCH_1):PAGE452_I7@PURE_QUANTA.PT5161LRS(CHIPS)':
 'VQPS': CDS_PINID='VQPS';
NODE_NAME     R6795 1
 '@T6G_MB_LIB.T6G(SCH_1):PAGE452_I20@PURE_QUANTA.Q_RES(CHIPS)':
 'A': CDS_PINID='A';
NODE_NAME     R6794 2
 '@T6G_MB_LIB.T6G(SCH_1):PAGE452_I21@PURE_QUANTA.Q_RES(CHIPS)':
 'B': CDS_PINID='B';
NET_NAME
'RT_CPU1_P3_ADDR1'
 '@T6G_MB_LIB.T6G(SCH_1):RT_CPU1_P3_ADDR1':
 C_SIGNAL='@t6g_mb_lib.t6g(sch_1):rt_cpu1_p3_addr1';
NODE_NAME     R949 1
 '@T6G_MB_LIB.T6G(SCH_1):PAGE462_I83@PURE_QUANTA.Q_RES(CHIPS)':
 'A': CDS_PINID='A';
NODE_NAME     R927 2
 '@T6G_MB_LIB.T6G(SCH_1):PAGE462_I84@PURE_QUANTA.Q_RES(CHIPS)':
 'B': CDS_PINID='B';
NODE_NAME     U6017 F34
 '@T6G_MB_LIB.T6G(SCH_1):PAGE462_I97@PURE_QUANTA.PT5161LRS(CHIPS)':
 'SMB_ADDR1': CDS_PINID='SMB_ADDR1';
NET_NAME
'RT_CPU1_P3_ADDR2'
 '@T6G_MB_LIB.T6G(SCH_1):RT_CPU1_P3_ADDR2':
 C_SIGNAL='@t6g_mb_lib.t6g(sch_1):rt_cpu1_p3_addr2';
NODE_NAME     R906 1
 '@T6G_MB_LIB.T6G(SCH_1):PAGE462_I81@PURE_QUANTA.Q_RES(CHIPS)':
 'A': CDS_PINID='A';
NODE_NAME     R904 2
 '@T6G_MB_LIB.T6G(SCH_1):PAGE462_I82@PURE_QUANTA.Q_RES(CHIPS)':
 'B': CDS_PINID='B';
NODE_NAME     U6017 B23
 '@T6G_MB_LIB.T6G(SCH_1):PAGE462_I97@PURE_QUANTA.PT5161LRS(CHIPS)':
 'SMB_ADDR2': CDS_PINID='SMB_ADDR2';
NET_NAME
'RT_CPU1_P3_ADDR3'
 '@T6G_MB_LIB.T6G(SCH_1):RT_CPU1_P3_ADDR3':
 C_SIGNAL='@t6g_mb_lib.t6g(sch_1):rt_cpu1_p3_addr3';
NODE_NAME     R903 1
 '@T6G_MB_LIB.T6G(SCH_1):PAGE462_I79@PURE_QUANTA.Q_RES(CHIPS)':
 'A': CDS_PINID='A';
NODE_NAME     R902 2
 '@T6G_MB_LIB.T6G(SCH_1):PAGE462_I80@PURE_QUANTA.Q_RES(CHIPS)':
 'B': CDS_PINID='B';
NODE_NAME     U6017 B25
 '@T6G_MB_LIB.T6G(SCH_1):PAGE462_I97@PURE_QUANTA.PT5161LRS(CHIPS)':
 'SMB_ADDR3': CDS_PINID='SMB_ADDR3';
NET_NAME
'RT_CPU1_P3_SCAN_MODE'
 '@T6G_MB_LIB.T6G(SCH_1):RT_CPU1_P3_SCAN_MODE':
 C_SIGNAL='@t6g_mb_lib.t6g(sch_1):rt_cpu1_p3_scan_mode';
NODE_NAME     R909 2
 '@T6G_MB_LIB.T6G(SCH_1):PAGE462_I17@PURE_QUANTA.Q_RES(CHIPS)':
 'B': CDS_PINID='B';
NODE_NAME     U6017 FF33
 '@T6G_MB_LIB.T6G(SCH_1):PAGE462_I97@PURE_QUANTA.PT5161LRS(CHIPS)':
 'SCAN_MODE': CDS_PINID='SCAN_MODE';
NODE_NAME     R910 1
 '@T6G_MB_LIB.T6G(SCH_1):PAGE462_I119@PURE_QUANTA.Q_RES(CHIPS)':
 'A': CDS_PINID='A';
NET_NAME
'RT_CPU1_P3_VQPS'
 '@T6G_MB_LIB.T6G(SCH_1):RT_CPU1_P3_VQPS':
 C_SIGNAL='@t6g_mb_lib.t6g(sch_1):rt_cpu1_p3_vqps';
NODE_NAME     U6017 G1
 '@T6G_MB_LIB.T6G(SCH_1):PAGE463_I5@PURE_QUANTA.PT5161LRS(CHIPS)':
 'VQPS': CDS_PINID='VQPS';
NODE_NAME     R6901 1
 '@T6G_MB_LIB.T6G(SCH_1):PAGE463_I18@PURE_QUANTA.Q_RES(CHIPS)':
 'A': CDS_PINID='A';
NODE_NAME     R6900 2
 '@T6G_MB_LIB.T6G(SCH_1):PAGE463_I19@PURE_QUANTA.Q_RES(CHIPS)':
 'B': CDS_PINID='B';
NET_NAME
'RT_ROM_MUX1_OE_N'
 '@T6G_MB_LIB.T6G(SCH_1):RT_ROM_MUX1_OE_N':
 C_SIGNAL='@t6g_mb_lib.t6g(sch_1):rt_rom_mux1_oe_n';
NODE_NAME     U45 6
 '@T6G_MB_LIB.T6G(SCH_1):PAGE376_I22@PURE_QUANTA.PI3CSW12ZUAEX(CHIPS)':
 'OE#': CDS_PINID='\oe#\';
NODE_NAME     R1215 2
 '@T6G_MB_LIB.T6G(SCH_1):PAGE376_I28@PURE_QUANTA.Q_RES(CHIPS)':
 'B': CDS_PINID='B';
NET_NAME
'RT_ROM_MUX2_OE_N'
 '@T6G_MB_LIB.T6G(SCH_1):RT_ROM_MUX2_OE_N':
 C_SIGNAL='@t6g_mb_lib.t6g(sch_1):rt_rom_mux2_oe_n';
NODE_NAME     U42 6
 '@T6G_MB_LIB.T6G(SCH_1):PAGE376_I31@PURE_QUANTA.PI3CSW12ZUAEX(CHIPS)':
 'OE#': CDS_PINID='\oe#\';
NODE_NAME     R1213 2
 '@T6G_MB_LIB.T6G(SCH_1):PAGE376_I41@PURE_QUANTA.Q_RES(CHIPS)':
 'B': CDS_PINID='B';
NET_NAME
'RT_ROM_MUX3_OE_N'
 '@T6G_MB_LIB.T6G(SCH_1):RT_ROM_MUX3_OE_N':
 C_SIGNAL='@t6g_mb_lib.t6g(sch_1):rt_rom_mux3_oe_n';
NODE_NAME     U41 6
 '@T6G_MB_LIB.T6G(SCH_1):PAGE376_I46@PURE_QUANTA.PI3CSW12ZUAEX(CHIPS)':
 'OE#': CDS_PINID='\oe#\';
NODE_NAME     R1212 2
 '@T6G_MB_LIB.T6G(SCH_1):PAGE376_I54@PURE_QUANTA.Q_RES(CHIPS)':
 'B': CDS_PINID='B';
NET_NAME
'RT_ROM_MUX4_OE_N'
 '@T6G_MB_LIB.T6G(SCH_1):RT_ROM_MUX4_OE_N':
 C_SIGNAL='@t6g_mb_lib.t6g(sch_1):rt_rom_mux4_oe_n';
NODE_NAME     U43 6
 '@T6G_MB_LIB.T6G(SCH_1):PAGE376_I61@PURE_QUANTA.PI3CSW12ZUAEX(CHIPS)':
 'OE#': CDS_PINID='\oe#\';
NODE_NAME     R1214 2
 '@T6G_MB_LIB.T6G(SCH_1):PAGE376_I69@PURE_QUANTA.Q_RES(CHIPS)':
 'B': CDS_PINID='B';
NET_NAME
'RT_ROM_MUX5_OE_N'
 '@T6G_MB_LIB.T6G(SCH_1):RT_ROM_MUX5_OE_N':
 C_SIGNAL='@t6g_mb_lib.t6g(sch_1):rt_rom_mux5_oe_n';
NODE_NAME     U49 6
 '@T6G_MB_LIB.T6G(SCH_1):PAGE376_I85@PURE_QUANTA.PI3CSW12ZUAEX(CHIPS)':
 'OE#': CDS_PINID='\oe#\';
NODE_NAME     R1219 2
 '@T6G_MB_LIB.T6G(SCH_1):PAGE376_I87@PURE_QUANTA.Q_RES(CHIPS)':
 'B': CDS_PINID='B';
NET_NAME
'RT_ROM_MUX6_OE_N'
 '@T6G_MB_LIB.T6G(SCH_1):RT_ROM_MUX6_OE_N':
 C_SIGNAL='@t6g_mb_lib.t6g(sch_1):rt_rom_mux6_oe_n';
NODE_NAME     U48 6
 '@T6G_MB_LIB.T6G(SCH_1):PAGE376_I76@PURE_QUANTA.PI3CSW12ZUAEX(CHIPS)':
 'OE#': CDS_PINID='\oe#\';
NODE_NAME     R1218 2
 '@T6G_MB_LIB.T6G(SCH_1):PAGE376_I110@PURE_QUANTA.Q_RES(CHIPS)':
 'B': CDS_PINID='B';
NET_NAME
'RT_ROM_MUX7_OE_N'
 '@T6G_MB_LIB.T6G(SCH_1):RT_ROM_MUX7_OE_N':
 C_SIGNAL='@t6g_mb_lib.t6g(sch_1):rt_rom_mux7_oe_n';
NODE_NAME     U46 6
 '@T6G_MB_LIB.T6G(SCH_1):PAGE376_I108@PURE_QUANTA.PI3CSW12ZUAEX(CHIPS)':
 'OE#': CDS_PINID='\oe#\';
NODE_NAME     R1216 2
 '@T6G_MB_LIB.T6G(SCH_1):PAGE376_I116@PURE_QUANTA.Q_RES(CHIPS)':
 'B': CDS_PINID='B';
NET_NAME
'RT_ROM_MUX8_OE_N'
 '@T6G_MB_LIB.T6G(SCH_1):RT_ROM_MUX8_OE_N':
 C_SIGNAL='@t6g_mb_lib.t6g(sch_1):rt_rom_mux8_oe_n';
NODE_NAME     U47 6
 '@T6G_MB_LIB.T6G(SCH_1):PAGE376_I121@PURE_QUANTA.PI3CSW12ZUAEX(CHIPS)':
 'OE#': CDS_PINID='\oe#\';
NODE_NAME     R1217 2
 '@T6G_MB_LIB.T6G(SCH_1):PAGE376_I122@PURE_QUANTA.Q_RES(CHIPS)':
 'B': CDS_PINID='B';
NET_NAME
'RT_ROM_SMB_MUX_ADDR0'
 '@T6G_MB_LIB.T6G(SCH_1):RT_ROM_SMB_MUX_ADDR0':
 C_SIGNAL='@t6g_mb_lib.t6g(sch_1):rt_rom_smb_mux_addr0';
NODE_NAME     R847 1
 '@T6G_MB_LIB.T6G(SCH_1):PAGE377_I8@PURE_QUANTA.Q_RES(CHIPS)':
 'A': CDS_PINID='A';
NODE_NAME     R844 2
 '@T6G_MB_LIB.T6G(SCH_1):PAGE377_I9@PURE_QUANTA.Q_RES(CHIPS)':
 'B': CDS_PINID='B';
NODE_NAME     U22 1
 '@T6G_MB_LIB.T6G(SCH_1):PAGE377_I94@PURE_QUANTA.TCA9548APWR(CHIPS)':
 'A0': CDS_PINID='A0';
NET_NAME
'RT_ROM_SMB_MUX_ADDR1'
 '@T6G_MB_LIB.T6G(SCH_1):RT_ROM_SMB_MUX_ADDR1':
 C_SIGNAL='@t6g_mb_lib.t6g(sch_1):rt_rom_smb_mux_addr1';
NODE_NAME     R846 1
 '@T6G_MB_LIB.T6G(SCH_1):PAGE377_I3@PURE_QUANTA.Q_RES(CHIPS)':
 'A': CDS_PINID='A';
NODE_NAME     R843 2
 '@T6G_MB_LIB.T6G(SCH_1):PAGE377_I5@PURE_QUANTA.Q_RES(CHIPS)':
 'B': CDS_PINID='B';
NODE_NAME     U22 2
 '@T6G_MB_LIB.T6G(SCH_1):PAGE377_I94@PURE_QUANTA.TCA9548APWR(CHIPS)':
 'A1': CDS_PINID='A1';
NET_NAME
'RT_ROM_SMB_MUX_ADDR2'
 '@T6G_MB_LIB.T6G(SCH_1):RT_ROM_SMB_MUX_ADDR2':
 C_SIGNAL='@t6g_mb_lib.t6g(sch_1):rt_rom_smb_mux_addr2';
NODE_NAME     R845 1
 '@T6G_MB_LIB.T6G(SCH_1):PAGE377_I2@PURE_QUANTA.Q_RES(CHIPS)':
 'A': CDS_PINID='A';
NODE_NAME     R842 2
 '@T6G_MB_LIB.T6G(SCH_1):PAGE377_I4@PURE_QUANTA.Q_RES(CHIPS)':
 'B': CDS_PINID='B';
NODE_NAME     U22 21
 '@T6G_MB_LIB.T6G(SCH_1):PAGE377_I94@PURE_QUANTA.TCA9548APWR(CHIPS)':
 'A2': CDS_PINID='A2';
NET_NAME
'RT_SMB_MUX_ADDR0'
 '@T6G_MB_LIB.T6G(SCH_1):RT_SMB_MUX_ADDR0':
 C_SIGNAL='@t6g_mb_lib.t6g(sch_1):rt_smb_mux_addr0';
NODE_NAME     U6020 1
 '@T6G_MB_LIB.T6G(SCH_1):PAGE378_I1@PURE_QUANTA.TCA9548APWR(CHIPS)':
 'A0': CDS_PINID='A0';
NODE_NAME     R6775 1
 '@T6G_MB_LIB.T6G(SCH_1):PAGE378_I97@PURE_QUANTA.Q_RES(CHIPS)':
 'A': CDS_PINID='A';
NODE_NAME     R6772 2
 '@T6G_MB_LIB.T6G(SCH_1):PAGE378_I98@PURE_QUANTA.Q_RES(CHIPS)':
 'B': CDS_PINID='B';
NET_NAME
'RT_SMB_MUX_ADDR1'
 '@T6G_MB_LIB.T6G(SCH_1):RT_SMB_MUX_ADDR1':
 C_SIGNAL='@t6g_mb_lib.t6g(sch_1):rt_smb_mux_addr1';
NODE_NAME     U6020 2
 '@T6G_MB_LIB.T6G(SCH_1):PAGE378_I1@PURE_QUANTA.TCA9548APWR(CHIPS)':
 'A1': CDS_PINID='A1';
NODE_NAME     R6774 1
 '@T6G_MB_LIB.T6G(SCH_1):PAGE378_I95@PURE_QUANTA.Q_RES(CHIPS)':
 'A': CDS_PINID='A';
NODE_NAME     R6771 2
 '@T6G_MB_LIB.T6G(SCH_1):PAGE378_I100@PURE_QUANTA.Q_RES(CHIPS)':
 'B': CDS_PINID='B';
NET_NAME
'RT_SMB_MUX_ADDR2'
 '@T6G_MB_LIB.T6G(SCH_1):RT_SMB_MUX_ADDR2':
 C_SIGNAL='@t6g_mb_lib.t6g(sch_1):rt_smb_mux_addr2';
NODE_NAME     U6020 21
 '@T6G_MB_LIB.T6G(SCH_1):PAGE378_I1@PURE_QUANTA.TCA9548APWR(CHIPS)':
 'A2': CDS_PINID='A2';
NODE_NAME     R6773 1
 '@T6G_MB_LIB.T6G(SCH_1):PAGE378_I94@PURE_QUANTA.Q_RES(CHIPS)':
 'A': CDS_PINID='A';
NODE_NAME     R6770 2
 '@T6G_MB_LIB.T6G(SCH_1):PAGE378_I96@PURE_QUANTA.Q_RES(CHIPS)':
 'B': CDS_PINID='B';
NET_NAME
'RXDET_BYP_RT_CPU0_P0'
 '@T6G_MB_LIB.T6G(SCH_1):RXDET_BYP_RT_CPU0_P0':
 C_SIGNAL='@t6g_mb_lib.t6g(sch_1):rxdet_byp_rt_cpu0_p0';
NODE_NAME     U6010 E11
 '@T6G_MB_LIB.T6G(SCH_1):PAGE385_I53@PURE_QUANTA.PT5161LRS(CHIPS)':
 'RXDET_BYP': CDS_PINID='RXDET_BYP';
NODE_NAME     R1370 1
 '@T6G_MB_LIB.T6G(SCH_1):PAGE385_I114@PURE_QUANTA.Q_RES(CHIPS)':
 'A': CDS_PINID='A';
NODE_NAME     R1369 2
 '@T6G_MB_LIB.T6G(SCH_1):PAGE385_I116@PURE_QUANTA.Q_RES(CHIPS)':
 'B': CDS_PINID='B';
NET_NAME
'RXDET_BYP_RT_CPU0_P1'
 '@T6G_MB_LIB.T6G(SCH_1):RXDET_BYP_RT_CPU0_P1':
 C_SIGNAL='@t6g_mb_lib.t6g(sch_1):rxdet_byp_rt_cpu0_p1';
NODE_NAME     U6011 E11
 '@T6G_MB_LIB.T6G(SCH_1):PAGE408_I83@PURE_QUANTA.PT5161LRS(CHIPS)':
 'RXDET_BYP': CDS_PINID='RXDET_BYP';
NODE_NAME     R1398 1
 '@T6G_MB_LIB.T6G(SCH_1):PAGE408_I98@PURE_QUANTA.Q_RES(CHIPS)':
 'A': CDS_PINID='A';
NODE_NAME     R1397 2
 '@T6G_MB_LIB.T6G(SCH_1):PAGE408_I99@PURE_QUANTA.Q_RES(CHIPS)':
 'B': CDS_PINID='B';
NET_NAME
'RXDET_BYP_RT_CPU0_P2'
 '@T6G_MB_LIB.T6G(SCH_1):RXDET_BYP_RT_CPU0_P2':
 C_SIGNAL='@t6g_mb_lib.t6g(sch_1):rxdet_byp_rt_cpu0_p2';
NODE_NAME     U6012 E11
 '@T6G_MB_LIB.T6G(SCH_1):PAGE419_I83@PURE_QUANTA.PT5161LRS(CHIPS)':
 'RXDET_BYP': CDS_PINID='RXDET_BYP';
NODE_NAME     R1406 1
 '@T6G_MB_LIB.T6G(SCH_1):PAGE419_I95@PURE_QUANTA.Q_RES(CHIPS)':
 'A': CDS_PINID='A';
NODE_NAME     R1405 2
 '@T6G_MB_LIB.T6G(SCH_1):PAGE419_I96@PURE_QUANTA.Q_RES(CHIPS)':
 'B': CDS_PINID='B';
NET_NAME
'RXDET_BYP_RT_CPU0_P3'
 '@T6G_MB_LIB.T6G(SCH_1):RXDET_BYP_RT_CPU0_P3':
 C_SIGNAL='@t6g_mb_lib.t6g(sch_1):rxdet_byp_rt_cpu0_p3';
NODE_NAME     U6013 E11
 '@T6G_MB_LIB.T6G(SCH_1):PAGE430_I83@PURE_QUANTA.PT5161LRS(CHIPS)':
 'RXDET_BYP': CDS_PINID='RXDET_BYP';
NODE_NAME     R1414 1
 '@T6G_MB_LIB.T6G(SCH_1):PAGE430_I96@PURE_QUANTA.Q_RES(CHIPS)':
 'A': CDS_PINID='A';
NODE_NAME     R1413 2
 '@T6G_MB_LIB.T6G(SCH_1):PAGE430_I97@PURE_QUANTA.Q_RES(CHIPS)':
 'B': CDS_PINID='B';
NET_NAME
'RXDET_BYP_RT_CPU1_P0'
 '@T6G_MB_LIB.T6G(SCH_1):RXDET_BYP_RT_CPU1_P0':
 C_SIGNAL='@t6g_mb_lib.t6g(sch_1):rxdet_byp_rt_cpu1_p0';
NODE_NAME     U6014 E11
 '@T6G_MB_LIB.T6G(SCH_1):PAGE401_I1@PURE_QUANTA.PT5161LRS(CHIPS)':
 'RXDET_BYP': CDS_PINID='RXDET_BYP';
NODE_NAME     R1389 1
 '@T6G_MB_LIB.T6G(SCH_1):PAGE401_I124@PURE_QUANTA.Q_RES(CHIPS)':
 'A': CDS_PINID='A';
NODE_NAME     R1388 2
 '@T6G_MB_LIB.T6G(SCH_1):PAGE401_I125@PURE_QUANTA.Q_RES(CHIPS)':
 'B': CDS_PINID='B';
NET_NAME
'RXDET_BYP_RT_CPU1_P1'
 '@T6G_MB_LIB.T6G(SCH_1):RXDET_BYP_RT_CPU1_P1':
 C_SIGNAL='@t6g_mb_lib.t6g(sch_1):rxdet_byp_rt_cpu1_p1';
NODE_NAME     U6015 E11
 '@T6G_MB_LIB.T6G(SCH_1):PAGE392_I47@PURE_QUANTA.PT5161LRS(CHIPS)':
 'RXDET_BYP': CDS_PINID='RXDET_BYP';
NODE_NAME     R1377 2
 '@T6G_MB_LIB.T6G(SCH_1):PAGE392_I125@PURE_QUANTA.Q_RES(CHIPS)':
 'B': CDS_PINID='B';
NODE_NAME     R1378 1
 '@T6G_MB_LIB.T6G(SCH_1):PAGE392_I126@PURE_QUANTA.Q_RES(CHIPS)':
 'A': CDS_PINID='A';
NET_NAME
'RXDET_BYP_RT_CPU1_P2'
 '@T6G_MB_LIB.T6G(SCH_1):RXDET_BYP_RT_CPU1_P2':
 C_SIGNAL='@t6g_mb_lib.t6g(sch_1):rxdet_byp_rt_cpu1_p2';
NODE_NAME     U6016 E11
 '@T6G_MB_LIB.T6G(SCH_1):PAGE451_I97@PURE_QUANTA.PT5161LRS(CHIPS)':
 'RXDET_BYP': CDS_PINID='RXDET_BYP';
NODE_NAME     R1427 1
 '@T6G_MB_LIB.T6G(SCH_1):PAGE451_I113@PURE_QUANTA.Q_RES(CHIPS)':
 'A': CDS_PINID='A';
NODE_NAME     R1426 2
 '@T6G_MB_LIB.T6G(SCH_1):PAGE451_I114@PURE_QUANTA.Q_RES(CHIPS)':
 'B': CDS_PINID='B';
NET_NAME
'RXDET_BYP_RT_CPU1_P3'
 '@T6G_MB_LIB.T6G(SCH_1):RXDET_BYP_RT_CPU1_P3':
 C_SIGNAL='@t6g_mb_lib.t6g(sch_1):rxdet_byp_rt_cpu1_p3';
NODE_NAME     U6017 E11
 '@T6G_MB_LIB.T6G(SCH_1):PAGE462_I97@PURE_QUANTA.PT5161LRS(CHIPS)':
 'RXDET_BYP': CDS_PINID='RXDET_BYP';
NODE_NAME     R1435 1
 '@T6G_MB_LIB.T6G(SCH_1):PAGE462_I114@PURE_QUANTA.Q_RES(CHIPS)':
 'A': CDS_PINID='A';
NODE_NAME     R1434 2
 '@T6G_MB_LIB.T6G(SCH_1):PAGE462_I115@PURE_QUANTA.Q_RES(CHIPS)':
 'B': CDS_PINID='B';
NET_NAME
'SCM_HDT_DBREQ_N'
 '@T6G_MB_LIB.T6G(SCH_1):SCM_HDT_DBREQ_N':
 C_SIGNAL='@t6g_mb_lib.t6g(sch_1):scm_hdt_dbreq_n';
NODE_NAME     R6032 2
 '@T6G_MB_LIB.T6G(SCH_1):PAGE348_I28@PURE_QUANTA.Q_RES(CHIPS)':
 'B': CDS_PINID='B';
NODE_NAME     J41 A49
 '@T6G_MB_LIB.T6G(SCH_1):PAGE348_I176@PURE_QUANTA.SCONN168_ME1016810202011(CHIPS)':
 'GND_A49': CDS_PINID='GND_A49';
NET_NAME
'SCM_IRQ_1V8_N'
 '@T6G_MB_LIB.T6G(SCH_1):SCM_IRQ_1V8_N':
 C_SIGNAL='@t6g_mb_lib.t6g(sch_1):scm_irq_1v8_n';
NODE_NAME     R174 2
 '@T6G_MB_LIB.T6G(SCH_1):PAGE80_I160@PURE_QUANTA.Q_RES(CHIPS)':
 'B': CDS_PINID='B';
NODE_NAME     R996 2
 '@T6G_MB_LIB.T6G(SCH_1):PAGE83_I22@PURE_QUANTA.Q_RES(CHIPS)':
 'B': CDS_PINID='B';
NODE_NAME     U92 2
 '@T6G_MB_LIB.T6G(SCH_1):PAGE83_I26@PURE_QUANTA.SN74LVC1G07DBVR(CHIPS)':
 'A': CDS_PINID='A';
NET_NAME
'SCM_IRQ_1V8_R_N'
 '@T6G_MB_LIB.T6G(SCH_1):SCM_IRQ_1V8_R_N':
 C_SIGNAL='@t6g_mb_lib.t6g(sch_1):scm_irq_1v8_r_n';
NODE_NAME     R174 1
 '@T6G_MB_LIB.T6G(SCH_1):PAGE80_I160@PURE_QUANTA.Q_RES(CHIPS)':
 'A': CDS_PINID='A';
NODE_NAME     U18 T20
 '@T6G_MB_LIB.T6G(SCH_1):PAGE80_I217@PURE_QUANTA.LCMXO3LF9400C5BG484C(CHIPS)':
 'PR26D': CDS_PINID='PR26D';
NET_NAME
'SCM_IRQ_N'
 '@T6G_MB_LIB.T6G(SCH_1):SCM_IRQ_N':
 C_SIGNAL='@t6g_mb_lib.t6g(sch_1):scm_irq_n';
NODE_NAME     R321 1
 '@T6G_MB_LIB.T6G(SCH_1):PAGE348_I24@PURE_QUANTA.Q_RES(CHIPS)':
 'A': CDS_PINID='A';
NODE_NAME     R71 2
 '@T6G_MB_LIB.T6G(SCH_1):PAGE83_I27@PURE_QUANTA.Q_RES(CHIPS)':
 'B': CDS_PINID='B';
NODE_NAME     R1338 2
 '@T6G_MB_LIB.T6G(SCH_1):PAGE83_I29@PURE_QUANTA.Q_RES(CHIPS)':
 'B': CDS_PINID='B';
NET_NAME
'SCM_IRQ_R_N'
 '@T6G_MB_LIB.T6G(SCH_1):SCM_IRQ_R_N':
 C_SIGNAL='@t6g_mb_lib.t6g(sch_1):scm_irq_r_n';
NODE_NAME     U92 4
 '@T6G_MB_LIB.T6G(SCH_1):PAGE83_I26@PURE_QUANTA.SN74LVC1G07DBVR(CHIPS)':
 'Y': CDS_PINID='Y';
NODE_NAME     R71 1
 '@T6G_MB_LIB.T6G(SCH_1):PAGE83_I27@PURE_QUANTA.Q_RES(CHIPS)':
 'A': CDS_PINID='A';
NET_NAME
'SCM_JTAG_MUX_R_S0'
 '@T6G_MB_LIB.T6G(SCH_1):SCM_JTAG_MUX_R_S0':
 C_SIGNAL='@t6g_mb_lib.t6g(sch_1):scm_jtag_mux_r_s0';
NODE_NAME     R49 1
 '@T6G_MB_LIB.T6G(SCH_1):PAGE79_I46@PURE_QUANTA.Q_RES(CHIPS)':
 'A': CDS_PINID='A';
NODE_NAME     U18 B3
 '@T6G_MB_LIB.T6G(SCH_1):PAGE79_I94@PURE_QUANTA.LCMXO3LF9400C5BG484C(CHIPS)':
 'PT11A': CDS_PINID='PT11A';
NET_NAME
'SCM_JTAG_MUX_R_S1'
 '@T6G_MB_LIB.T6G(SCH_1):SCM_JTAG_MUX_R_S1':
 C_SIGNAL='@t6g_mb_lib.t6g(sch_1):scm_jtag_mux_r_s1';
NODE_NAME     R50 1
 '@T6G_MB_LIB.T6G(SCH_1):PAGE79_I49@PURE_QUANTA.Q_RES(CHIPS)':
 'A': CDS_PINID='A';
NODE_NAME     U18 A3
 '@T6G_MB_LIB.T6G(SCH_1):PAGE79_I94@PURE_QUANTA.LCMXO3LF9400C5BG484C(CHIPS)':
 'PT10B': CDS_PINID='PT10B';
NET_NAME
'SCM_JTAG_MUX_S0'
 '@T6G_MB_LIB.T6G(SCH_1):SCM_JTAG_MUX_S0':
 C_SIGNAL='@t6g_mb_lib.t6g(sch_1):scm_jtag_mux_s0';
NODE_NAME     R1659 2
 '@T6G_MB_LIB.T6G(SCH_1):PAGE148_I309@PURE_QUANTA.Q_RES(CHIPS)':
 'B': CDS_PINID='B';
NODE_NAME     R1658 1
 '@T6G_MB_LIB.T6G(SCH_1):PAGE148_I310@PURE_QUANTA.Q_RES(CHIPS)':
 'A': CDS_PINID='A';
NODE_NAME     R49 2
 '@T6G_MB_LIB.T6G(SCH_1):PAGE79_I46@PURE_QUANTA.Q_RES(CHIPS)':
 'B': CDS_PINID='B';
NODE_NAME     R6101 1
 '@T6G_MB_LIB.T6G(SCH_1):PAGE148_I375@PURE_QUANTA.Q_RES(CHIPS)':
 'A': CDS_PINID='A';
NODE_NAME     R6102 1
 '@T6G_MB_LIB.T6G(SCH_1):PAGE148_I376@PURE_QUANTA.Q_RES(CHIPS)':
 'A': CDS_PINID='A';
NET_NAME
'SCM_JTAG_MUX_S0_R1'
 '@T6G_MB_LIB.T6G(SCH_1):SCM_JTAG_MUX_S0_R1':
 C_SIGNAL='@t6g_mb_lib.t6g(sch_1):scm_jtag_mux_s0_r1';
NODE_NAME     U160 10
 '@T6G_MB_LIB.T6G(SCH_1):PAGE148_I266@PURE_QUANTA.74LV4052PW(CHIPS)':
 'S0': CDS_PINID='S0';
NODE_NAME     R6101 2
 '@T6G_MB_LIB.T6G(SCH_1):PAGE148_I375@PURE_QUANTA.Q_RES(CHIPS)':
 'B': CDS_PINID='B';
NET_NAME
'SCM_JTAG_MUX_S0_R2'
 '@T6G_MB_LIB.T6G(SCH_1):SCM_JTAG_MUX_S0_R2':
 C_SIGNAL='@t6g_mb_lib.t6g(sch_1):scm_jtag_mux_s0_r2';
NODE_NAME     U212 10
 '@T6G_MB_LIB.T6G(SCH_1):PAGE148_I302@PURE_QUANTA.74LV4052PW(CHIPS)':
 'S0': CDS_PINID='S0';
NODE_NAME     R6102 2
 '@T6G_MB_LIB.T6G(SCH_1):PAGE148_I376@PURE_QUANTA.Q_RES(CHIPS)':
 'B': CDS_PINID='B';
NET_NAME
'SCM_JTAG_MUX_S1'
 '@T6G_MB_LIB.T6G(SCH_1):SCM_JTAG_MUX_S1':
 C_SIGNAL='@t6g_mb_lib.t6g(sch_1):scm_jtag_mux_s1';
NODE_NAME     U160 9
 '@T6G_MB_LIB.T6G(SCH_1):PAGE148_I266@PURE_QUANTA.74LV4052PW(CHIPS)':
 'S1': CDS_PINID='S1';
NODE_NAME     U212 9
 '@T6G_MB_LIB.T6G(SCH_1):PAGE148_I302@PURE_QUANTA.74LV4052PW(CHIPS)':
 'S1': CDS_PINID='S1';
NODE_NAME     R1730 2
 '@T6G_MB_LIB.T6G(SCH_1):PAGE148_I305@PURE_QUANTA.Q_RES(CHIPS)':
 'B': CDS_PINID='B';
NODE_NAME     R1729 1
 '@T6G_MB_LIB.T6G(SCH_1):PAGE148_I306@PURE_QUANTA.Q_RES(CHIPS)':
 'A': CDS_PINID='A';
NODE_NAME     R1343 2
 '@T6G_MB_LIB.T6G(SCH_1):PAGE148_I339@PURE_QUANTA.Q_RES(CHIPS)':
 'B': CDS_PINID='B';
NODE_NAME     U99 4
 '@T6G_MB_LIB.T6G(SCH_1):PAGE148_I340@PURE_QUANTA.SN74LVC1G07DBVR(CHIPS)':
 'Y': CDS_PINID='Y';
NODE_NAME     R50 2
 '@T6G_MB_LIB.T6G(SCH_1):PAGE79_I49@PURE_QUANTA.Q_RES(CHIPS)':
 'B': CDS_PINID='B';
NET_NAME
'SCM_ROT_CPU_RST_N'
 '@T6G_MB_LIB.T6G(SCH_1):SCM_ROT_CPU_RST_N':
 C_SIGNAL='@t6g_mb_lib.t6g(sch_1):scm_rot_cpu_rst_n';
NODE_NAME     R1798 2
 '@T6G_MB_LIB.T6G(SCH_1):PAGE348_I26@PURE_QUANTA.Q_RES(CHIPS)':
 'B': CDS_PINID='B';
NODE_NAME     J41 A53
 '@T6G_MB_LIB.T6G(SCH_1):PAGE348_I176@PURE_QUANTA.SCONN168_ME1016810202011(CHIPS)':
 'PERN11': CDS_PINID='PERN11';
NET_NAME
'SCM_ROT_CPU_RST_R_N'
 '@T6G_MB_LIB.T6G(SCH_1):SCM_ROT_CPU_RST_R_N':
 C_SIGNAL='@t6g_mb_lib.t6g(sch_1):scm_rot_cpu_rst_r_n';
NODE_NAME     R6035 1
 '@T6G_MB_LIB.T6G(SCH_1):PAGE348_I17@PURE_QUANTA.Q_RES(CHIPS)':
 'A': CDS_PINID='A';
NODE_NAME     R6034 2
 '@T6G_MB_LIB.T6G(SCH_1):PAGE348_I18@PURE_QUANTA.Q_RES(CHIPS)':
 'B': CDS_PINID='B';
NODE_NAME     R1798 1
 '@T6G_MB_LIB.T6G(SCH_1):PAGE348_I26@PURE_QUANTA.Q_RES(CHIPS)':
 'A': CDS_PINID='A';
NODE_NAME     U18 C13
 '@T6G_MB_LIB.T6G(SCH_1):PAGE79_I94@PURE_QUANTA.LCMXO3LF9400C5BG484C(CHIPS)':
 'PT29C': CDS_PINID='PT29C';
NET_NAME
'SCM_SPARE_0'
 '@T6G_MB_LIB.T6G(SCH_1):SCM_SPARE_0':
 C_SIGNAL='@t6g_mb_lib.t6g(sch_1):scm_spare_0';
NODE_NAME     R888 2
 '@T6G_MB_LIB.T6G(SCH_1):PAGE349_I145@PURE_QUANTA.Q_RES(CHIPS)':
 'B': CDS_PINID='B';
NODE_NAME     U18 G14
 '@T6G_MB_LIB.T6G(SCH_1):PAGE79_I94@PURE_QUANTA.LCMXO3LF9400C5BG484C(CHIPS)':
 'PT31A': CDS_PINID='PT31A';
NODE_NAME     R889 1
 '@T6G_MB_LIB.T6G(SCH_1):PAGE349_I142@PURE_QUANTA.Q_RES(CHIPS)':
 'A': CDS_PINID='A';
NET_NAME
'SCM_SPARE_1'
 '@T6G_MB_LIB.T6G(SCH_1):SCM_SPARE_1':
 C_SIGNAL='@t6g_mb_lib.t6g(sch_1):scm_spare_1';
NODE_NAME     R890 2
 '@T6G_MB_LIB.T6G(SCH_1):PAGE349_I147@PURE_QUANTA.Q_RES(CHIPS)':
 'B': CDS_PINID='B';
NODE_NAME     U18 F14
 '@T6G_MB_LIB.T6G(SCH_1):PAGE79_I94@PURE_QUANTA.LCMXO3LF9400C5BG484C(CHIPS)':
 'PT31B': CDS_PINID='PT31B';
NODE_NAME     R891 1
 '@T6G_MB_LIB.T6G(SCH_1):PAGE349_I144@PURE_QUANTA.Q_RES(CHIPS)':
 'A': CDS_PINID='A';
NET_NAME
'SCM_SYS_PWRBTN_N'
 '@T6G_MB_LIB.T6G(SCH_1):SCM_SYS_PWRBTN_N':
 C_SIGNAL='@t6g_mb_lib.t6g(sch_1):scm_sys_pwrbtn_n';
NODE_NAME     R1815 1
 '@T6G_MB_LIB.T6G(SCH_1):PAGE348_I29@PURE_QUANTA.Q_RES(CHIPS)':
 'A': CDS_PINID='A';
NODE_NAME     U18 E12
 '@T6G_MB_LIB.T6G(SCH_1):PAGE79_I94@PURE_QUANTA.LCMXO3LF9400C5BG484C(CHIPS)':
 'PT27B': CDS_PINID='PT27B';
NODE_NAME     R64 1
 '@T6G_MB_LIB.T6G(SCH_1):PAGE82_I166@PURE_QUANTA.Q_RES(CHIPS)':
 'A': CDS_PINID='A';
NET_NAME
'SCM_SYS_PWRBTN_R_N'
 '@T6G_MB_LIB.T6G(SCH_1):SCM_SYS_PWRBTN_R_N':
 C_SIGNAL='@t6g_mb_lib.t6g(sch_1):scm_sys_pwrbtn_r_n';
NODE_NAME     R1815 2
 '@T6G_MB_LIB.T6G(SCH_1):PAGE348_I29@PURE_QUANTA.Q_RES(CHIPS)':
 'B': CDS_PINID='B';
NODE_NAME     J41 A47
 '@T6G_MB_LIB.T6G(SCH_1):PAGE348_I176@PURE_QUANTA.SCONN168_ME1016810202011(CHIPS)':
 'PERN9': CDS_PINID='PERN9';
NET_NAME
'SCM_SYS_PWROK'
 '@T6G_MB_LIB.T6G(SCH_1):SCM_SYS_PWROK':
 C_SIGNAL='@t6g_mb_lib.t6g(sch_1):scm_sys_pwrok';
NODE_NAME     R63 2
 '@T6G_MB_LIB.T6G(SCH_1):PAGE79_I79@PURE_QUANTA.Q_RES(CHIPS)':
 'B': CDS_PINID='B';
NODE_NAME     U18 A15
 '@T6G_MB_LIB.T6G(SCH_1):PAGE79_I94@PURE_QUANTA.LCMXO3LF9400C5BG484C(CHIPS)':
 'PT38A': CDS_PINID='PT38A';
NET_NAME
'SCM_SYS_PWROK_R'
 '@T6G_MB_LIB.T6G(SCH_1):SCM_SYS_PWROK_R':
 C_SIGNAL='@t6g_mb_lib.t6g(sch_1):scm_sys_pwrok_r';
NODE_NAME     R63 1
 '@T6G_MB_LIB.T6G(SCH_1):PAGE79_I79@PURE_QUANTA.Q_RES(CHIPS)':
 'A': CDS_PINID='A';
NODE_NAME     R6092 1
 '@T6G_MB_LIB.T6G(SCH_1):PAGE84_I82@PURE_QUANTA.Q_RES(CHIPS)':
 'A': CDS_PINID='A';
NODE_NAME     R6093 1
 '@T6G_MB_LIB.T6G(SCH_1):PAGE84_I84@PURE_QUANTA.Q_RES(CHIPS)':
 'A': CDS_PINID='A';
NET_NAME
'SCM_SYS_PWROK_R1'
 '@T6G_MB_LIB.T6G(SCH_1):SCM_SYS_PWROK_R1':
 C_SIGNAL='@t6g_mb_lib.t6g(sch_1):scm_sys_pwrok_r1';
NODE_NAME     J41 A48
 '@T6G_MB_LIB.T6G(SCH_1):PAGE348_I176@PURE_QUANTA.SCONN168_ME1016810202011(CHIPS)':
 'PERP9': CDS_PINID='PERP9';
NODE_NAME     R6092 2
 '@T6G_MB_LIB.T6G(SCH_1):PAGE84_I82@PURE_QUANTA.Q_RES(CHIPS)':
 'B': CDS_PINID='B';
NET_NAME
'SCM_SYS_PWROK_R2'
 '@T6G_MB_LIB.T6G(SCH_1):SCM_SYS_PWROK_R2':
 C_SIGNAL='@t6g_mb_lib.t6g(sch_1):scm_sys_pwrok_r2';
NODE_NAME     R6093 2
 '@T6G_MB_LIB.T6G(SCH_1):PAGE84_I84@PURE_QUANTA.Q_RES(CHIPS)':
 'B': CDS_PINID='B';
NODE_NAME     Q87 5
 '@T6G_MB_LIB.T6G(SCH_1):PAGE254_I35@PURE_QUANTA.MOSFET_NCH_DUAL(CHIPS)':
 'G2': CDS_PINID='G2';
NODE_NAME     C1209 1
 '@T6G_MB_LIB.T6G(SCH_1):PAGE84_I88@PURE_QUANTA.Q_CAP(CHIPS)':
 'A': CDS_PINID='A';
NET_NAME
'SCM_USB_OC_BUF_N'
 '@T6G_MB_LIB.T6G(SCH_1):SCM_USB_OC_BUF_N':
 C_SIGNAL='@t6g_mb_lib.t6g(sch_1):scm_usb_oc_buf_n';
NODE_NAME     U25 E23
 '@T6G_MB_LIB.T6G(SCH_1):PAGE29_I287@PURE_QUANTA.GENOA_SP5(CHIPS)':
 'USB00_OC_L||AGPIO264': CDS_PINID='\usb00_oc_l||agpio264\';
NODE_NAME     R589 2
 '@T6G_MB_LIB.T6G(SCH_1):PAGE29_I377@PURE_QUANTA.Q_RES(CHIPS)':
 'B': CDS_PINID='B';
NODE_NAME     R454 2
 '@T6G_MB_LIB.T6G(SCH_1):PAGE29_I383@PURE_QUANTA.Q_RES(CHIPS)':
 'B': CDS_PINID='B';
NET_NAME
'SCM_USB_OC_BU_R_N'
 '@T6G_MB_LIB.T6G(SCH_1):SCM_USB_OC_BU_R_N':
 C_SIGNAL='@t6g_mb_lib.t6g(sch_1):scm_usb_oc_bu_r_n';
NODE_NAME     U3 4
 '@T6G_MB_LIB.T6G(SCH_1):PAGE29_I373@PURE_QUANTA.SN74LVC1G07DBVR(CHIPS)':
 'Y': CDS_PINID='Y';
NODE_NAME     R589 1
 '@T6G_MB_LIB.T6G(SCH_1):PAGE29_I377@PURE_QUANTA.Q_RES(CHIPS)':
 'A': CDS_PINID='A';
NET_NAME
'SCM_USB_OC_N'
 '@T6G_MB_LIB.T6G(SCH_1):SCM_USB_OC_N':
 C_SIGNAL='@t6g_mb_lib.t6g(sch_1):scm_usb_oc_n';
NODE_NAME     U3 2
 '@T6G_MB_LIB.T6G(SCH_1):PAGE29_I373@PURE_QUANTA.SN74LVC1G07DBVR(CHIPS)':
 'A': CDS_PINID='A';
NODE_NAME     R588 2
 '@T6G_MB_LIB.T6G(SCH_1):PAGE80_I164@PURE_QUANTA.Q_RES(CHIPS)':
 'B': CDS_PINID='B';
NODE_NAME     R654 1
 '@T6G_MB_LIB.T6G(SCH_1):PAGE82_I64@PURE_QUANTA.Q_RES(CHIPS)':
 'A': CDS_PINID='A';
NET_NAME
'SCM_USB_OC_R_N'
 '@T6G_MB_LIB.T6G(SCH_1):SCM_USB_OC_R_N':
 C_SIGNAL='@t6g_mb_lib.t6g(sch_1):scm_usb_oc_r_n';
NODE_NAME     R588 1
 '@T6G_MB_LIB.T6G(SCH_1):PAGE80_I164@PURE_QUANTA.Q_RES(CHIPS)':
 'A': CDS_PINID='A';
NODE_NAME     U18 R19
 '@T6G_MB_LIB.T6G(SCH_1):PAGE80_I217@PURE_QUANTA.LCMXO3LF9400C5BG484C(CHIPS)':
 'PR25D': CDS_PINID='PR25D';
NET_NAME
'SCM_VDD_RTC'
 '@T6G_MB_LIB.T6G(SCH_1):SCM_VDD_RTC':
 C_SIGNAL='@t6g_mb_lib.t6g(sch_1):scm_vdd_rtc',
 CDS_GLOBAL_NET='TRUE';
NODE_NAME     J41 B41
 '@T6G_MB_LIB.T6G(SCH_1):PAGE348_I176@PURE_QUANTA.SCONN168_ME1016810202011(CHIPS)':
 'GND_B41': CDS_PINID='GND_B41';
NODE_NAME     R364 2
 '@T6G_MB_LIB.T6G(SCH_1):PAGE349_I231@PURE_QUANTA.Q_RES(CHIPS)':
 'B': CDS_PINID='B';
NODE_NAME     C6000 1
 '@T6G_MB_LIB.T6G(SCH_1):PAGE348_I219@PURE_QUANTA.Q_CAP(CHIPS)':
 'A': CDS_PINID='A';
NET_NAME
'SGPIO_OCP_SFF_CLK'
 '@T6G_MB_LIB.T6G(SCH_1):SGPIO_OCP_SFF_CLK':
 C_SIGNAL='@t6g_mb_lib.t6g(sch_1):sgpio_ocp_sff_clk';
NODE_NAME     J38 OB6
 '@T6G_MB_LIB.T6G(SCH_1):PAGE335_I168@PURE_QUANTA.SCONN168_ME1016810202011(CHIPS)':
 'CLK': CDS_PINID='CLK';
NODE_NAME     R8423 1
 '@T6G_MB_LIB.T6G(SCH_1):PAGE335_I20@PURE_QUANTA.Q_RES(CHIPS)':
 'A': CDS_PINID='A';
NODE_NAME     U18 C9
 '@T6G_MB_LIB.T6G(SCH_1):PAGE79_I94@PURE_QUANTA.LCMXO3LF9400C5BG484C(CHIPS)':
 'PT20C': CDS_PINID='PT20C';
NET_NAME
'SGPIO_OCP_SFF_DATAIN'
 '@T6G_MB_LIB.T6G(SCH_1):SGPIO_OCP_SFF_DATAIN':
 C_SIGNAL='@t6g_mb_lib.t6g(sch_1):sgpio_ocp_sff_datain';
NODE_NAME     J38 OB4
 '@T6G_MB_LIB.T6G(SCH_1):PAGE335_I168@PURE_QUANTA.SCONN168_ME1016810202011(CHIPS)':
 'DATA_IN': CDS_PINID='DATA_IN';
NODE_NAME     R8421 1
 '@T6G_MB_LIB.T6G(SCH_1):PAGE335_I21@PURE_QUANTA.Q_RES(CHIPS)':
 'A': CDS_PINID='A';
NODE_NAME     U18 B8
 '@T6G_MB_LIB.T6G(SCH_1):PAGE79_I94@PURE_QUANTA.LCMXO3LF9400C5BG484C(CHIPS)':
 'PT20A': CDS_PINID='PT20A';
NET_NAME
'SGPIO_OCP_SFF_DATAOUT'
 '@T6G_MB_LIB.T6G(SCH_1):SGPIO_OCP_SFF_DATAOUT':
 C_SIGNAL='@t6g_mb_lib.t6g(sch_1):sgpio_ocp_sff_dataout';
NODE_NAME     J38 OB5
 '@T6G_MB_LIB.T6G(SCH_1):PAGE335_I168@PURE_QUANTA.SCONN168_ME1016810202011(CHIPS)':
 'DATA_OUT': CDS_PINID='DATA_OUT';
NODE_NAME     R8422 1
 '@T6G_MB_LIB.T6G(SCH_1):PAGE335_I19@PURE_QUANTA.Q_RES(CHIPS)':
 'A': CDS_PINID='A';
NODE_NAME     U18 A8
 '@T6G_MB_LIB.T6G(SCH_1):PAGE79_I94@PURE_QUANTA.LCMXO3LF9400C5BG484C(CHIPS)':
 'PT20B': CDS_PINID='PT20B';
NET_NAME
'SGPIO_OCP_SFF_LD_N'
 '@T6G_MB_LIB.T6G(SCH_1):SGPIO_OCP_SFF_LD_N':
 C_SIGNAL='@t6g_mb_lib.t6g(sch_1):sgpio_ocp_sff_ld_n';
NODE_NAME     J38 OB3
 '@T6G_MB_LIB.T6G(SCH_1):PAGE335_I168@PURE_QUANTA.SCONN168_ME1016810202011(CHIPS)':
 'LD#': CDS_PINID='\ld#\';
NODE_NAME     R8420 1
 '@T6G_MB_LIB.T6G(SCH_1):PAGE335_I22@PURE_QUANTA.Q_RES(CHIPS)':
 'A': CDS_PINID='A';
NODE_NAME     U18 D8
 '@T6G_MB_LIB.T6G(SCH_1):PAGE79_I94@PURE_QUANTA.LCMXO3LF9400C5BG484C(CHIPS)':
 'PT15B': CDS_PINID='PT15B';
NET_NAME
'SGPIO_OCP_V3_2_CLK'
 '@T6G_MB_LIB.T6G(SCH_1):SGPIO_OCP_V3_2_CLK':
 C_SIGNAL='@t6g_mb_lib.t6g(sch_1):sgpio_ocp_v3_2_clk';
NODE_NAME     J35 OB6
 '@T6G_MB_LIB.T6G(SCH_1):PAGE341_I168@PURE_QUANTA.SCONN168_ME1016810202011(CHIPS)':
 'CLK': CDS_PINID='CLK';
NODE_NAME     R3176 1
 '@T6G_MB_LIB.T6G(SCH_1):PAGE341_I12@PURE_QUANTA.Q_RES(CHIPS)':
 'A': CDS_PINID='A';
NODE_NAME     U18 D14
 '@T6G_MB_LIB.T6G(SCH_1):PAGE79_I94@PURE_QUANTA.LCMXO3LF9400C5BG484C(CHIPS)':
 'PT30D': CDS_PINID='PT30D';
NET_NAME
'SGPIO_OCP_V3_2_DATAIN'
 '@T6G_MB_LIB.T6G(SCH_1):SGPIO_OCP_V3_2_DATAIN':
 C_SIGNAL='@t6g_mb_lib.t6g(sch_1):sgpio_ocp_v3_2_datain';
NODE_NAME     J35 OB4
 '@T6G_MB_LIB.T6G(SCH_1):PAGE341_I168@PURE_QUANTA.SCONN168_ME1016810202011(CHIPS)':
 'DATA_IN': CDS_PINID='DATA_IN';
NODE_NAME     R3174 1
 '@T6G_MB_LIB.T6G(SCH_1):PAGE341_I9@PURE_QUANTA.Q_RES(CHIPS)':
 'A': CDS_PINID='A';
NODE_NAME     U18 B14
 '@T6G_MB_LIB.T6G(SCH_1):PAGE79_I94@PURE_QUANTA.LCMXO3LF9400C5BG484C(CHIPS)':
 'PT30B': CDS_PINID='PT30B';
NET_NAME
'SGPIO_OCP_V3_2_DATAOUT'
 '@T6G_MB_LIB.T6G(SCH_1):SGPIO_OCP_V3_2_DATAOUT':
 C_SIGNAL='@t6g_mb_lib.t6g(sch_1):sgpio_ocp_v3_2_dataout';
NODE_NAME     J35 OB5
 '@T6G_MB_LIB.T6G(SCH_1):PAGE341_I168@PURE_QUANTA.SCONN168_ME1016810202011(CHIPS)':
 'DATA_OUT': CDS_PINID='DATA_OUT';
NODE_NAME     R3175 1
 '@T6G_MB_LIB.T6G(SCH_1):PAGE341_I11@PURE_QUANTA.Q_RES(CHIPS)':
 'A': CDS_PINID='A';
NODE_NAME     U18 C14
 '@T6G_MB_LIB.T6G(SCH_1):PAGE79_I94@PURE_QUANTA.LCMXO3LF9400C5BG484C(CHIPS)':
 'PT30C': CDS_PINID='PT30C';
NET_NAME
'SGPIO_OCP_V3_2_LD_N'
 '@T6G_MB_LIB.T6G(SCH_1):SGPIO_OCP_V3_2_LD_N':
 C_SIGNAL='@t6g_mb_lib.t6g(sch_1):sgpio_ocp_v3_2_ld_n';
NODE_NAME     J35 OB3
 '@T6G_MB_LIB.T6G(SCH_1):PAGE341_I168@PURE_QUANTA.SCONN168_ME1016810202011(CHIPS)':
 'LD#': CDS_PINID='\ld#\';
NODE_NAME     R3173 1
 '@T6G_MB_LIB.T6G(SCH_1):PAGE341_I10@PURE_QUANTA.Q_RES(CHIPS)':
 'A': CDS_PINID='A';
NODE_NAME     U18 A14
 '@T6G_MB_LIB.T6G(SCH_1):PAGE79_I94@PURE_QUANTA.LCMXO3LF9400C5BG484C(CHIPS)':
 'PT30A': CDS_PINID='PT30A';
NET_NAME
'SGPIO_SCM_CLK_<0>'
 '@T6G_MB_LIB.T6G(SCH_1):SGPIO_SCM_CLK_'<0>:
 C_SIGNAL='@t6g_mb_lib.t6g(sch_1):\sgpio_scm_clk_\(0)';
NODE_NAME     R6017 2
 '@T6G_MB_LIB.T6G(SCH_1):PAGE349_I28@PURE_QUANTA.Q_RES(CHIPS)':
 'B': CDS_PINID='B';
NODE_NAME     U18 D6
 '@T6G_MB_LIB.T6G(SCH_1):PAGE79_I94@PURE_QUANTA.LCMXO3LF9400C5BG484C(CHIPS)':
 'PT13C': CDS_PINID='PT13C';
NODE_NAME     R6009 1
 '@T6G_MB_LIB.T6G(SCH_1):PAGE348_I134@PURE_QUANTA.Q_RES(CHIPS)':
 'A': CDS_PINID='A';
NET_NAME
'SGPIO_SCM_CLK_<1>'
 '@T6G_MB_LIB.T6G(SCH_1):SGPIO_SCM_CLK_'<1>:
 C_SIGNAL='@t6g_mb_lib.t6g(sch_1):\sgpio_scm_clk_\(1)';
NODE_NAME     R6013 1
 '@T6G_MB_LIB.T6G(SCH_1):PAGE348_I130@PURE_QUANTA.Q_RES(CHIPS)':
 'A': CDS_PINID='A';
NODE_NAME     U18 D18
 '@T6G_MB_LIB.T6G(SCH_1):PAGE79_I94@PURE_QUANTA.LCMXO3LF9400C5BG484C(CHIPS)':
 'PT41D': CDS_PINID='PT41D';
NODE_NAME     R6021 2
 '@T6G_MB_LIB.T6G(SCH_1):PAGE349_I22@PURE_QUANTA.Q_RES(CHIPS)':
 'B': CDS_PINID='B';
NET_NAME
'SGPIO_SCM_CLK_R_<0>'
 '@T6G_MB_LIB.T6G(SCH_1):SGPIO_SCM_CLK_R_'<0>:
 C_SIGNAL='@t6g_mb_lib.t6g(sch_1):\sgpio_scm_clk_r_\(0)';
NODE_NAME     J41 B30
 '@T6G_MB_LIB.T6G(SCH_1):PAGE348_I176@PURE_QUANTA.SCONN168_ME1016810202011(CHIPS)':
 'PETN4': CDS_PINID='PETN4';
NODE_NAME     R6009 2
 '@T6G_MB_LIB.T6G(SCH_1):PAGE348_I134@PURE_QUANTA.Q_RES(CHIPS)':
 'B': CDS_PINID='B';
NET_NAME
'SGPIO_SCM_CLK_R_<1>'
 '@T6G_MB_LIB.T6G(SCH_1):SGPIO_SCM_CLK_R_'<1>:
 C_SIGNAL='@t6g_mb_lib.t6g(sch_1):\sgpio_scm_clk_r_\(1)';
NODE_NAME     R6013 2
 '@T6G_MB_LIB.T6G(SCH_1):PAGE348_I130@PURE_QUANTA.Q_RES(CHIPS)':
 'B': CDS_PINID='B';
NODE_NAME     J41 B35
 '@T6G_MB_LIB.T6G(SCH_1):PAGE348_I176@PURE_QUANTA.SCONN168_ME1016810202011(CHIPS)':
 'GND_B35': CDS_PINID='GND_B35';
NET_NAME
'SGPIO_SCM_DI_<0>'
 '@T6G_MB_LIB.T6G(SCH_1):SGPIO_SCM_DI_'<0>:
 C_SIGNAL='@t6g_mb_lib.t6g(sch_1):\sgpio_scm_di_\(0)';
NODE_NAME     R167 2
 '@T6G_MB_LIB.T6G(SCH_1):PAGE79_I45@PURE_QUANTA.Q_RES(CHIPS)':
 'B': CDS_PINID='B';
NODE_NAME     R6010 1
 '@T6G_MB_LIB.T6G(SCH_1):PAGE348_I133@PURE_QUANTA.Q_RES(CHIPS)':
 'A': CDS_PINID='A';
NODE_NAME     R6018 2
 '@T6G_MB_LIB.T6G(SCH_1):PAGE349_I27@PURE_QUANTA.Q_RES(CHIPS)':
 'B': CDS_PINID='B';
NET_NAME
'SGPIO_SCM_DI_<1>'
 '@T6G_MB_LIB.T6G(SCH_1):SGPIO_SCM_DI_'<1>:
 C_SIGNAL='@t6g_mb_lib.t6g(sch_1):\sgpio_scm_di_\(1)';
NODE_NAME     R6014 1
 '@T6G_MB_LIB.T6G(SCH_1):PAGE348_I128@PURE_QUANTA.Q_RES(CHIPS)':
 'A': CDS_PINID='A';
NODE_NAME     R168 2
 '@T6G_MB_LIB.T6G(SCH_1):PAGE79_I24@PURE_QUANTA.Q_RES(CHIPS)':
 'B': CDS_PINID='B';
NODE_NAME     R6022 2
 '@T6G_MB_LIB.T6G(SCH_1):PAGE349_I23@PURE_QUANTA.Q_RES(CHIPS)':
 'B': CDS_PINID='B';
NET_NAME
'SGPIO_SCM_DI_R<0>'
 '@T6G_MB_LIB.T6G(SCH_1):SGPIO_SCM_DI_R'<0>:
 C_SIGNAL='@t6g_mb_lib.t6g(sch_1):sgpio_scm_di_r(0)';
NODE_NAME     R167 1
 '@T6G_MB_LIB.T6G(SCH_1):PAGE79_I45@PURE_QUANTA.Q_RES(CHIPS)':
 'A': CDS_PINID='A';
NODE_NAME     U18 A4
 '@T6G_MB_LIB.T6G(SCH_1):PAGE79_I94@PURE_QUANTA.LCMXO3LF9400C5BG484C(CHIPS)':
 'PT11B': CDS_PINID='PT11B';
NET_NAME
'SGPIO_SCM_DI_R<1>'
 '@T6G_MB_LIB.T6G(SCH_1):SGPIO_SCM_DI_R'<1>:
 C_SIGNAL='@t6g_mb_lib.t6g(sch_1):sgpio_scm_di_r(1)';
NODE_NAME     R168 1
 '@T6G_MB_LIB.T6G(SCH_1):PAGE79_I24@PURE_QUANTA.Q_RES(CHIPS)':
 'A': CDS_PINID='A';
NODE_NAME     U18 C6
 '@T6G_MB_LIB.T6G(SCH_1):PAGE79_I94@PURE_QUANTA.LCMXO3LF9400C5BG484C(CHIPS)':
 'PT14C': CDS_PINID='PT14C';
NET_NAME
'SGPIO_SCM_DI_R_<0>'
 '@T6G_MB_LIB.T6G(SCH_1):SGPIO_SCM_DI_R_'<0>:
 C_SIGNAL='@t6g_mb_lib.t6g(sch_1):\sgpio_scm_di_r_\(0)';
NODE_NAME     J41 B31
 '@T6G_MB_LIB.T6G(SCH_1):PAGE348_I176@PURE_QUANTA.SCONN168_ME1016810202011(CHIPS)':
 'PETP4': CDS_PINID='PETP4';
NODE_NAME     R6010 2
 '@T6G_MB_LIB.T6G(SCH_1):PAGE348_I133@PURE_QUANTA.Q_RES(CHIPS)':
 'B': CDS_PINID='B';
NET_NAME
'SGPIO_SCM_DI_R_<1>'
 '@T6G_MB_LIB.T6G(SCH_1):SGPIO_SCM_DI_R_'<1>:
 C_SIGNAL='@t6g_mb_lib.t6g(sch_1):\sgpio_scm_di_r_\(1)';
NODE_NAME     R6014 2
 '@T6G_MB_LIB.T6G(SCH_1):PAGE348_I128@PURE_QUANTA.Q_RES(CHIPS)':
 'B': CDS_PINID='B';
NODE_NAME     J41 B36
 '@T6G_MB_LIB.T6G(SCH_1):PAGE348_I176@PURE_QUANTA.SCONN168_ME1016810202011(CHIPS)':
 'PETN6': CDS_PINID='PETN6';
NET_NAME
'SGPIO_SCM_DO_<0>'
 '@T6G_MB_LIB.T6G(SCH_1):SGPIO_SCM_DO_'<0>:
 C_SIGNAL='@t6g_mb_lib.t6g(sch_1):\sgpio_scm_do_\(0)';
NODE_NAME     R6016 2
 '@T6G_MB_LIB.T6G(SCH_1):PAGE349_I29@PURE_QUANTA.Q_RES(CHIPS)':
 'B': CDS_PINID='B';
NODE_NAME     U18 E7
 '@T6G_MB_LIB.T6G(SCH_1):PAGE79_I94@PURE_QUANTA.LCMXO3LF9400C5BG484C(CHIPS)':
 'PT13D': CDS_PINID='PT13D';
NODE_NAME     R6008 1
 '@T6G_MB_LIB.T6G(SCH_1):PAGE348_I135@PURE_QUANTA.Q_RES(CHIPS)':
 'A': CDS_PINID='A';
NET_NAME
'SGPIO_SCM_DO_<1>'
 '@T6G_MB_LIB.T6G(SCH_1):SGPIO_SCM_DO_'<1>:
 C_SIGNAL='@t6g_mb_lib.t6g(sch_1):\sgpio_scm_do_\(1)';
NODE_NAME     U18 B4
 '@T6G_MB_LIB.T6G(SCH_1):PAGE79_I94@PURE_QUANTA.LCMXO3LF9400C5BG484C(CHIPS)':
 'PT12A': CDS_PINID='PT12A';
NODE_NAME     R6012 1
 '@T6G_MB_LIB.T6G(SCH_1):PAGE348_I131@PURE_QUANTA.Q_RES(CHIPS)':
 'A': CDS_PINID='A';
NODE_NAME     R6020 2
 '@T6G_MB_LIB.T6G(SCH_1):PAGE349_I24@PURE_QUANTA.Q_RES(CHIPS)':
 'B': CDS_PINID='B';
NET_NAME
'SGPIO_SCM_DO_R_<0>'
 '@T6G_MB_LIB.T6G(SCH_1):SGPIO_SCM_DO_R_'<0>:
 C_SIGNAL='@t6g_mb_lib.t6g(sch_1):\sgpio_scm_do_r_\(0)';
NODE_NAME     J41 B29
 '@T6G_MB_LIB.T6G(SCH_1):PAGE348_I176@PURE_QUANTA.SCONN168_ME1016810202011(CHIPS)':
 'GND_B29': CDS_PINID='GND_B29';
NODE_NAME     R6008 2
 '@T6G_MB_LIB.T6G(SCH_1):PAGE348_I135@PURE_QUANTA.Q_RES(CHIPS)':
 'B': CDS_PINID='B';
NET_NAME
'SGPIO_SCM_DO_R_<1>'
 '@T6G_MB_LIB.T6G(SCH_1):SGPIO_SCM_DO_R_'<1>:
 C_SIGNAL='@t6g_mb_lib.t6g(sch_1):\sgpio_scm_do_r_\(1)';
NODE_NAME     J41 B34
 '@T6G_MB_LIB.T6G(SCH_1):PAGE348_I176@PURE_QUANTA.SCONN168_ME1016810202011(CHIPS)':
 'PETP5': CDS_PINID='PETP5';
NODE_NAME     R6012 2
 '@T6G_MB_LIB.T6G(SCH_1):PAGE348_I131@PURE_QUANTA.Q_RES(CHIPS)':
 'B': CDS_PINID='B';
NET_NAME
'SGPIO_SCM_INTR_N'
 '@T6G_MB_LIB.T6G(SCH_1):SGPIO_SCM_INTR_N':
 C_SIGNAL='@t6g_mb_lib.t6g(sch_1):sgpio_scm_intr_n';
NODE_NAME     R58 2
 '@T6G_MB_LIB.T6G(SCH_1):PAGE79_I44@PURE_QUANTA.Q_RES(CHIPS)':
 'B': CDS_PINID='B';
NODE_NAME     R6026 1
 '@T6G_MB_LIB.T6G(SCH_1):PAGE348_I42@PURE_QUANTA.Q_RES(CHIPS)':
 'A': CDS_PINID='A';
NODE_NAME     R6024 2
 '@T6G_MB_LIB.T6G(SCH_1):PAGE349_I20@PURE_QUANTA.Q_RES(CHIPS)':
 'B': CDS_PINID='B';
NET_NAME
'SGPIO_SCM_INTR_R1_N'
 '@T6G_MB_LIB.T6G(SCH_1):SGPIO_SCM_INTR_R1_N':
 C_SIGNAL='@t6g_mb_lib.t6g(sch_1):sgpio_scm_intr_r1_n';
NODE_NAME     J41 B40
 '@T6G_MB_LIB.T6G(SCH_1):PAGE348_I176@PURE_QUANTA.SCONN168_ME1016810202011(CHIPS)':
 'PETP7': CDS_PINID='PETP7';
NODE_NAME     R6026 2
 '@T6G_MB_LIB.T6G(SCH_1):PAGE348_I42@PURE_QUANTA.Q_RES(CHIPS)':
 'B': CDS_PINID='B';
NET_NAME
'SGPIO_SCM_INTR_R_N'
 '@T6G_MB_LIB.T6G(SCH_1):SGPIO_SCM_INTR_R_N':
 C_SIGNAL='@t6g_mb_lib.t6g(sch_1):sgpio_scm_intr_r_n';
NODE_NAME     R58 1
 '@T6G_MB_LIB.T6G(SCH_1):PAGE79_I44@PURE_QUANTA.Q_RES(CHIPS)':
 'A': CDS_PINID='A';
NODE_NAME     U18 G8
 '@T6G_MB_LIB.T6G(SCH_1):PAGE79_I94@PURE_QUANTA.LCMXO3LF9400C5BG484C(CHIPS)':
 'PT11D': CDS_PINID='PT11D';
NET_NAME
'SGPIO_SCM_LD_<0>'
 '@T6G_MB_LIB.T6G(SCH_1):SGPIO_SCM_LD_'<0>:
 C_SIGNAL='@t6g_mb_lib.t6g(sch_1):\sgpio_scm_ld_\(0)';
NODE_NAME     U18 D7
 '@T6G_MB_LIB.T6G(SCH_1):PAGE79_I94@PURE_QUANTA.LCMXO3LF9400C5BG484C(CHIPS)':
 'PT14D': CDS_PINID='PT14D';
NODE_NAME     R6011 1
 '@T6G_MB_LIB.T6G(SCH_1):PAGE348_I132@PURE_QUANTA.Q_RES(CHIPS)':
 'A': CDS_PINID='A';
NODE_NAME     R6019 2
 '@T6G_MB_LIB.T6G(SCH_1):PAGE349_I25@PURE_QUANTA.Q_RES(CHIPS)':
 'B': CDS_PINID='B';
NET_NAME
'SGPIO_SCM_LD_<1>'
 '@T6G_MB_LIB.T6G(SCH_1):SGPIO_SCM_LD_'<1>:
 C_SIGNAL='@t6g_mb_lib.t6g(sch_1):\sgpio_scm_ld_\(1)';
NODE_NAME     R6015 1
 '@T6G_MB_LIB.T6G(SCH_1):PAGE348_I129@PURE_QUANTA.Q_RES(CHIPS)':
 'A': CDS_PINID='A';
NODE_NAME     U18 B5
 '@T6G_MB_LIB.T6G(SCH_1):PAGE79_I94@PURE_QUANTA.LCMXO3LF9400C5BG484C(CHIPS)':
 'PT13A': CDS_PINID='PT13A';
NODE_NAME     R6023 2
 '@T6G_MB_LIB.T6G(SCH_1):PAGE349_I21@PURE_QUANTA.Q_RES(CHIPS)':
 'B': CDS_PINID='B';
NET_NAME
'SGPIO_SCM_LD_R_<0>'
 '@T6G_MB_LIB.T6G(SCH_1):SGPIO_SCM_LD_R_'<0>:
 C_SIGNAL='@t6g_mb_lib.t6g(sch_1):\sgpio_scm_ld_r_\(0)';
NODE_NAME     J41 B32
 '@T6G_MB_LIB.T6G(SCH_1):PAGE348_I176@PURE_QUANTA.SCONN168_ME1016810202011(CHIPS)':
 'GND_B32': CDS_PINID='GND_B32';
NODE_NAME     R6011 2
 '@T6G_MB_LIB.T6G(SCH_1):PAGE348_I132@PURE_QUANTA.Q_RES(CHIPS)':
 'B': CDS_PINID='B';
NET_NAME
'SGPIO_SCM_LD_R_<1>'
 '@T6G_MB_LIB.T6G(SCH_1):SGPIO_SCM_LD_R_'<1>:
 C_SIGNAL='@t6g_mb_lib.t6g(sch_1):\sgpio_scm_ld_r_\(1)';
NODE_NAME     R6015 2
 '@T6G_MB_LIB.T6G(SCH_1):PAGE348_I129@PURE_QUANTA.Q_RES(CHIPS)':
 'B': CDS_PINID='B';
NODE_NAME     J41 B37
 '@T6G_MB_LIB.T6G(SCH_1):PAGE348_I176@PURE_QUANTA.SCONN168_ME1016810202011(CHIPS)':
 'PETP6': CDS_PINID='PETP6';
NET_NAME
'SGPIO_SCM_RESET_N'
 '@T6G_MB_LIB.T6G(SCH_1):SGPIO_SCM_RESET_N':
 C_SIGNAL='@t6g_mb_lib.t6g(sch_1):sgpio_scm_reset_n';
NODE_NAME     R6025 1
 '@T6G_MB_LIB.T6G(SCH_1):PAGE348_I43@PURE_QUANTA.Q_RES(CHIPS)':
 'A': CDS_PINID='A';
NODE_NAME     R6027 1
 '@T6G_MB_LIB.T6G(SCH_1):PAGE349_I32@PURE_QUANTA.Q_RES(CHIPS)':
 'A': CDS_PINID='A';
NODE_NAME     U18 A5
 '@T6G_MB_LIB.T6G(SCH_1):PAGE79_I94@PURE_QUANTA.LCMXO3LF9400C5BG484C(CHIPS)':
 'PT12B': CDS_PINID='PT12B';
NET_NAME
'SGPIO_SCM_RESET_R_N'
 '@T6G_MB_LIB.T6G(SCH_1):SGPIO_SCM_RESET_R_N':
 C_SIGNAL='@t6g_mb_lib.t6g(sch_1):sgpio_scm_reset_r_n';
NODE_NAME     R6025 2
 '@T6G_MB_LIB.T6G(SCH_1):PAGE348_I43@PURE_QUANTA.Q_RES(CHIPS)':
 'B': CDS_PINID='B';
NODE_NAME     J41 B39
 '@T6G_MB_LIB.T6G(SCH_1):PAGE348_I176@PURE_QUANTA.SCONN168_ME1016810202011(CHIPS)':
 'PETN7': CDS_PINID='PETN7';
NET_NAME
'SMB_1_BMC_GPU_BUF_R_SCL'
 '@T6G_MB_LIB.T6G(SCH_1):SMB_1_BMC_GPU_BUF_R_SCL':
 C_SIGNAL='@t6g_mb_lib.t6g(sch_1):smb_1_bmc_gpu_buf_r_scl';
NODE_NAME     U194 2
 '@T6G_MB_LIB.T6G(SCH_1):PAGE249_I42@PURE_QUANTA.LTC4307CMS8(CHIPS)':
 'SCL_OUT': CDS_PINID='SCL_OUT';
NODE_NAME     R2893 2
 '@T6G_MB_LIB.T6G(SCH_1):PAGE249_I68@PURE_QUANTA.Q_RES(CHIPS)':
 'B': CDS_PINID='B';
NODE_NAME     R2897 1
 '@T6G_MB_LIB.T6G(SCH_1):PAGE249_I74@PURE_QUANTA.Q_RES(CHIPS)':
 'A': CDS_PINID='A';
NODE_NAME     R3523 2
 '@T6G_MB_LIB.T6G(SCH_1):PAGE249_I80@PURE_QUANTA.Q_RES(CHIPS)':
 'B': CDS_PINID='B';
NET_NAME
'SMB_1_BMC_GPU_BUF_R_SDA'
 '@T6G_MB_LIB.T6G(SCH_1):SMB_1_BMC_GPU_BUF_R_SDA':
 C_SIGNAL='@t6g_mb_lib.t6g(sch_1):smb_1_bmc_gpu_buf_r_sda';
NODE_NAME     U194 7
 '@T6G_MB_LIB.T6G(SCH_1):PAGE249_I42@PURE_QUANTA.LTC4307CMS8(CHIPS)':
 'SDA_OUT': CDS_PINID='SDA_OUT';
NODE_NAME     R2894 2
 '@T6G_MB_LIB.T6G(SCH_1):PAGE249_I67@PURE_QUANTA.Q_RES(CHIPS)':
 'B': CDS_PINID='B';
NODE_NAME     R2898 1
 '@T6G_MB_LIB.T6G(SCH_1):PAGE249_I73@PURE_QUANTA.Q_RES(CHIPS)':
 'A': CDS_PINID='A';
NODE_NAME     R3524 2
 '@T6G_MB_LIB.T6G(SCH_1):PAGE249_I81@PURE_QUANTA.Q_RES(CHIPS)':
 'B': CDS_PINID='B';
NET_NAME
'SMB_1_BMC_GPU_BUF_SCL'
 '@T6G_MB_LIB.T6G(SCH_1):SMB_1_BMC_GPU_BUF_SCL':
 C_SIGNAL='@t6g_mb_lib.t6g(sch_1):smb_1_bmc_gpu_buf_scl';
NODE_NAME     R2897 2
 '@T6G_MB_LIB.T6G(SCH_1):PAGE249_I74@PURE_QUANTA.Q_RES(CHIPS)':
 'B': CDS_PINID='B';
NODE_NAME     J112 Q4
 '@T6G_MB_LIB.T6G(SCH_1):PAGE329_I102@PURE_QUANTA.CONN160_10131762101LF(CHIPS)':
 'Q4': CDS_PINID='Q4';
NET_NAME
'SMB_1_BMC_GPU_BUF_SDA'
 '@T6G_MB_LIB.T6G(SCH_1):SMB_1_BMC_GPU_BUF_SDA':
 C_SIGNAL='@t6g_mb_lib.t6g(sch_1):smb_1_bmc_gpu_buf_sda';
NODE_NAME     R2898 2
 '@T6G_MB_LIB.T6G(SCH_1):PAGE249_I73@PURE_QUANTA.Q_RES(CHIPS)':
 'B': CDS_PINID='B';
NODE_NAME     J112 R4
 '@T6G_MB_LIB.T6G(SCH_1):PAGE329_I102@PURE_QUANTA.CONN160_10131762101LF(CHIPS)':
 'R4': CDS_PINID='R4';
NET_NAME
'SMB_1_BMC_GPU_R_SCL'
 '@T6G_MB_LIB.T6G(SCH_1):SMB_1_BMC_GPU_R_SCL':
 C_SIGNAL='@t6g_mb_lib.t6g(sch_1):smb_1_bmc_gpu_r_scl';
NODE_NAME     R3109 2
 '@T6G_MB_LIB.T6G(SCH_1):PAGE249_I35@PURE_QUANTA.Q_RES(CHIPS)':
 'B': CDS_PINID='B';
NODE_NAME     U194 3
 '@T6G_MB_LIB.T6G(SCH_1):PAGE249_I42@PURE_QUANTA.LTC4307CMS8(CHIPS)':
 'SCL_IN': CDS_PINID='SCL_IN';
NODE_NAME     R2893 1
 '@T6G_MB_LIB.T6G(SCH_1):PAGE249_I68@PURE_QUANTA.Q_RES(CHIPS)':
 'A': CDS_PINID='A';
NET_NAME
'SMB_1_BMC_GPU_R_SDA'
 '@T6G_MB_LIB.T6G(SCH_1):SMB_1_BMC_GPU_R_SDA':
 C_SIGNAL='@t6g_mb_lib.t6g(sch_1):smb_1_bmc_gpu_r_sda';
NODE_NAME     R3110 2
 '@T6G_MB_LIB.T6G(SCH_1):PAGE249_I34@PURE_QUANTA.Q_RES(CHIPS)':
 'B': CDS_PINID='B';
NODE_NAME     U194 6
 '@T6G_MB_LIB.T6G(SCH_1):PAGE249_I42@PURE_QUANTA.LTC4307CMS8(CHIPS)':
 'SDA_IN': CDS_PINID='SDA_IN';
NODE_NAME     R2894 1
 '@T6G_MB_LIB.T6G(SCH_1):PAGE249_I67@PURE_QUANTA.Q_RES(CHIPS)':
 'A': CDS_PINID='A';
NET_NAME
'SMB_1_BMC_GPU_SCL'
 '@T6G_MB_LIB.T6G(SCH_1):SMB_1_BMC_GPU_SCL':
 C_SIGNAL='@t6g_mb_lib.t6g(sch_1):smb_1_bmc_gpu_scl';
NODE_NAME     R3226 1
 '@T6G_MB_LIB.T6G(SCH_1):PAGE349_I122@PURE_QUANTA.Q_RES(CHIPS)':
 'A': CDS_PINID='A';
NODE_NAME     R3109 1
 '@T6G_MB_LIB.T6G(SCH_1):PAGE249_I35@PURE_QUANTA.Q_RES(CHIPS)':
 'A': CDS_PINID='A';
NODE_NAME     R2415 1
 '@T6G_MB_LIB.T6G(SCH_1):PAGE348_I60@PURE_QUANTA.Q_RES(CHIPS)':
 'A': CDS_PINID='A';
NET_NAME
'SMB_1_BMC_GPU_SDA'
 '@T6G_MB_LIB.T6G(SCH_1):SMB_1_BMC_GPU_SDA':
 C_SIGNAL='@t6g_mb_lib.t6g(sch_1):smb_1_bmc_gpu_sda';
NODE_NAME     R3227 1
 '@T6G_MB_LIB.T6G(SCH_1):PAGE349_I121@PURE_QUANTA.Q_RES(CHIPS)':
 'A': CDS_PINID='A';
NODE_NAME     R3110 1
 '@T6G_MB_LIB.T6G(SCH_1):PAGE249_I34@PURE_QUANTA.Q_RES(CHIPS)':
 'A': CDS_PINID='A';
NODE_NAME     R2416 1
 '@T6G_MB_LIB.T6G(SCH_1):PAGE348_I33@PURE_QUANTA.Q_RES(CHIPS)':
 'A': CDS_PINID='A';
NET_NAME
'SMB_1_PLD_3V3AUX_SCL'
 '@T6G_MB_LIB.T6G(SCH_1):SMB_1_PLD_3V3AUX_SCL':
 C_SIGNAL='@t6g_mb_lib.t6g(sch_1):smb_1_pld_3v3aux_scl';
NODE_NAME     R4508 1
 '@T6G_MB_LIB.T6G(SCH_1):PAGE348_I88@PURE_QUANTA.Q_RES(CHIPS)':
 'A': CDS_PINID='A';
NODE_NAME     R6036 1
 '@T6G_MB_LIB.T6G(SCH_1):PAGE349_I131@PURE_QUANTA.Q_RES(CHIPS)':
 'A': CDS_PINID='A';
NODE_NAME     R4151 1
 '@T6G_MB_LIB.T6G(SCH_1):PAGE349_I83@PURE_QUANTA.Q_RES(CHIPS)':
 'A': CDS_PINID='A';
NODE_NAME     R4149 1
 '@T6G_MB_LIB.T6G(SCH_1):PAGE349_I89@PURE_QUANTA.Q_RES(CHIPS)':
 'A': CDS_PINID='A';
NET_NAME
'SMB_1_PLD_3V3AUX_SCL_R1'
 '@T6G_MB_LIB.T6G(SCH_1):SMB_1_PLD_3V3AUX_SCL_R1':
 C_SIGNAL='@t6g_mb_lib.t6g(sch_1):smb_1_pld_3v3aux_scl_r1';
NODE_NAME     R51 1
 '@T6G_MB_LIB.T6G(SCH_1):PAGE79_I83@PURE_QUANTA.Q_RES(CHIPS)':
 'A': CDS_PINID='A';
NODE_NAME     R4149 2
 '@T6G_MB_LIB.T6G(SCH_1):PAGE349_I89@PURE_QUANTA.Q_RES(CHIPS)':
 'B': CDS_PINID='B';
NET_NAME
'SMB_1_PLD_3V3AUX_SCL_R2'
 '@T6G_MB_LIB.T6G(SCH_1):SMB_1_PLD_3V3AUX_SCL_R2':
 C_SIGNAL='@t6g_mb_lib.t6g(sch_1):smb_1_pld_3v3aux_scl_r2';
NODE_NAME     R51 2
 '@T6G_MB_LIB.T6G(SCH_1):PAGE79_I83@PURE_QUANTA.Q_RES(CHIPS)':
 'B': CDS_PINID='B';
NODE_NAME     U18 B12
 '@T6G_MB_LIB.T6G(SCH_1):PAGE79_I94@PURE_QUANTA.LCMXO3LF9400C5BG484C(CHIPS)':
 'PT27C||SCL||PCLKT0_0': CDS_PINID='\pt27c||scl||pclkt0_0\';
NET_NAME
'SMB_1_PLD_3V3AUX_SCL_R3'
 '@T6G_MB_LIB.T6G(SCH_1):SMB_1_PLD_3V3AUX_SCL_R3':
 C_SIGNAL='@t6g_mb_lib.t6g(sch_1):smb_1_pld_3v3aux_scl_r3';
NODE_NAME     R4508 2
 '@T6G_MB_LIB.T6G(SCH_1):PAGE348_I88@PURE_QUANTA.Q_RES(CHIPS)':
 'B': CDS_PINID='B';
NODE_NAME     J41 A27
 '@T6G_MB_LIB.T6G(SCH_1):PAGE348_I176@PURE_QUANTA.SCONN168_ME1016810202011(CHIPS)':
 'PERP3': CDS_PINID='PERP3';
NET_NAME
'SMB_1_PLD_3V3AUX_SDA'
 '@T6G_MB_LIB.T6G(SCH_1):SMB_1_PLD_3V3AUX_SDA':
 C_SIGNAL='@t6g_mb_lib.t6g(sch_1):smb_1_pld_3v3aux_sda';
NODE_NAME     R4509 1
 '@T6G_MB_LIB.T6G(SCH_1):PAGE348_I87@PURE_QUANTA.Q_RES(CHIPS)':
 'A': CDS_PINID='A';
NODE_NAME     R4152 1
 '@T6G_MB_LIB.T6G(SCH_1):PAGE349_I84@PURE_QUANTA.Q_RES(CHIPS)':
 'A': CDS_PINID='A';
NODE_NAME     R6037 1
 '@T6G_MB_LIB.T6G(SCH_1):PAGE349_I132@PURE_QUANTA.Q_RES(CHIPS)':
 'A': CDS_PINID='A';
NODE_NAME     R4150 1
 '@T6G_MB_LIB.T6G(SCH_1):PAGE349_I90@PURE_QUANTA.Q_RES(CHIPS)':
 'A': CDS_PINID='A';
NET_NAME
'SMB_1_PLD_3V3AUX_SDA_R1'
 '@T6G_MB_LIB.T6G(SCH_1):SMB_1_PLD_3V3AUX_SDA_R1':
 C_SIGNAL='@t6g_mb_lib.t6g(sch_1):smb_1_pld_3v3aux_sda_r1';
NODE_NAME     R56 1
 '@T6G_MB_LIB.T6G(SCH_1):PAGE79_I82@PURE_QUANTA.Q_RES(CHIPS)':
 'A': CDS_PINID='A';
NODE_NAME     R4150 2
 '@T6G_MB_LIB.T6G(SCH_1):PAGE349_I90@PURE_QUANTA.Q_RES(CHIPS)':
 'B': CDS_PINID='B';
NET_NAME
'SMB_1_PLD_3V3AUX_SDA_R2'
 '@T6G_MB_LIB.T6G(SCH_1):SMB_1_PLD_3V3AUX_SDA_R2':
 C_SIGNAL='@t6g_mb_lib.t6g(sch_1):smb_1_pld_3v3aux_sda_r2';
NODE_NAME     R56 2
 '@T6G_MB_LIB.T6G(SCH_1):PAGE79_I82@PURE_QUANTA.Q_RES(CHIPS)':
 'B': CDS_PINID='B';
NODE_NAME     U18 A12
 '@T6G_MB_LIB.T6G(SCH_1):PAGE79_I94@PURE_QUANTA.LCMXO3LF9400C5BG484C(CHIPS)':
 'PT27D||SDA||PCLKC0_0': CDS_PINID='\pt27d||sda||pclkc0_0\';
NET_NAME
'SMB_1_PLD_3V3AUX_SDA_R3'
 '@T6G_MB_LIB.T6G(SCH_1):SMB_1_PLD_3V3AUX_SDA_R3':
 C_SIGNAL='@t6g_mb_lib.t6g(sch_1):smb_1_pld_3v3aux_sda_r3';
NODE_NAME     R4509 2
 '@T6G_MB_LIB.T6G(SCH_1):PAGE348_I87@PURE_QUANTA.Q_RES(CHIPS)':
 'B': CDS_PINID='B';
NODE_NAME     J41 A28
 '@T6G_MB_LIB.T6G(SCH_1):PAGE348_I176@PURE_QUANTA.SCONN168_ME1016810202011(CHIPS)':
 'GND_A28': CDS_PINID='GND_A28';
NET_NAME
'SMB_2_BMC_GPU_BUF_R_SCL'
 '@T6G_MB_LIB.T6G(SCH_1):SMB_2_BMC_GPU_BUF_R_SCL':
 C_SIGNAL='@t6g_mb_lib.t6g(sch_1):smb_2_bmc_gpu_buf_r_scl';
NODE_NAME     U200 2
 '@T6G_MB_LIB.T6G(SCH_1):PAGE249_I15@PURE_QUANTA.LTC4307CMS8(CHIPS)':
 'SCL_OUT': CDS_PINID='SCL_OUT';
NODE_NAME     R2986 2
 '@T6G_MB_LIB.T6G(SCH_1):PAGE249_I18@PURE_QUANTA.Q_RES(CHIPS)':
 'B': CDS_PINID='B';
NODE_NAME     R3521 2
 '@T6G_MB_LIB.T6G(SCH_1):PAGE249_I36@PURE_QUANTA.Q_RES(CHIPS)':
 'B': CDS_PINID='B';
NODE_NAME     R2990 1
 '@T6G_MB_LIB.T6G(SCH_1):PAGE249_I38@PURE_QUANTA.Q_RES(CHIPS)':
 'A': CDS_PINID='A';
NET_NAME
'SMB_2_BMC_GPU_BUF_R_SDA'
 '@T6G_MB_LIB.T6G(SCH_1):SMB_2_BMC_GPU_BUF_R_SDA':
 C_SIGNAL='@t6g_mb_lib.t6g(sch_1):smb_2_bmc_gpu_buf_r_sda';
NODE_NAME     U200 7
 '@T6G_MB_LIB.T6G(SCH_1):PAGE249_I15@PURE_QUANTA.LTC4307CMS8(CHIPS)':
 'SDA_OUT': CDS_PINID='SDA_OUT';
NODE_NAME     R2987 2
 '@T6G_MB_LIB.T6G(SCH_1):PAGE249_I17@PURE_QUANTA.Q_RES(CHIPS)':
 'B': CDS_PINID='B';
NODE_NAME     R3522 2
 '@T6G_MB_LIB.T6G(SCH_1):PAGE249_I37@PURE_QUANTA.Q_RES(CHIPS)':
 'B': CDS_PINID='B';
NODE_NAME     R2991 1
 '@T6G_MB_LIB.T6G(SCH_1):PAGE249_I39@PURE_QUANTA.Q_RES(CHIPS)':
 'A': CDS_PINID='A';
NET_NAME
'SMB_2_BMC_GPU_BUF_SCL'
 '@T6G_MB_LIB.T6G(SCH_1):SMB_2_BMC_GPU_BUF_SCL':
 C_SIGNAL='@t6g_mb_lib.t6g(sch_1):smb_2_bmc_gpu_buf_scl';
NODE_NAME     R2990 2
 '@T6G_MB_LIB.T6G(SCH_1):PAGE249_I38@PURE_QUANTA.Q_RES(CHIPS)':
 'B': CDS_PINID='B';
NODE_NAME     J112 R3
 '@T6G_MB_LIB.T6G(SCH_1):PAGE329_I102@PURE_QUANTA.CONN160_10131762101LF(CHIPS)':
 'R3': CDS_PINID='R3';
NET_NAME
'SMB_2_BMC_GPU_BUF_SDA'
 '@T6G_MB_LIB.T6G(SCH_1):SMB_2_BMC_GPU_BUF_SDA':
 C_SIGNAL='@t6g_mb_lib.t6g(sch_1):smb_2_bmc_gpu_buf_sda';
NODE_NAME     R2991 2
 '@T6G_MB_LIB.T6G(SCH_1):PAGE249_I39@PURE_QUANTA.Q_RES(CHIPS)':
 'B': CDS_PINID='B';
NODE_NAME     J112 S3
 '@T6G_MB_LIB.T6G(SCH_1):PAGE329_I102@PURE_QUANTA.CONN160_10131762101LF(CHIPS)':
 'S3': CDS_PINID='S3';
NET_NAME
'SMB_2_BMC_GPU_R_SCL'
 '@T6G_MB_LIB.T6G(SCH_1):SMB_2_BMC_GPU_R_SCL':
 C_SIGNAL='@t6g_mb_lib.t6g(sch_1):smb_2_bmc_gpu_r_scl';
NODE_NAME     R3107 2
 '@T6G_MB_LIB.T6G(SCH_1):PAGE249_I13@PURE_QUANTA.Q_RES(CHIPS)':
 'B': CDS_PINID='B';
NODE_NAME     U200 3
 '@T6G_MB_LIB.T6G(SCH_1):PAGE249_I15@PURE_QUANTA.LTC4307CMS8(CHIPS)':
 'SCL_IN': CDS_PINID='SCL_IN';
NODE_NAME     R2986 1
 '@T6G_MB_LIB.T6G(SCH_1):PAGE249_I18@PURE_QUANTA.Q_RES(CHIPS)':
 'A': CDS_PINID='A';
NET_NAME
'SMB_2_BMC_GPU_R_SDA'
 '@T6G_MB_LIB.T6G(SCH_1):SMB_2_BMC_GPU_R_SDA':
 C_SIGNAL='@t6g_mb_lib.t6g(sch_1):smb_2_bmc_gpu_r_sda';
NODE_NAME     R3108 2
 '@T6G_MB_LIB.T6G(SCH_1):PAGE249_I14@PURE_QUANTA.Q_RES(CHIPS)':
 'B': CDS_PINID='B';
NODE_NAME     U200 6
 '@T6G_MB_LIB.T6G(SCH_1):PAGE249_I15@PURE_QUANTA.LTC4307CMS8(CHIPS)':
 'SDA_IN': CDS_PINID='SDA_IN';
NODE_NAME     R2987 1
 '@T6G_MB_LIB.T6G(SCH_1):PAGE249_I17@PURE_QUANTA.Q_RES(CHIPS)':
 'A': CDS_PINID='A';
NET_NAME
'SMB_2_BMC_GPU_SCL'
 '@T6G_MB_LIB.T6G(SCH_1):SMB_2_BMC_GPU_SCL':
 C_SIGNAL='@t6g_mb_lib.t6g(sch_1):smb_2_bmc_gpu_scl';
NODE_NAME     R2413 1
 '@T6G_MB_LIB.T6G(SCH_1):PAGE348_I86@PURE_QUANTA.Q_RES(CHIPS)':
 'A': CDS_PINID='A';
NODE_NAME     R2999 1
 '@T6G_MB_LIB.T6G(SCH_1):PAGE349_I124@PURE_QUANTA.Q_RES(CHIPS)':
 'A': CDS_PINID='A';
NODE_NAME     R3107 1
 '@T6G_MB_LIB.T6G(SCH_1):PAGE249_I13@PURE_QUANTA.Q_RES(CHIPS)':
 'A': CDS_PINID='A';
NET_NAME
'SMB_2_BMC_GPU_SDA'
 '@T6G_MB_LIB.T6G(SCH_1):SMB_2_BMC_GPU_SDA':
 C_SIGNAL='@t6g_mb_lib.t6g(sch_1):smb_2_bmc_gpu_sda';
NODE_NAME     R2414 1
 '@T6G_MB_LIB.T6G(SCH_1):PAGE348_I85@PURE_QUANTA.Q_RES(CHIPS)':
 'A': CDS_PINID='A';
NODE_NAME     R3004 1
 '@T6G_MB_LIB.T6G(SCH_1):PAGE349_I123@PURE_QUANTA.Q_RES(CHIPS)':
 'A': CDS_PINID='A';
NODE_NAME     R3108 1
 '@T6G_MB_LIB.T6G(SCH_1):PAGE249_I14@PURE_QUANTA.Q_RES(CHIPS)':
 'A': CDS_PINID='A';
NET_NAME
'SMB_2_PLD_3V3AUX_SCL_R1'
 '@T6G_MB_LIB.T6G(SCH_1):SMB_2_PLD_3V3AUX_SCL_R1':
 C_SIGNAL='@t6g_mb_lib.t6g(sch_1):smb_2_pld_3v3aux_scl_r1';
NODE_NAME     R210 1
 '@T6G_MB_LIB.T6G(SCH_1):PAGE79_I81@PURE_QUANTA.Q_RES(CHIPS)':
 'A': CDS_PINID='A';
NODE_NAME     R4151 2
 '@T6G_MB_LIB.T6G(SCH_1):PAGE349_I83@PURE_QUANTA.Q_RES(CHIPS)':
 'B': CDS_PINID='B';
NET_NAME
'SMB_2_PLD_3V3AUX_SCL_R2'
 '@T6G_MB_LIB.T6G(SCH_1):SMB_2_PLD_3V3AUX_SCL_R2':
 C_SIGNAL='@t6g_mb_lib.t6g(sch_1):smb_2_pld_3v3aux_scl_r2';
NODE_NAME     R210 2
 '@T6G_MB_LIB.T6G(SCH_1):PAGE79_I81@PURE_QUANTA.Q_RES(CHIPS)':
 'B': CDS_PINID='B';
NODE_NAME     U18 A13
 '@T6G_MB_LIB.T6G(SCH_1):PAGE79_I94@PURE_QUANTA.LCMXO3LF9400C5BG484C(CHIPS)':
 'PT29A': CDS_PINID='PT29A';
NET_NAME
'SMB_2_PLD_3V3AUX_SDA_R1'
 '@T6G_MB_LIB.T6G(SCH_1):SMB_2_PLD_3V3AUX_SDA_R1':
 C_SIGNAL='@t6g_mb_lib.t6g(sch_1):smb_2_pld_3v3aux_sda_r1';
NODE_NAME     R4152 2
 '@T6G_MB_LIB.T6G(SCH_1):PAGE349_I84@PURE_QUANTA.Q_RES(CHIPS)':
 'B': CDS_PINID='B';
NODE_NAME     R211 1
 '@T6G_MB_LIB.T6G(SCH_1):PAGE79_I80@PURE_QUANTA.Q_RES(CHIPS)':
 'A': CDS_PINID='A';
NET_NAME
'SMB_2_PLD_3V3AUX_SDA_R2'
 '@T6G_MB_LIB.T6G(SCH_1):SMB_2_PLD_3V3AUX_SDA_R2':
 C_SIGNAL='@t6g_mb_lib.t6g(sch_1):smb_2_pld_3v3aux_sda_r2';
NODE_NAME     R211 2
 '@T6G_MB_LIB.T6G(SCH_1):PAGE79_I80@PURE_QUANTA.Q_RES(CHIPS)':
 'B': CDS_PINID='B';
NODE_NAME     U18 B13
 '@T6G_MB_LIB.T6G(SCH_1):PAGE79_I94@PURE_QUANTA.LCMXO3LF9400C5BG484C(CHIPS)':
 'PT29B': CDS_PINID='PT29B';
NET_NAME
'SMB_9ZXL045_P0_SCL'
 '@T6G_MB_LIB.T6G(SCH_1):SMB_9ZXL045_P0_SCL':
 C_SIGNAL='@t6g_mb_lib.t6g(sch_1):smb_9zxl045_p0_scl';
NODE_NAME     U314 7
 '@T6G_MB_LIB.T6G(SCH_1):PAGE160_I63@PURE_QUANTA.9ZXL0451EKILFT(CHIPS)':
 'SMBCLK': CDS_PINID='SMBCLK';
NODE_NAME     R6864 2
 '@T6G_MB_LIB.T6G(SCH_1):PAGE349_I220@PURE_QUANTA.Q_RES(CHIPS)':
 'B': CDS_PINID='B';
NET_NAME
'SMB_9ZXL045_P0_SDA'
 '@T6G_MB_LIB.T6G(SCH_1):SMB_9ZXL045_P0_SDA':
 C_SIGNAL='@t6g_mb_lib.t6g(sch_1):smb_9zxl045_p0_sda';
NODE_NAME     U314 6
 '@T6G_MB_LIB.T6G(SCH_1):PAGE160_I63@PURE_QUANTA.9ZXL0451EKILFT(CHIPS)':
 'SMBDAT': CDS_PINID='SMBDAT';
NODE_NAME     R6865 2
 '@T6G_MB_LIB.T6G(SCH_1):PAGE349_I221@PURE_QUANTA.Q_RES(CHIPS)':
 'B': CDS_PINID='B';
NET_NAME
'SMB_9ZXL045_P1_SCL'
 '@T6G_MB_LIB.T6G(SCH_1):SMB_9ZXL045_P1_SCL':
 C_SIGNAL='@t6g_mb_lib.t6g(sch_1):smb_9zxl045_p1_scl';
NODE_NAME     U10 7
 '@T6G_MB_LIB.T6G(SCH_1):PAGE379_I63@PURE_QUANTA.9ZXL0451EKILFT(CHIPS)':
 'SMBCLK': CDS_PINID='SMBCLK';
NODE_NAME     R6862 2
 '@T6G_MB_LIB.T6G(SCH_1):PAGE349_I218@PURE_QUANTA.Q_RES(CHIPS)':
 'B': CDS_PINID='B';
NET_NAME
'SMB_9ZXL045_P1_SDA'
 '@T6G_MB_LIB.T6G(SCH_1):SMB_9ZXL045_P1_SDA':
 C_SIGNAL='@t6g_mb_lib.t6g(sch_1):smb_9zxl045_p1_sda';
NODE_NAME     U10 6
 '@T6G_MB_LIB.T6G(SCH_1):PAGE379_I63@PURE_QUANTA.9ZXL0451EKILFT(CHIPS)':
 'SMBDAT': CDS_PINID='SMBDAT';
NODE_NAME     R6863 2
 '@T6G_MB_LIB.T6G(SCH_1):PAGE349_I219@PURE_QUANTA.Q_RES(CHIPS)':
 'B': CDS_PINID='B';
NET_NAME
'SMB_ADC_SCL'
 '@T6G_MB_LIB.T6G(SCH_1):SMB_ADC_SCL':
 C_SIGNAL='@t6g_mb_lib.t6g(sch_1):smb_adc_scl';
NODE_NAME     U39 18
 '@T6G_MB_LIB.T6G(SCH_1):PAGE251_I74@PURE_QUANTA.TCA9548APWR(CHIPS)':
 'SC6': CDS_PINID='SC6';
NODE_NAME     R1315 1
 '@T6G_MB_LIB.T6G(SCH_1):PAGE251_I80@PURE_QUANTA.Q_RES(CHIPS)':
 'A': CDS_PINID='A';
NET_NAME
'SMB_ADC_SCL_R'
 '@T6G_MB_LIB.T6G(SCH_1):SMB_ADC_SCL_R':
 C_SIGNAL='@t6g_mb_lib.t6g(sch_1):smb_adc_scl_r';
NODE_NAME     R1228 1
 '@T6G_MB_LIB.T6G(SCH_1):PAGE263_I139@PURE_QUANTA.Q_RES(CHIPS)':
 'A': CDS_PINID='A';
NODE_NAME     R1244 1
 '@T6G_MB_LIB.T6G(SCH_1):PAGE263_I140@PURE_QUANTA.Q_RES(CHIPS)':
 'A': CDS_PINID='A';
NODE_NAME     R1315 2
 '@T6G_MB_LIB.T6G(SCH_1):PAGE251_I80@PURE_QUANTA.Q_RES(CHIPS)':
 'B': CDS_PINID='B';
NODE_NAME     R1316 2
 '@T6G_MB_LIB.T6G(SCH_1):PAGE251_I83@PURE_QUANTA.Q_RES(CHIPS)':
 'B': CDS_PINID='B';
NET_NAME
'SMB_ADC_SDA'
 '@T6G_MB_LIB.T6G(SCH_1):SMB_ADC_SDA':
 C_SIGNAL='@t6g_mb_lib.t6g(sch_1):smb_adc_sda';
NODE_NAME     U39 17
 '@T6G_MB_LIB.T6G(SCH_1):PAGE251_I74@PURE_QUANTA.TCA9548APWR(CHIPS)':
 'SD6': CDS_PINID='SD6';
NODE_NAME     R1312 1
 '@T6G_MB_LIB.T6G(SCH_1):PAGE251_I79@PURE_QUANTA.Q_RES(CHIPS)':
 'A': CDS_PINID='A';
NET_NAME
'SMB_ADC_SDA_R'
 '@T6G_MB_LIB.T6G(SCH_1):SMB_ADC_SDA_R':
 C_SIGNAL='@t6g_mb_lib.t6g(sch_1):smb_adc_sda_r';
NODE_NAME     R1227 1
 '@T6G_MB_LIB.T6G(SCH_1):PAGE263_I138@PURE_QUANTA.Q_RES(CHIPS)':
 'A': CDS_PINID='A';
NODE_NAME     R1243 1
 '@T6G_MB_LIB.T6G(SCH_1):PAGE263_I141@PURE_QUANTA.Q_RES(CHIPS)':
 'A': CDS_PINID='A';
NODE_NAME     R1312 2
 '@T6G_MB_LIB.T6G(SCH_1):PAGE251_I79@PURE_QUANTA.Q_RES(CHIPS)':
 'B': CDS_PINID='B';
NODE_NAME     R1341 2
 '@T6G_MB_LIB.T6G(SCH_1):PAGE251_I84@PURE_QUANTA.Q_RES(CHIPS)':
 'B': CDS_PINID='B';
NET_NAME
'SMB_APML_CPU0_MUX2_SCL'
 '@T6G_MB_LIB.T6G(SCH_1):SMB_APML_CPU0_MUX2_SCL':
 C_SIGNAL='@t6g_mb_lib.t6g(sch_1):smb_apml_cpu0_mux2_scl';
NODE_NAME     R327 1
 '@T6G_MB_LIB.T6G(SCH_1):PAGE138_I91@PURE_QUANTA.Q_RES(CHIPS)':
 'A': CDS_PINID='A';
NODE_NAME     U4 1
 '@T6G_MB_LIB.T6G(SCH_1):PAGE138_I114@PURE_QUANTA.PI3CSW12ZUAEX(CHIPS)':
 '1D+': CDS_PINID='\1d+\';
NET_NAME
'SMB_APML_CPU0_MUX2_SDA'
 '@T6G_MB_LIB.T6G(SCH_1):SMB_APML_CPU0_MUX2_SDA':
 C_SIGNAL='@t6g_mb_lib.t6g(sch_1):smb_apml_cpu0_mux2_sda';
NODE_NAME     R328 1
 '@T6G_MB_LIB.T6G(SCH_1):PAGE138_I92@PURE_QUANTA.Q_RES(CHIPS)':
 'A': CDS_PINID='A';
NODE_NAME     U4 2
 '@T6G_MB_LIB.T6G(SCH_1):PAGE138_I114@PURE_QUANTA.PI3CSW12ZUAEX(CHIPS)':
 '1D-': CDS_PINID='\1d-\';
NET_NAME
'SMB_APML_CPU0_R_SCL'
 '@T6G_MB_LIB.T6G(SCH_1):SMB_APML_CPU0_R_SCL':
 C_SIGNAL='@t6g_mb_lib.t6g(sch_1):smb_apml_cpu0_r_scl';
NODE_NAME     R142 2
 '@T6G_MB_LIB.T6G(SCH_1):PAGE138_I35@PURE_QUANTA.Q_RES(CHIPS)':
 'B': CDS_PINID='B';
NODE_NAME     R1156 1
 '@T6G_MB_LIB.T6G(SCH_1):PAGE138_I38@PURE_QUANTA.Q_RES(CHIPS)':
 'A': CDS_PINID='A';
NODE_NAME     U213 4
 '@T6G_MB_LIB.T6G(SCH_1):PAGE138_I111@PURE_QUANTA.IML3112Y2B000NCG8(CHIPS)':
 'LSCL_0': CDS_PINID='LSCL_0';
NET_NAME
'SMB_APML_CPU0_R_SDA'
 '@T6G_MB_LIB.T6G(SCH_1):SMB_APML_CPU0_R_SDA':
 C_SIGNAL='@t6g_mb_lib.t6g(sch_1):smb_apml_cpu0_r_sda';
NODE_NAME     R143 2
 '@T6G_MB_LIB.T6G(SCH_1):PAGE138_I34@PURE_QUANTA.Q_RES(CHIPS)':
 'B': CDS_PINID='B';
NODE_NAME     R1155 1
 '@T6G_MB_LIB.T6G(SCH_1):PAGE138_I39@PURE_QUANTA.Q_RES(CHIPS)':
 'A': CDS_PINID='A';
NODE_NAME     U213 1
 '@T6G_MB_LIB.T6G(SCH_1):PAGE138_I111@PURE_QUANTA.IML3112Y2B000NCG8(CHIPS)':
 'LSDA_0': CDS_PINID='LSDA_0';
NET_NAME
'SMB_APML_CPU0_SCL'
 '@T6G_MB_LIB.T6G(SCH_1):SMB_APML_CPU0_SCL':
 C_SIGNAL='@t6g_mb_lib.t6g(sch_1):smb_apml_cpu0_scl';
NODE_NAME     U25 DJ71
 '@T6G_MB_LIB.T6G(SCH_1):PAGE27_I227@PURE_QUANTA.GENOA_SP5(CHIPS)':
 'SIC': CDS_PINID='SIC';
NODE_NAME     R1156 2
 '@T6G_MB_LIB.T6G(SCH_1):PAGE138_I38@PURE_QUANTA.Q_RES(CHIPS)':
 'B': CDS_PINID='B';
NODE_NAME     R363 2
 '@T6G_MB_LIB.T6G(SCH_1):PAGE138_I56@PURE_QUANTA.Q_RES(CHIPS)':
 'B': CDS_PINID='B';
NODE_NAME     R327 2
 '@T6G_MB_LIB.T6G(SCH_1):PAGE138_I91@PURE_QUANTA.Q_RES(CHIPS)':
 'B': CDS_PINID='B';
NET_NAME
'SMB_APML_CPU0_SDA'
 '@T6G_MB_LIB.T6G(SCH_1):SMB_APML_CPU0_SDA':
 C_SIGNAL='@t6g_mb_lib.t6g(sch_1):smb_apml_cpu0_sda';
NODE_NAME     U25 DH71
 '@T6G_MB_LIB.T6G(SCH_1):PAGE27_I227@PURE_QUANTA.GENOA_SP5(CHIPS)':
 'SID': CDS_PINID='SID';
NODE_NAME     R1155 2
 '@T6G_MB_LIB.T6G(SCH_1):PAGE138_I39@PURE_QUANTA.Q_RES(CHIPS)':
 'B': CDS_PINID='B';
NODE_NAME     R360 2
 '@T6G_MB_LIB.T6G(SCH_1):PAGE138_I55@PURE_QUANTA.Q_RES(CHIPS)':
 'B': CDS_PINID='B';
NODE_NAME     R328 2
 '@T6G_MB_LIB.T6G(SCH_1):PAGE138_I92@PURE_QUANTA.Q_RES(CHIPS)':
 'B': CDS_PINID='B';
NET_NAME
'SMB_APML_CPU1_MUX2_SCL'
 '@T6G_MB_LIB.T6G(SCH_1):SMB_APML_CPU1_MUX2_SCL':
 C_SIGNAL='@t6g_mb_lib.t6g(sch_1):smb_apml_cpu1_mux2_scl';
NODE_NAME     R337 1
 '@T6G_MB_LIB.T6G(SCH_1):PAGE138_I93@PURE_QUANTA.Q_RES(CHIPS)':
 'A': CDS_PINID='A';
NODE_NAME     U4 3
 '@T6G_MB_LIB.T6G(SCH_1):PAGE138_I114@PURE_QUANTA.PI3CSW12ZUAEX(CHIPS)':
 '2D+': CDS_PINID='\2d+\';
NET_NAME
'SMB_APML_CPU1_MUX2_SDA'
 '@T6G_MB_LIB.T6G(SCH_1):SMB_APML_CPU1_MUX2_SDA':
 C_SIGNAL='@t6g_mb_lib.t6g(sch_1):smb_apml_cpu1_mux2_sda';
NODE_NAME     R338 1
 '@T6G_MB_LIB.T6G(SCH_1):PAGE138_I94@PURE_QUANTA.Q_RES(CHIPS)':
 'A': CDS_PINID='A';
NODE_NAME     U4 4
 '@T6G_MB_LIB.T6G(SCH_1):PAGE138_I114@PURE_QUANTA.PI3CSW12ZUAEX(CHIPS)':
 '2D-': CDS_PINID='\2d-\';
NET_NAME
'SMB_APML_CPU1_R_SCL'
 '@T6G_MB_LIB.T6G(SCH_1):SMB_APML_CPU1_R_SCL':
 C_SIGNAL='@t6g_mb_lib.t6g(sch_1):smb_apml_cpu1_r_scl';
NODE_NAME     R146 2
 '@T6G_MB_LIB.T6G(SCH_1):PAGE138_I17@PURE_QUANTA.Q_RES(CHIPS)':
 'B': CDS_PINID='B';
NODE_NAME     R1157 1
 '@T6G_MB_LIB.T6G(SCH_1):PAGE138_I74@PURE_QUANTA.Q_RES(CHIPS)':
 'A': CDS_PINID='A';
NODE_NAME     U213 6
 '@T6G_MB_LIB.T6G(SCH_1):PAGE138_I111@PURE_QUANTA.IML3112Y2B000NCG8(CHIPS)':
 'LSCL_1': CDS_PINID='LSCL_1';
NET_NAME
'SMB_APML_CPU1_R_SDA'
 '@T6G_MB_LIB.T6G(SCH_1):SMB_APML_CPU1_R_SDA':
 C_SIGNAL='@t6g_mb_lib.t6g(sch_1):smb_apml_cpu1_r_sda';
NODE_NAME     R5004 1
 '@T6G_MB_LIB.T6G(SCH_1):PAGE138_I27@PURE_QUANTA.Q_RES(CHIPS)':
 'A': CDS_PINID='A';
NODE_NAME     R147 2
 '@T6G_MB_LIB.T6G(SCH_1):PAGE138_I16@PURE_QUANTA.Q_RES(CHIPS)':
 'B': CDS_PINID='B';
NODE_NAME     R1158 1
 '@T6G_MB_LIB.T6G(SCH_1):PAGE138_I73@PURE_QUANTA.Q_RES(CHIPS)':
 'A': CDS_PINID='A';
NODE_NAME     U213 8
 '@T6G_MB_LIB.T6G(SCH_1):PAGE138_I111@PURE_QUANTA.IML3112Y2B000NCG8(CHIPS)':
 'LSDA_1||HSA': CDS_PINID='\lsda_1||hsa\';
NET_NAME
'SMB_APML_CPU1_SCL'
 '@T6G_MB_LIB.T6G(SCH_1):SMB_APML_CPU1_SCL':
 C_SIGNAL='@t6g_mb_lib.t6g(sch_1):smb_apml_cpu1_scl';
NODE_NAME     U26 DJ71
 '@T6G_MB_LIB.T6G(SCH_1):PAGE54_I190@PURE_QUANTA.GENOA_SP5(CHIPS)':
 'SIC': CDS_PINID='SIC';
NODE_NAME     R362 2
 '@T6G_MB_LIB.T6G(SCH_1):PAGE138_I53@PURE_QUANTA.Q_RES(CHIPS)':
 'B': CDS_PINID='B';
NODE_NAME     R1157 2
 '@T6G_MB_LIB.T6G(SCH_1):PAGE138_I74@PURE_QUANTA.Q_RES(CHIPS)':
 'B': CDS_PINID='B';
NODE_NAME     R337 2
 '@T6G_MB_LIB.T6G(SCH_1):PAGE138_I93@PURE_QUANTA.Q_RES(CHIPS)':
 'B': CDS_PINID='B';
NET_NAME
'SMB_APML_CPU1_SDA'
 '@T6G_MB_LIB.T6G(SCH_1):SMB_APML_CPU1_SDA':
 C_SIGNAL='@t6g_mb_lib.t6g(sch_1):smb_apml_cpu1_sda';
NODE_NAME     U26 DH71
 '@T6G_MB_LIB.T6G(SCH_1):PAGE54_I190@PURE_QUANTA.GENOA_SP5(CHIPS)':
 'SID': CDS_PINID='SID';
NODE_NAME     R359 2
 '@T6G_MB_LIB.T6G(SCH_1):PAGE138_I52@PURE_QUANTA.Q_RES(CHIPS)':
 'B': CDS_PINID='B';
NODE_NAME     R1158 2
 '@T6G_MB_LIB.T6G(SCH_1):PAGE138_I73@PURE_QUANTA.Q_RES(CHIPS)':
 'B': CDS_PINID='B';
NODE_NAME     R338 2
 '@T6G_MB_LIB.T6G(SCH_1):PAGE138_I94@PURE_QUANTA.Q_RES(CHIPS)':
 'B': CDS_PINID='B';
NET_NAME
'SMB_BMC_GPU_EN'
 '@T6G_MB_LIB.T6G(SCH_1):SMB_BMC_GPU_EN':
 C_SIGNAL='@t6g_mb_lib.t6g(sch_1):smb_bmc_gpu_en';
NODE_NAME     R2992 1
 '@T6G_MB_LIB.T6G(SCH_1):PAGE249_I12@PURE_QUANTA.Q_RES(CHIPS)':
 'A': CDS_PINID='A';
NODE_NAME     R4603 1
 '@T6G_MB_LIB.T6G(SCH_1):PAGE249_I23@PURE_QUANTA.Q_RES(CHIPS)':
 'A': CDS_PINID='A';
NODE_NAME     R2899 1
 '@T6G_MB_LIB.T6G(SCH_1):PAGE249_I50@PURE_QUANTA.Q_RES(CHIPS)':
 'A': CDS_PINID='A';
NODE_NAME     U18 L4
 '@T6G_MB_LIB.T6G(SCH_1):PAGE81_I143@PURE_QUANTA.LCMXO3LF9400C5BG484C(CHIPS)':
 'PL16D': CDS_PINID='PL16D';
NET_NAME
'SMB_BMC_GPU_EN_R1'
 '@T6G_MB_LIB.T6G(SCH_1):SMB_BMC_GPU_EN_R1':
 C_SIGNAL='@t6g_mb_lib.t6g(sch_1):smb_bmc_gpu_en_r1';
NODE_NAME     U194 1
 '@T6G_MB_LIB.T6G(SCH_1):PAGE249_I42@PURE_QUANTA.LTC4307CMS8(CHIPS)':
 'ENABLE': CDS_PINID='ENABLE';
NODE_NAME     R2899 2
 '@T6G_MB_LIB.T6G(SCH_1):PAGE249_I50@PURE_QUANTA.Q_RES(CHIPS)':
 'B': CDS_PINID='B';
NET_NAME
'SMB_BMC_GPU_EN_R3'
 '@T6G_MB_LIB.T6G(SCH_1):SMB_BMC_GPU_EN_R3':
 C_SIGNAL='@t6g_mb_lib.t6g(sch_1):smb_bmc_gpu_en_r3';
NODE_NAME     R2992 2
 '@T6G_MB_LIB.T6G(SCH_1):PAGE249_I12@PURE_QUANTA.Q_RES(CHIPS)':
 'B': CDS_PINID='B';
NODE_NAME     U200 1
 '@T6G_MB_LIB.T6G(SCH_1):PAGE249_I15@PURE_QUANTA.LTC4307CMS8(CHIPS)':
 'ENABLE': CDS_PINID='ENABLE';
NET_NAME
'SMB_BMC_SWB_BUF_R_SCL'
 '@T6G_MB_LIB.T6G(SCH_1):SMB_BMC_SWB_BUF_R_SCL':
 C_SIGNAL='@t6g_mb_lib.t6g(sch_1):smb_bmc_swb_buf_r_scl';
NODE_NAME     R2705 2
 '@T6G_MB_LIB.T6G(SCH_1):PAGE249_I47@PURE_QUANTA.Q_RES(CHIPS)':
 'B': CDS_PINID='B';
NODE_NAME     U175 2
 '@T6G_MB_LIB.T6G(SCH_1):PAGE249_I49@PURE_QUANTA.LTC4307CMS8(CHIPS)':
 'SCL_OUT': CDS_PINID='SCL_OUT';
NODE_NAME     R2667 2
 '@T6G_MB_LIB.T6G(SCH_1):PAGE249_I54@PURE_QUANTA.Q_RES(CHIPS)':
 'B': CDS_PINID='B';
NODE_NAME     R2671 1
 '@T6G_MB_LIB.T6G(SCH_1):PAGE249_I58@PURE_QUANTA.Q_RES(CHIPS)':
 'A': CDS_PINID='A';
NET_NAME
'SMB_BMC_SWB_BUF_R_SDA'
 '@T6G_MB_LIB.T6G(SCH_1):SMB_BMC_SWB_BUF_R_SDA':
 C_SIGNAL='@t6g_mb_lib.t6g(sch_1):smb_bmc_swb_buf_r_sda';
NODE_NAME     R2724 2
 '@T6G_MB_LIB.T6G(SCH_1):PAGE249_I48@PURE_QUANTA.Q_RES(CHIPS)':
 'B': CDS_PINID='B';
NODE_NAME     U175 7
 '@T6G_MB_LIB.T6G(SCH_1):PAGE249_I49@PURE_QUANTA.LTC4307CMS8(CHIPS)':
 'SDA_OUT': CDS_PINID='SDA_OUT';
NODE_NAME     R2672 1
 '@T6G_MB_LIB.T6G(SCH_1):PAGE249_I56@PURE_QUANTA.Q_RES(CHIPS)':
 'A': CDS_PINID='A';
NODE_NAME     R2669 2
 '@T6G_MB_LIB.T6G(SCH_1):PAGE249_I57@PURE_QUANTA.Q_RES(CHIPS)':
 'B': CDS_PINID='B';
NET_NAME
'SMB_BMC_SWB_BUF_SCL'
 '@T6G_MB_LIB.T6G(SCH_1):SMB_BMC_SWB_BUF_SCL':
 C_SIGNAL='@t6g_mb_lib.t6g(sch_1):smb_bmc_swb_buf_scl';
NODE_NAME     R2671 2
 '@T6G_MB_LIB.T6G(SCH_1):PAGE249_I58@PURE_QUANTA.Q_RES(CHIPS)':
 'B': CDS_PINID='B';
NODE_NAME     J109 A5
 '@T6G_MB_LIB.T6G(SCH_1):PAGE319_I16@PURE_QUANTA.CONN112_10137002101LF(CHIPS)':
 'A5': CDS_PINID='A5';
NET_NAME
'SMB_BMC_SWB_BUF_SDA'
 '@T6G_MB_LIB.T6G(SCH_1):SMB_BMC_SWB_BUF_SDA':
 C_SIGNAL='@t6g_mb_lib.t6g(sch_1):smb_bmc_swb_buf_sda';
NODE_NAME     R2672 2
 '@T6G_MB_LIB.T6G(SCH_1):PAGE249_I56@PURE_QUANTA.Q_RES(CHIPS)':
 'B': CDS_PINID='B';
NODE_NAME     J109 A7
 '@T6G_MB_LIB.T6G(SCH_1):PAGE319_I16@PURE_QUANTA.CONN112_10137002101LF(CHIPS)':
 'A7': CDS_PINID='A7';
NET_NAME
'SMB_BMC_SWB_EN'
 '@T6G_MB_LIB.T6G(SCH_1):SMB_BMC_SWB_EN':
 C_SIGNAL='@t6g_mb_lib.t6g(sch_1):smb_bmc_swb_en';
NODE_NAME     R2666 1
 '@T6G_MB_LIB.T6G(SCH_1):PAGE249_I8@PURE_QUANTA.Q_RES(CHIPS)':
 'A': CDS_PINID='A';
NODE_NAME     R2676 1
 '@T6G_MB_LIB.T6G(SCH_1):PAGE249_I26@PURE_QUANTA.Q_RES(CHIPS)':
 'A': CDS_PINID='A';
NODE_NAME     R2707 1
 '@T6G_MB_LIB.T6G(SCH_1):PAGE249_I45@PURE_QUANTA.Q_RES(CHIPS)':
 'A': CDS_PINID='A';
NODE_NAME     U18 A21
 '@T6G_MB_LIB.T6G(SCH_1):PAGE79_I94@PURE_QUANTA.LCMXO3LF9400C5BG484C(CHIPS)':
 'PT44A||R_GPLLT': CDS_PINID='\pt44a||r_gpllt\';
NET_NAME
'SMB_BMC_SWB_EN_R'
 '@T6G_MB_LIB.T6G(SCH_1):SMB_BMC_SWB_EN_R':
 C_SIGNAL='@t6g_mb_lib.t6g(sch_1):smb_bmc_swb_en_r';
NODE_NAME     R2707 2
 '@T6G_MB_LIB.T6G(SCH_1):PAGE249_I45@PURE_QUANTA.Q_RES(CHIPS)':
 'B': CDS_PINID='B';
NODE_NAME     U175 1
 '@T6G_MB_LIB.T6G(SCH_1):PAGE249_I49@PURE_QUANTA.LTC4307CMS8(CHIPS)':
 'ENABLE': CDS_PINID='ENABLE';
NET_NAME
'SMB_BMC_SWB_EN_R2'
 '@T6G_MB_LIB.T6G(SCH_1):SMB_BMC_SWB_EN_R2':
 C_SIGNAL='@t6g_mb_lib.t6g(sch_1):smb_bmc_swb_en_r2';
NODE_NAME     R2676 2
 '@T6G_MB_LIB.T6G(SCH_1):PAGE249_I26@PURE_QUANTA.Q_RES(CHIPS)':
 'B': CDS_PINID='B';
NODE_NAME     U176 1
 '@T6G_MB_LIB.T6G(SCH_1):PAGE249_I30@PURE_QUANTA.LTC4307CMS8(CHIPS)':
 'ENABLE': CDS_PINID='ENABLE';
NET_NAME
'SMB_BMC_SWB_R_SCL'
 '@T6G_MB_LIB.T6G(SCH_1):SMB_BMC_SWB_R_SCL':
 C_SIGNAL='@t6g_mb_lib.t6g(sch_1):smb_bmc_swb_r_scl';
NODE_NAME     R3105 2
 '@T6G_MB_LIB.T6G(SCH_1):PAGE249_I44@PURE_QUANTA.Q_RES(CHIPS)':
 'B': CDS_PINID='B';
NODE_NAME     R2705 1
 '@T6G_MB_LIB.T6G(SCH_1):PAGE249_I47@PURE_QUANTA.Q_RES(CHIPS)':
 'A': CDS_PINID='A';
NODE_NAME     U175 3
 '@T6G_MB_LIB.T6G(SCH_1):PAGE249_I49@PURE_QUANTA.LTC4307CMS8(CHIPS)':
 'SCL_IN': CDS_PINID='SCL_IN';
NET_NAME
'SMB_BMC_SWB_R_SDA'
 '@T6G_MB_LIB.T6G(SCH_1):SMB_BMC_SWB_R_SDA':
 C_SIGNAL='@t6g_mb_lib.t6g(sch_1):smb_bmc_swb_r_sda';
NODE_NAME     R3106 2
 '@T6G_MB_LIB.T6G(SCH_1):PAGE249_I43@PURE_QUANTA.Q_RES(CHIPS)':
 'B': CDS_PINID='B';
NODE_NAME     R2724 1
 '@T6G_MB_LIB.T6G(SCH_1):PAGE249_I48@PURE_QUANTA.Q_RES(CHIPS)':
 'A': CDS_PINID='A';
NODE_NAME     U175 6
 '@T6G_MB_LIB.T6G(SCH_1):PAGE249_I49@PURE_QUANTA.LTC4307CMS8(CHIPS)':
 'SDA_IN': CDS_PINID='SDA_IN';
NET_NAME
'SMB_BMC_SWB_SCL'
 '@T6G_MB_LIB.T6G(SCH_1):SMB_BMC_SWB_SCL':
 C_SIGNAL='@t6g_mb_lib.t6g(sch_1):smb_bmc_swb_scl';
NODE_NAME     R3105 1
 '@T6G_MB_LIB.T6G(SCH_1):PAGE249_I44@PURE_QUANTA.Q_RES(CHIPS)':
 'A': CDS_PINID='A';
NODE_NAME     R2984 2
 '@T6G_MB_LIB.T6G(SCH_1):PAGE252_I41@PURE_QUANTA.Q_RES(CHIPS)':
 'B': CDS_PINID='B';
NODE_NAME     R2703 2
 '@T6G_MB_LIB.T6G(SCH_1):PAGE252_I71@PURE_QUANTA.Q_RES(CHIPS)':
 'B': CDS_PINID='B';
NET_NAME
'SMB_BMC_SWB_SCL_R4'
 '@T6G_MB_LIB.T6G(SCH_1):SMB_BMC_SWB_SCL_R4':
 C_SIGNAL='@t6g_mb_lib.t6g(sch_1):smb_bmc_swb_scl_r4';
NODE_NAME     U36 14
 '@T6G_MB_LIB.T6G(SCH_1):PAGE252_I33@PURE_QUANTA.TCA9548APWR(CHIPS)':
 'SC4': CDS_PINID='SC4';
NODE_NAME     R2703 1
 '@T6G_MB_LIB.T6G(SCH_1):PAGE252_I71@PURE_QUANTA.Q_RES(CHIPS)':
 'A': CDS_PINID='A';
NET_NAME
'SMB_BMC_SWB_SDA'
 '@T6G_MB_LIB.T6G(SCH_1):SMB_BMC_SWB_SDA':
 C_SIGNAL='@t6g_mb_lib.t6g(sch_1):smb_bmc_swb_sda';
NODE_NAME     R3106 1
 '@T6G_MB_LIB.T6G(SCH_1):PAGE249_I43@PURE_QUANTA.Q_RES(CHIPS)':
 'A': CDS_PINID='A';
NODE_NAME     R2985 2
 '@T6G_MB_LIB.T6G(SCH_1):PAGE252_I42@PURE_QUANTA.Q_RES(CHIPS)':
 'B': CDS_PINID='B';
NODE_NAME     R2704 2
 '@T6G_MB_LIB.T6G(SCH_1):PAGE252_I70@PURE_QUANTA.Q_RES(CHIPS)':
 'B': CDS_PINID='B';
NET_NAME
'SMB_BMC_SWB_SDA_R4'
 '@T6G_MB_LIB.T6G(SCH_1):SMB_BMC_SWB_SDA_R4':
 C_SIGNAL='@t6g_mb_lib.t6g(sch_1):smb_bmc_swb_sda_r4';
NODE_NAME     U36 13
 '@T6G_MB_LIB.T6G(SCH_1):PAGE252_I33@PURE_QUANTA.TCA9548APWR(CHIPS)':
 'SD4': CDS_PINID='SD4';
NODE_NAME     R2704 1
 '@T6G_MB_LIB.T6G(SCH_1):PAGE252_I70@PURE_QUANTA.Q_RES(CHIPS)':
 'A': CDS_PINID='A';
NET_NAME
'SMB_CLK_PVDDCR_CPU1_P0_R'
 '@T6G_MB_LIB.T6G(SCH_1):SMB_CLK_PVDDCR_CPU1_P0_R':
 C_SIGNAL='@t6g_mb_lib.t6g(sch_1):smb_clk_pvddcr_cpu1_p0_r';
NODE_NAME     R8071 2
 '@T6G_MB_LIB.T6G(SCH_1):PAGE175_I85@PURE_QUANTA.Q_RES(CHIPS)':
 'B': CDS_PINID='B';
NODE_NAME     PU12 14
 '@T6G_MB_LIB.T6G(SCH_1):PAGE175_I128@PURE_QUANTA.RAA229620GNPHA0(CHIPS)':
 'PMSCL': CDS_PINID='PMSCL';
NET_NAME
'SMB_CLK_PVDDCR_CPU1_P1_R'
 '@T6G_MB_LIB.T6G(SCH_1):SMB_CLK_PVDDCR_CPU1_P1_R':
 C_SIGNAL='@t6g_mb_lib.t6g(sch_1):smb_clk_pvddcr_cpu1_p1_r';
NODE_NAME     R8248 2
 '@T6G_MB_LIB.T6G(SCH_1):PAGE192_I84@PURE_QUANTA.Q_RES(CHIPS)':
 'B': CDS_PINID='B';
NODE_NAME     PU34 14
 '@T6G_MB_LIB.T6G(SCH_1):PAGE192_I128@PURE_QUANTA.RAA229620GNPHA0(CHIPS)':
 'PMSCL': CDS_PINID='PMSCL';
NET_NAME
'SMB_CPU0_2_R_SCL'
 '@T6G_MB_LIB.T6G(SCH_1):SMB_CPU0_2_R_SCL':
 C_SIGNAL='@t6g_mb_lib.t6g(sch_1):smb_cpu0_2_r_scl';
NODE_NAME     U25 C72
 '@T6G_MB_LIB.T6G(SCH_1):PAGE28_I188@PURE_QUANTA.GENOA_SP5(CHIPS)':
 'I3C2_SCL||I2C2_SCL||SPD2_SCL||AGPIO149': CDS_PINID='\i3c2_scl||i2c2_scl||spd2_scl||agpio149\';
NODE_NAME     R27 1
 '@T6G_MB_LIB.T6G(SCH_1):PAGE28_I206@PURE_QUANTA.Q_RES(CHIPS)':
 'A': CDS_PINID='A';
NET_NAME
'SMB_CPU0_2_R_SDA'
 '@T6G_MB_LIB.T6G(SCH_1):SMB_CPU0_2_R_SDA':
 C_SIGNAL='@t6g_mb_lib.t6g(sch_1):smb_cpu0_2_r_sda';
NODE_NAME     U25 B72
 '@T6G_MB_LIB.T6G(SCH_1):PAGE28_I188@PURE_QUANTA.GENOA_SP5(CHIPS)':
 'I3C2_SDA||I2C2_SDA||SPD2_SDA||AGPIO150': CDS_PINID='\i3c2_sda||i2c2_sda||spd2_sda||agpio150\';
NODE_NAME     R28 1
 '@T6G_MB_LIB.T6G(SCH_1):PAGE28_I207@PURE_QUANTA.Q_RES(CHIPS)':
 'A': CDS_PINID='A';
NET_NAME
'SMB_CPU0_2_SCL'
 '@T6G_MB_LIB.T6G(SCH_1):SMB_CPU0_2_SCL':
 C_SIGNAL='@t6g_mb_lib.t6g(sch_1):smb_cpu0_2_scl';
NODE_NAME     R27 2
 '@T6G_MB_LIB.T6G(SCH_1):PAGE28_I206@PURE_QUANTA.Q_RES(CHIPS)':
 'B': CDS_PINID='B';
NODE_NAME     R6081 2
 '@T6G_MB_LIB.T6G(SCH_1):PAGE28_I210@PURE_QUANTA.Q_RES(CHIPS)':
 'B': CDS_PINID='B';
NET_NAME
'SMB_CPU0_2_SDA'
 '@T6G_MB_LIB.T6G(SCH_1):SMB_CPU0_2_SDA':
 C_SIGNAL='@t6g_mb_lib.t6g(sch_1):smb_cpu0_2_sda';
NODE_NAME     R28 2
 '@T6G_MB_LIB.T6G(SCH_1):PAGE28_I207@PURE_QUANTA.Q_RES(CHIPS)':
 'B': CDS_PINID='B';
NODE_NAME     R6082 2
 '@T6G_MB_LIB.T6G(SCH_1):PAGE28_I212@PURE_QUANTA.Q_RES(CHIPS)':
 'B': CDS_PINID='B';
NET_NAME
'SMB_CPU0_3_R_SCL'
 '@T6G_MB_LIB.T6G(SCH_1):SMB_CPU0_3_R_SCL':
 C_SIGNAL='@t6g_mb_lib.t6g(sch_1):smb_cpu0_3_r_scl';
NODE_NAME     U25 A4
 '@T6G_MB_LIB.T6G(SCH_1):PAGE28_I188@PURE_QUANTA.GENOA_SP5(CHIPS)':
 'I3C3_SCL||I2C3_SCL||SPD3_SCL||AGPIO151': CDS_PINID='\i3c3_scl||i2c3_scl||spd3_scl||agpio151\';
NODE_NAME     R29 1
 '@T6G_MB_LIB.T6G(SCH_1):PAGE28_I208@PURE_QUANTA.Q_RES(CHIPS)':
 'A': CDS_PINID='A';
NET_NAME
'SMB_CPU0_3_R_SDA'
 '@T6G_MB_LIB.T6G(SCH_1):SMB_CPU0_3_R_SDA':
 C_SIGNAL='@t6g_mb_lib.t6g(sch_1):smb_cpu0_3_r_sda';
NODE_NAME     U25 B4
 '@T6G_MB_LIB.T6G(SCH_1):PAGE28_I188@PURE_QUANTA.GENOA_SP5(CHIPS)':
 'I3C3_SDA||I2C3_SDA||SPD3_SDA||AGPIO152': CDS_PINID='\i3c3_sda||i2c3_sda||spd3_sda||agpio152\';
NODE_NAME     R30 1
 '@T6G_MB_LIB.T6G(SCH_1):PAGE28_I209@PURE_QUANTA.Q_RES(CHIPS)':
 'A': CDS_PINID='A';
NET_NAME
'SMB_CPU0_3_SCL'
 '@T6G_MB_LIB.T6G(SCH_1):SMB_CPU0_3_SCL':
 C_SIGNAL='@t6g_mb_lib.t6g(sch_1):smb_cpu0_3_scl';
NODE_NAME     R29 2
 '@T6G_MB_LIB.T6G(SCH_1):PAGE28_I208@PURE_QUANTA.Q_RES(CHIPS)':
 'B': CDS_PINID='B';
NODE_NAME     R6083 2
 '@T6G_MB_LIB.T6G(SCH_1):PAGE28_I213@PURE_QUANTA.Q_RES(CHIPS)':
 'B': CDS_PINID='B';
NET_NAME
'SMB_CPU0_3_SDA'
 '@T6G_MB_LIB.T6G(SCH_1):SMB_CPU0_3_SDA':
 C_SIGNAL='@t6g_mb_lib.t6g(sch_1):smb_cpu0_3_sda';
NODE_NAME     R30 2
 '@T6G_MB_LIB.T6G(SCH_1):PAGE28_I209@PURE_QUANTA.Q_RES(CHIPS)':
 'B': CDS_PINID='B';
NODE_NAME     R6084 2
 '@T6G_MB_LIB.T6G(SCH_1):PAGE28_I214@PURE_QUANTA.Q_RES(CHIPS)':
 'B': CDS_PINID='B';
NET_NAME
'SMB_CPU0_4_R_SCL'
 '@T6G_MB_LIB.T6G(SCH_1):SMB_CPU0_4_R_SCL':
 C_SIGNAL='@t6g_mb_lib.t6g(sch_1):smb_cpu0_4_r_scl';
NODE_NAME     R430 1
 '@T6G_MB_LIB.T6G(SCH_1):PAGE28_I98@PURE_QUANTA.Q_RES(CHIPS)':
 'A': CDS_PINID='A';
NODE_NAME     U25 DG12
 '@T6G_MB_LIB.T6G(SCH_1):PAGE28_I188@PURE_QUANTA.GENOA_SP5(CHIPS)':
 'I2C4_SCL||HP_SCL||UBM_SCL||AGPIO13': CDS_PINID='\i2c4_scl||hp_scl||ubm_scl||agpio13\';
NET_NAME
'SMB_CPU0_4_R_SDA'
 '@T6G_MB_LIB.T6G(SCH_1):SMB_CPU0_4_R_SDA':
 C_SIGNAL='@t6g_mb_lib.t6g(sch_1):smb_cpu0_4_r_sda';
NODE_NAME     R431 1
 '@T6G_MB_LIB.T6G(SCH_1):PAGE28_I97@PURE_QUANTA.Q_RES(CHIPS)':
 'A': CDS_PINID='A';
NODE_NAME     U25 DH12
 '@T6G_MB_LIB.T6G(SCH_1):PAGE28_I188@PURE_QUANTA.GENOA_SP5(CHIPS)':
 'I2C4_SDA||HP_SDA||UBM_SDA||AGPIO14': CDS_PINID='\i2c4_sda||hp_sda||ubm_sda||agpio14\';
NET_NAME
'SMB_CPU0_4_SCL'
 '@T6G_MB_LIB.T6G(SCH_1):SMB_CPU0_4_SCL':
 C_SIGNAL='@t6g_mb_lib.t6g(sch_1):smb_cpu0_4_scl';
NODE_NAME     U27 2
 '@T6G_MB_LIB.T6G(SCH_1):PAGE34_I18@PURE_QUANTA.PCA9617ADP(CHIPS)':
 'SCLA': CDS_PINID='SCLA';
NODE_NAME     R495 2
 '@T6G_MB_LIB.T6G(SCH_1):PAGE34_I106@PURE_QUANTA.Q_RES(CHIPS)':
 'B': CDS_PINID='B';
NODE_NAME     R430 2
 '@T6G_MB_LIB.T6G(SCH_1):PAGE28_I98@PURE_QUANTA.Q_RES(CHIPS)':
 'B': CDS_PINID='B';
NET_NAME
'SMB_CPU0_4_SDA'
 '@T6G_MB_LIB.T6G(SCH_1):SMB_CPU0_4_SDA':
 C_SIGNAL='@t6g_mb_lib.t6g(sch_1):smb_cpu0_4_sda';
NODE_NAME     U27 3
 '@T6G_MB_LIB.T6G(SCH_1):PAGE34_I18@PURE_QUANTA.PCA9617ADP(CHIPS)':
 'SDAA': CDS_PINID='SDAA';
NODE_NAME     R498 2
 '@T6G_MB_LIB.T6G(SCH_1):PAGE34_I107@PURE_QUANTA.Q_RES(CHIPS)':
 'B': CDS_PINID='B';
NODE_NAME     R431 2
 '@T6G_MB_LIB.T6G(SCH_1):PAGE28_I97@PURE_QUANTA.Q_RES(CHIPS)':
 'B': CDS_PINID='B';
NET_NAME
'SMB_CPU0_4_XLTR_R_SCL'
 '@T6G_MB_LIB.T6G(SCH_1):SMB_CPU0_4_XLTR_R_SCL':
 C_SIGNAL='@t6g_mb_lib.t6g(sch_1):smb_cpu0_4_xltr_r_scl';
NODE_NAME     R70 1
 '@T6G_MB_LIB.T6G(SCH_1):PAGE79_I19@PURE_QUANTA.Q_RES(CHIPS)':
 'A': CDS_PINID='A';
NODE_NAME     U18 G11
 '@T6G_MB_LIB.T6G(SCH_1):PAGE79_I94@PURE_QUANTA.LCMXO3LF9400C5BG484C(CHIPS)':
 'PT23C': CDS_PINID='PT23C';
NET_NAME
'SMB_CPU0_4_XLTR_R_SDA'
 '@T6G_MB_LIB.T6G(SCH_1):SMB_CPU0_4_XLTR_R_SDA':
 C_SIGNAL='@t6g_mb_lib.t6g(sch_1):smb_cpu0_4_xltr_r_sda';
NODE_NAME     R493 1
 '@T6G_MB_LIB.T6G(SCH_1):PAGE79_I18@PURE_QUANTA.Q_RES(CHIPS)':
 'A': CDS_PINID='A';
NODE_NAME     U18 F11
 '@T6G_MB_LIB.T6G(SCH_1):PAGE79_I94@PURE_QUANTA.LCMXO3LF9400C5BG484C(CHIPS)':
 'PT23D': CDS_PINID='PT23D';
NET_NAME
'SMB_CPU0_4_XLTR_SCL'
 '@T6G_MB_LIB.T6G(SCH_1):SMB_CPU0_4_XLTR_SCL':
 C_SIGNAL='@t6g_mb_lib.t6g(sch_1):smb_cpu0_4_xltr_scl';
NODE_NAME     R499 2
 '@T6G_MB_LIB.T6G(SCH_1):PAGE34_I4@PURE_QUANTA.Q_RES(CHIPS)':
 'B': CDS_PINID='B';
NODE_NAME     U27 7
 '@T6G_MB_LIB.T6G(SCH_1):PAGE34_I18@PURE_QUANTA.PCA9617ADP(CHIPS)':
 'SCLB': CDS_PINID='SCLB';
NODE_NAME     R70 2
 '@T6G_MB_LIB.T6G(SCH_1):PAGE79_I19@PURE_QUANTA.Q_RES(CHIPS)':
 'B': CDS_PINID='B';
NET_NAME
'SMB_CPU0_4_XLTR_SDA'
 '@T6G_MB_LIB.T6G(SCH_1):SMB_CPU0_4_XLTR_SDA':
 C_SIGNAL='@t6g_mb_lib.t6g(sch_1):smb_cpu0_4_xltr_sda';
NODE_NAME     R590 2
 '@T6G_MB_LIB.T6G(SCH_1):PAGE34_I5@PURE_QUANTA.Q_RES(CHIPS)':
 'B': CDS_PINID='B';
NODE_NAME     U27 6
 '@T6G_MB_LIB.T6G(SCH_1):PAGE34_I18@PURE_QUANTA.PCA9617ADP(CHIPS)':
 'SDAB': CDS_PINID='SDAB';
NODE_NAME     R493 2
 '@T6G_MB_LIB.T6G(SCH_1):PAGE79_I18@PURE_QUANTA.Q_RES(CHIPS)':
 'B': CDS_PINID='B';
NET_NAME
'SMB_CPU0_CPU1_APML_BUF1_SCL'
 '@T6G_MB_LIB.T6G(SCH_1):SMB_CPU0_CPU1_APML_BUF1_SCL':
 C_SIGNAL='@t6g_mb_lib.t6g(sch_1):smb_cpu0_cpu1_apml_buf1_scl';
NODE_NAME     U5 2
 '@T6G_MB_LIB.T6G(SCH_1):PAGE137_I48@PURE_QUANTA.PCA9617ADP(CHIPS)':
 'SCLA': CDS_PINID='SCLA';
NODE_NAME     R789 1
 '@T6G_MB_LIB.T6G(SCH_1):PAGE137_I96@PURE_QUANTA.Q_RES(CHIPS)':
 'A': CDS_PINID='A';
NODE_NAME     R140 2
 '@T6G_MB_LIB.T6G(SCH_1):PAGE137_I98@PURE_QUANTA.Q_RES(CHIPS)':
 'B': CDS_PINID='B';
NET_NAME
'SMB_CPU0_CPU1_APML_BUF1_SCL_R1'
 '@T6G_MB_LIB.T6G(SCH_1):SMB_CPU0_CPU1_APML_BUF1_SCL_R1':
 C_SIGNAL='@t6g_mb_lib.t6g(sch_1):smb_cpu0_cpu1_apml_buf1_scl_r1';
NODE_NAME     U5 7
 '@T6G_MB_LIB.T6G(SCH_1):PAGE137_I48@PURE_QUANTA.PCA9617ADP(CHIPS)':
 'SCLB': CDS_PINID='SCLB';
NODE_NAME     R1151 1
 '@T6G_MB_LIB.T6G(SCH_1):PAGE137_I93@PURE_QUANTA.Q_RES(CHIPS)':
 'A': CDS_PINID='A';
NODE_NAME     R789 2
 '@T6G_MB_LIB.T6G(SCH_1):PAGE137_I96@PURE_QUANTA.Q_RES(CHIPS)':
 'B': CDS_PINID='B';
NET_NAME
'SMB_CPU0_CPU1_APML_BUF1_SCL_R2'
 '@T6G_MB_LIB.T6G(SCH_1):SMB_CPU0_CPU1_APML_BUF1_SCL_R2':
 C_SIGNAL='@t6g_mb_lib.t6g(sch_1):smb_cpu0_cpu1_apml_buf1_scl_r2';
NODE_NAME     R361 2
 '@T6G_MB_LIB.T6G(SCH_1):PAGE137_I40@PURE_QUANTA.Q_RES(CHIPS)':
 'B': CDS_PINID='B';
NODE_NAME     R256 1
 '@T6G_MB_LIB.T6G(SCH_1):PAGE137_I92@PURE_QUANTA.Q_RES(CHIPS)':
 'A': CDS_PINID='A';
NODE_NAME     R1151 2
 '@T6G_MB_LIB.T6G(SCH_1):PAGE137_I93@PURE_QUANTA.Q_RES(CHIPS)':
 'B': CDS_PINID='B';
NET_NAME
'SMB_CPU0_CPU1_APML_BUF1_SDA'
 '@T6G_MB_LIB.T6G(SCH_1):SMB_CPU0_CPU1_APML_BUF1_SDA':
 C_SIGNAL='@t6g_mb_lib.t6g(sch_1):smb_cpu0_cpu1_apml_buf1_sda';
NODE_NAME     U5 3
 '@T6G_MB_LIB.T6G(SCH_1):PAGE137_I48@PURE_QUANTA.PCA9617ADP(CHIPS)':
 'SDAA': CDS_PINID='SDAA';
NODE_NAME     R790 1
 '@T6G_MB_LIB.T6G(SCH_1):PAGE137_I95@PURE_QUANTA.Q_RES(CHIPS)':
 'A': CDS_PINID='A';
NODE_NAME     R150 2
 '@T6G_MB_LIB.T6G(SCH_1):PAGE137_I97@PURE_QUANTA.Q_RES(CHIPS)':
 'B': CDS_PINID='B';
NET_NAME
'SMB_CPU0_CPU1_APML_BUF1_SDA_R1'
 '@T6G_MB_LIB.T6G(SCH_1):SMB_CPU0_CPU1_APML_BUF1_SDA_R1':
 C_SIGNAL='@t6g_mb_lib.t6g(sch_1):smb_cpu0_cpu1_apml_buf1_sda_r1';
NODE_NAME     U5 6
 '@T6G_MB_LIB.T6G(SCH_1):PAGE137_I48@PURE_QUANTA.PCA9617ADP(CHIPS)':
 'SDAB': CDS_PINID='SDAB';
NODE_NAME     R1152 1
 '@T6G_MB_LIB.T6G(SCH_1):PAGE137_I94@PURE_QUANTA.Q_RES(CHIPS)':
 'A': CDS_PINID='A';
NODE_NAME     R790 2
 '@T6G_MB_LIB.T6G(SCH_1):PAGE137_I95@PURE_QUANTA.Q_RES(CHIPS)':
 'B': CDS_PINID='B';
NET_NAME
'SMB_CPU0_CPU1_APML_BUF1_SDA_R2'
 '@T6G_MB_LIB.T6G(SCH_1):SMB_CPU0_CPU1_APML_BUF1_SDA_R2':
 C_SIGNAL='@t6g_mb_lib.t6g(sch_1):smb_cpu0_cpu1_apml_buf1_sda_r2';
NODE_NAME     R365 2
 '@T6G_MB_LIB.T6G(SCH_1):PAGE137_I41@PURE_QUANTA.Q_RES(CHIPS)':
 'B': CDS_PINID='B';
NODE_NAME     R257 1
 '@T6G_MB_LIB.T6G(SCH_1):PAGE137_I91@PURE_QUANTA.Q_RES(CHIPS)':
 'A': CDS_PINID='A';
NODE_NAME     R1152 2
 '@T6G_MB_LIB.T6G(SCH_1):PAGE137_I94@PURE_QUANTA.Q_RES(CHIPS)':
 'B': CDS_PINID='B';
NET_NAME
'SMB_CPU0_CPU1_APML_BUF2_SCL'
 '@T6G_MB_LIB.T6G(SCH_1):SMB_CPU0_CPU1_APML_BUF2_SCL':
 C_SIGNAL='@t6g_mb_lib.t6g(sch_1):smb_cpu0_cpu1_apml_buf2_scl';
NODE_NAME     R151 2
 '@T6G_MB_LIB.T6G(SCH_1):PAGE137_I79@PURE_QUANTA.Q_RES(CHIPS)':
 'B': CDS_PINID='B';
NODE_NAME     U2 7
 '@T6G_MB_LIB.T6G(SCH_1):PAGE137_I99@PURE_QUANTA.PCA9617ADP(CHIPS)':
 'SCLB': CDS_PINID='SCLB';
NET_NAME
'SMB_CPU0_CPU1_APML_BUF2_SCL_R1'
 '@T6G_MB_LIB.T6G(SCH_1):SMB_CPU0_CPU1_APML_BUF2_SCL_R1':
 C_SIGNAL='@t6g_mb_lib.t6g(sch_1):smb_cpu0_cpu1_apml_buf2_scl_r1';
NODE_NAME     R202 1
 '@T6G_MB_LIB.T6G(SCH_1):PAGE137_I67@PURE_QUANTA.Q_RES(CHIPS)':
 'A': CDS_PINID='A';
NODE_NAME     U2 2
 '@T6G_MB_LIB.T6G(SCH_1):PAGE137_I99@PURE_QUANTA.PCA9617ADP(CHIPS)':
 'SCLA': CDS_PINID='SCLA';
NET_NAME
'SMB_CPU0_CPU1_APML_BUF2_SCL_R2'
 '@T6G_MB_LIB.T6G(SCH_1):SMB_CPU0_CPU1_APML_BUF2_SCL_R2':
 C_SIGNAL='@t6g_mb_lib.t6g(sch_1):smb_cpu0_cpu1_apml_buf2_scl_r2';
NODE_NAME     R202 2
 '@T6G_MB_LIB.T6G(SCH_1):PAGE137_I67@PURE_QUANTA.Q_RES(CHIPS)':
 'B': CDS_PINID='B';
NODE_NAME     R274 1
 '@T6G_MB_LIB.T6G(SCH_1):PAGE137_I71@PURE_QUANTA.Q_RES(CHIPS)':
 'A': CDS_PINID='A';
NODE_NAME     R322 2
 '@T6G_MB_LIB.T6G(SCH_1):PAGE137_I73@PURE_QUANTA.Q_RES(CHIPS)':
 'B': CDS_PINID='B';
NET_NAME
'SMB_CPU0_CPU1_APML_BUF2_SDA'
 '@T6G_MB_LIB.T6G(SCH_1):SMB_CPU0_CPU1_APML_BUF2_SDA':
 C_SIGNAL='@t6g_mb_lib.t6g(sch_1):smb_cpu0_cpu1_apml_buf2_sda';
NODE_NAME     R162 2
 '@T6G_MB_LIB.T6G(SCH_1):PAGE137_I80@PURE_QUANTA.Q_RES(CHIPS)':
 'B': CDS_PINID='B';
NODE_NAME     U2 6
 '@T6G_MB_LIB.T6G(SCH_1):PAGE137_I99@PURE_QUANTA.PCA9617ADP(CHIPS)':
 'SDAB': CDS_PINID='SDAB';
NET_NAME
'SMB_CPU0_CPU1_APML_BUF2_SDA_R1'
 '@T6G_MB_LIB.T6G(SCH_1):SMB_CPU0_CPU1_APML_BUF2_SDA_R1':
 C_SIGNAL='@t6g_mb_lib.t6g(sch_1):smb_cpu0_cpu1_apml_buf2_sda_r1';
NODE_NAME     R206 1
 '@T6G_MB_LIB.T6G(SCH_1):PAGE137_I68@PURE_QUANTA.Q_RES(CHIPS)':
 'A': CDS_PINID='A';
NODE_NAME     U2 3
 '@T6G_MB_LIB.T6G(SCH_1):PAGE137_I99@PURE_QUANTA.PCA9617ADP(CHIPS)':
 'SDAA': CDS_PINID='SDAA';
NET_NAME
'SMB_CPU0_CPU1_APML_BUF2_SDA_R2'
 '@T6G_MB_LIB.T6G(SCH_1):SMB_CPU0_CPU1_APML_BUF2_SDA_R2':
 C_SIGNAL='@t6g_mb_lib.t6g(sch_1):smb_cpu0_cpu1_apml_buf2_sda_r2';
NODE_NAME     R206 2
 '@T6G_MB_LIB.T6G(SCH_1):PAGE137_I68@PURE_QUANTA.Q_RES(CHIPS)':
 'B': CDS_PINID='B';
NODE_NAME     R281 1
 '@T6G_MB_LIB.T6G(SCH_1):PAGE137_I72@PURE_QUANTA.Q_RES(CHIPS)':
 'A': CDS_PINID='A';
NODE_NAME     R290 2
 '@T6G_MB_LIB.T6G(SCH_1):PAGE137_I78@PURE_QUANTA.Q_RES(CHIPS)':
 'B': CDS_PINID='B';
NET_NAME
'SMB_CPU0_CPU1_APML_MUX1_SCL'
 '@T6G_MB_LIB.T6G(SCH_1):SMB_CPU0_CPU1_APML_MUX1_SCL':
 C_SIGNAL='@t6g_mb_lib.t6g(sch_1):smb_cpu0_cpu1_apml_mux1_scl';
NODE_NAME     R146 1
 '@T6G_MB_LIB.T6G(SCH_1):PAGE138_I17@PURE_QUANTA.Q_RES(CHIPS)':
 'A': CDS_PINID='A';
NODE_NAME     R142 1
 '@T6G_MB_LIB.T6G(SCH_1):PAGE138_I35@PURE_QUANTA.Q_RES(CHIPS)':
 'A': CDS_PINID='A';
NODE_NAME     R324 2
 '@T6G_MB_LIB.T6G(SCH_1):PAGE138_I110@PURE_QUANTA.Q_RES(CHIPS)':
 'B': CDS_PINID='B';
NODE_NAME     U213 3
 '@T6G_MB_LIB.T6G(SCH_1):PAGE138_I111@PURE_QUANTA.IML3112Y2B000NCG8(CHIPS)':
 'HSCL': CDS_PINID='HSCL';
NET_NAME
'SMB_CPU0_CPU1_APML_MUX1_SDA'
 '@T6G_MB_LIB.T6G(SCH_1):SMB_CPU0_CPU1_APML_MUX1_SDA':
 C_SIGNAL='@t6g_mb_lib.t6g(sch_1):smb_cpu0_cpu1_apml_mux1_sda';
NODE_NAME     R147 1
 '@T6G_MB_LIB.T6G(SCH_1):PAGE138_I16@PURE_QUANTA.Q_RES(CHIPS)':
 'A': CDS_PINID='A';
NODE_NAME     R143 1
 '@T6G_MB_LIB.T6G(SCH_1):PAGE138_I34@PURE_QUANTA.Q_RES(CHIPS)':
 'A': CDS_PINID='A';
NODE_NAME     R323 2
 '@T6G_MB_LIB.T6G(SCH_1):PAGE138_I109@PURE_QUANTA.Q_RES(CHIPS)':
 'B': CDS_PINID='B';
NODE_NAME     U213 2
 '@T6G_MB_LIB.T6G(SCH_1):PAGE138_I111@PURE_QUANTA.IML3112Y2B000NCG8(CHIPS)':
 'HSDA': CDS_PINID='HSDA';
NET_NAME
'SMB_CPU0_CPU1_APML_MUX2_SCL'
 '@T6G_MB_LIB.T6G(SCH_1):SMB_CPU0_CPU1_APML_MUX2_SCL':
 C_SIGNAL='@t6g_mb_lib.t6g(sch_1):smb_cpu0_cpu1_apml_mux2_scl';
NODE_NAME     R325 2
 '@T6G_MB_LIB.T6G(SCH_1):PAGE138_I99@PURE_QUANTA.Q_RES(CHIPS)':
 'B': CDS_PINID='B';
NODE_NAME     U4 8
 '@T6G_MB_LIB.T6G(SCH_1):PAGE138_I114@PURE_QUANTA.PI3CSW12ZUAEX(CHIPS)':
 'D+': CDS_PINID='\d+\';
NET_NAME
'SMB_CPU0_CPU1_APML_MUX2_SDA'
 '@T6G_MB_LIB.T6G(SCH_1):SMB_CPU0_CPU1_APML_MUX2_SDA':
 C_SIGNAL='@t6g_mb_lib.t6g(sch_1):smb_cpu0_cpu1_apml_mux2_sda';
NODE_NAME     R326 2
 '@T6G_MB_LIB.T6G(SCH_1):PAGE138_I100@PURE_QUANTA.Q_RES(CHIPS)':
 'B': CDS_PINID='B';
NODE_NAME     U4 7
 '@T6G_MB_LIB.T6G(SCH_1):PAGE138_I114@PURE_QUANTA.PI3CSW12ZUAEX(CHIPS)':
 'D-': CDS_PINID='\d-\';
NET_NAME
'SMB_CPU0_CPU1_APML_SCL'
 '@T6G_MB_LIB.T6G(SCH_1):SMB_CPU0_CPU1_APML_SCL':
 C_SIGNAL='@t6g_mb_lib.t6g(sch_1):smb_cpu0_cpu1_apml_scl';
NODE_NAME     R1319 1
 '@T6G_MB_LIB.T6G(SCH_1):PAGE349_I138@PURE_QUANTA.Q_RES(CHIPS)':
 'A': CDS_PINID='A';
NODE_NAME     R2419 1
 '@T6G_MB_LIB.T6G(SCH_1):PAGE348_I104@PURE_QUANTA.Q_RES(CHIPS)':
 'A': CDS_PINID='A';
NODE_NAME     R151 1
 '@T6G_MB_LIB.T6G(SCH_1):PAGE137_I79@PURE_QUANTA.Q_RES(CHIPS)':
 'A': CDS_PINID='A';
NODE_NAME     R140 1
 '@T6G_MB_LIB.T6G(SCH_1):PAGE137_I98@PURE_QUANTA.Q_RES(CHIPS)':
 'A': CDS_PINID='A';
NET_NAME
'SMB_CPU0_CPU1_APML_SCL_R'
 '@T6G_MB_LIB.T6G(SCH_1):SMB_CPU0_CPU1_APML_SCL_R':
 C_SIGNAL='@t6g_mb_lib.t6g(sch_1):smb_cpu0_cpu1_apml_scl_r';
NODE_NAME     J41 A3
 '@T6G_MB_LIB.T6G(SCH_1):PAGE348_I176@PURE_QUANTA.SCONN168_ME1016810202011(CHIPS)':
 'GND_A3': CDS_PINID='GND_A3';
NODE_NAME     R2419 2
 '@T6G_MB_LIB.T6G(SCH_1):PAGE348_I104@PURE_QUANTA.Q_RES(CHIPS)':
 'B': CDS_PINID='B';
NET_NAME
'SMB_CPU0_CPU1_APML_SCL_R2'
 '@T6G_MB_LIB.T6G(SCH_1):SMB_CPU0_CPU1_APML_SCL_R2':
 C_SIGNAL='@t6g_mb_lib.t6g(sch_1):smb_cpu0_cpu1_apml_scl_r2';
NODE_NAME     R325 1
 '@T6G_MB_LIB.T6G(SCH_1):PAGE138_I99@PURE_QUANTA.Q_RES(CHIPS)':
 'A': CDS_PINID='A';
NODE_NAME     R274 2
 '@T6G_MB_LIB.T6G(SCH_1):PAGE137_I71@PURE_QUANTA.Q_RES(CHIPS)':
 'B': CDS_PINID='B';
NODE_NAME     R324 1
 '@T6G_MB_LIB.T6G(SCH_1):PAGE138_I110@PURE_QUANTA.Q_RES(CHIPS)':
 'A': CDS_PINID='A';
NODE_NAME     R256 2
 '@T6G_MB_LIB.T6G(SCH_1):PAGE137_I92@PURE_QUANTA.Q_RES(CHIPS)':
 'B': CDS_PINID='B';
NET_NAME
'SMB_CPU0_CPU1_APML_SDA'
 '@T6G_MB_LIB.T6G(SCH_1):SMB_CPU0_CPU1_APML_SDA':
 C_SIGNAL='@t6g_mb_lib.t6g(sch_1):smb_cpu0_cpu1_apml_sda';
NODE_NAME     R3062 1
 '@T6G_MB_LIB.T6G(SCH_1):PAGE349_I137@PURE_QUANTA.Q_RES(CHIPS)':
 'A': CDS_PINID='A';
NODE_NAME     R2420 1
 '@T6G_MB_LIB.T6G(SCH_1):PAGE348_I105@PURE_QUANTA.Q_RES(CHIPS)':
 'A': CDS_PINID='A';
NODE_NAME     R162 1
 '@T6G_MB_LIB.T6G(SCH_1):PAGE137_I80@PURE_QUANTA.Q_RES(CHIPS)':
 'A': CDS_PINID='A';
NODE_NAME     R150 1
 '@T6G_MB_LIB.T6G(SCH_1):PAGE137_I97@PURE_QUANTA.Q_RES(CHIPS)':
 'A': CDS_PINID='A';
NET_NAME
'SMB_CPU0_CPU1_APML_SDA_R'
 '@T6G_MB_LIB.T6G(SCH_1):SMB_CPU0_CPU1_APML_SDA_R':
 C_SIGNAL='@t6g_mb_lib.t6g(sch_1):smb_cpu0_cpu1_apml_sda_r';
NODE_NAME     J41 A4
 '@T6G_MB_LIB.T6G(SCH_1):PAGE348_I176@PURE_QUANTA.SCONN168_ME1016810202011(CHIPS)':
 'GND_A4': CDS_PINID='GND_A4';
NODE_NAME     R2420 2
 '@T6G_MB_LIB.T6G(SCH_1):PAGE348_I105@PURE_QUANTA.Q_RES(CHIPS)':
 'B': CDS_PINID='B';
NET_NAME
'SMB_CPU0_CPU1_APML_SDA_R2'
 '@T6G_MB_LIB.T6G(SCH_1):SMB_CPU0_CPU1_APML_SDA_R2':
 C_SIGNAL='@t6g_mb_lib.t6g(sch_1):smb_cpu0_cpu1_apml_sda_r2';
NODE_NAME     R326 1
 '@T6G_MB_LIB.T6G(SCH_1):PAGE138_I100@PURE_QUANTA.Q_RES(CHIPS)':
 'A': CDS_PINID='A';
NODE_NAME     R281 2
 '@T6G_MB_LIB.T6G(SCH_1):PAGE137_I72@PURE_QUANTA.Q_RES(CHIPS)':
 'B': CDS_PINID='B';
NODE_NAME     R323 1
 '@T6G_MB_LIB.T6G(SCH_1):PAGE138_I109@PURE_QUANTA.Q_RES(CHIPS)':
 'A': CDS_PINID='A';
NODE_NAME     R257 2
 '@T6G_MB_LIB.T6G(SCH_1):PAGE137_I91@PURE_QUANTA.Q_RES(CHIPS)':
 'B': CDS_PINID='B';
NET_NAME
'SMB_CPU0_CPU1_SEC_SCL'
 '@T6G_MB_LIB.T6G(SCH_1):SMB_CPU0_CPU1_SEC_SCL':
 C_SIGNAL='@t6g_mb_lib.t6g(sch_1):smb_cpu0_cpu1_sec_scl';
NODE_NAME     R1384 1
 '@T6G_MB_LIB.T6G(SCH_1):PAGE349_I136@PURE_QUANTA.Q_RES(CHIPS)':
 'A': CDS_PINID='A';
NODE_NAME     R4506 1
 '@T6G_MB_LIB.T6G(SCH_1):PAGE348_I191@PURE_QUANTA.Q_RES(CHIPS)':
 'A': CDS_PINID='A';
NODE_NAME     U96 7
 '@T6G_MB_LIB.T6G(SCH_1):PAGE137_I51@PURE_QUANTA.PCA9617ADP(CHIPS)':
 'SCLB': CDS_PINID='SCLB';
NET_NAME
'SMB_CPU0_CPU1_SEC_SCL_R'
 '@T6G_MB_LIB.T6G(SCH_1):SMB_CPU0_CPU1_SEC_SCL_R':
 C_SIGNAL='@t6g_mb_lib.t6g(sch_1):smb_cpu0_cpu1_sec_scl_r';
NODE_NAME     J41 A7
 '@T6G_MB_LIB.T6G(SCH_1):PAGE348_I176@PURE_QUANTA.SCONN168_ME1016810202011(CHIPS)':
 'SMCLK': CDS_PINID='SMCLK';
NODE_NAME     R4506 2
 '@T6G_MB_LIB.T6G(SCH_1):PAGE348_I191@PURE_QUANTA.Q_RES(CHIPS)':
 'B': CDS_PINID='B';
NET_NAME
'SMB_CPU0_CPU1_SEC_SCL_R1'
 '@T6G_MB_LIB.T6G(SCH_1):SMB_CPU0_CPU1_SEC_SCL_R1':
 C_SIGNAL='@t6g_mb_lib.t6g(sch_1):smb_cpu0_cpu1_sec_scl_r1';
NODE_NAME     R1153 1
 '@T6G_MB_LIB.T6G(SCH_1):PAGE137_I16@PURE_QUANTA.Q_RES(CHIPS)':
 'A': CDS_PINID='A';
NODE_NAME     U96 2
 '@T6G_MB_LIB.T6G(SCH_1):PAGE137_I51@PURE_QUANTA.PCA9617ADP(CHIPS)':
 'SCLA': CDS_PINID='SCLA';
NET_NAME
'SMB_CPU0_CPU1_SEC_SCL_R2'
 '@T6G_MB_LIB.T6G(SCH_1):SMB_CPU0_CPU1_SEC_SCL_R2':
 C_SIGNAL='@t6g_mb_lib.t6g(sch_1):smb_cpu0_cpu1_sec_scl_r2';
NODE_NAME     R358 1
 '@T6G_MB_LIB.T6G(SCH_1):PAGE138_I5@PURE_QUANTA.Q_RES(CHIPS)':
 'A': CDS_PINID='A';
NODE_NAME     R145 1
 '@T6G_MB_LIB.T6G(SCH_1):PAGE138_I14@PURE_QUANTA.Q_RES(CHIPS)':
 'A': CDS_PINID='A';
NODE_NAME     R1153 2
 '@T6G_MB_LIB.T6G(SCH_1):PAGE137_I16@PURE_QUANTA.Q_RES(CHIPS)':
 'B': CDS_PINID='B';
NODE_NAME     R368 2
 '@T6G_MB_LIB.T6G(SCH_1):PAGE137_I44@PURE_QUANTA.Q_RES(CHIPS)':
 'B': CDS_PINID='B';
NODE_NAME     U6 8
 '@T6G_MB_LIB.T6G(SCH_1):PAGE138_I67@PURE_QUANTA.PI3CSW12ZUAEX(CHIPS)':
 'D+': CDS_PINID='\d+\';
NET_NAME
'SMB_CPU0_CPU1_SEC_SDA'
 '@T6G_MB_LIB.T6G(SCH_1):SMB_CPU0_CPU1_SEC_SDA':
 C_SIGNAL='@t6g_mb_lib.t6g(sch_1):smb_cpu0_cpu1_sec_sda';
NODE_NAME     R1385 1
 '@T6G_MB_LIB.T6G(SCH_1):PAGE349_I135@PURE_QUANTA.Q_RES(CHIPS)':
 'A': CDS_PINID='A';
NODE_NAME     R4507 1
 '@T6G_MB_LIB.T6G(SCH_1):PAGE348_I190@PURE_QUANTA.Q_RES(CHIPS)':
 'A': CDS_PINID='A';
NODE_NAME     U96 6
 '@T6G_MB_LIB.T6G(SCH_1):PAGE137_I51@PURE_QUANTA.PCA9617ADP(CHIPS)':
 'SDAB': CDS_PINID='SDAB';
NET_NAME
'SMB_CPU0_CPU1_SEC_SDA_R'
 '@T6G_MB_LIB.T6G(SCH_1):SMB_CPU0_CPU1_SEC_SDA_R':
 C_SIGNAL='@t6g_mb_lib.t6g(sch_1):smb_cpu0_cpu1_sec_sda_r';
NODE_NAME     J41 A8
 '@T6G_MB_LIB.T6G(SCH_1):PAGE348_I176@PURE_QUANTA.SCONN168_ME1016810202011(CHIPS)':
 'SMDAT': CDS_PINID='SMDAT';
NODE_NAME     R4507 2
 '@T6G_MB_LIB.T6G(SCH_1):PAGE348_I190@PURE_QUANTA.Q_RES(CHIPS)':
 'B': CDS_PINID='B';
NET_NAME
'SMB_CPU0_CPU1_SEC_SDA_R1'
 '@T6G_MB_LIB.T6G(SCH_1):SMB_CPU0_CPU1_SEC_SDA_R1':
 C_SIGNAL='@t6g_mb_lib.t6g(sch_1):smb_cpu0_cpu1_sec_sda_r1';
NODE_NAME     R1154 1
 '@T6G_MB_LIB.T6G(SCH_1):PAGE137_I15@PURE_QUANTA.Q_RES(CHIPS)':
 'A': CDS_PINID='A';
NODE_NAME     U96 3
 '@T6G_MB_LIB.T6G(SCH_1):PAGE137_I51@PURE_QUANTA.PCA9617ADP(CHIPS)':
 'SDAA': CDS_PINID='SDAA';
NET_NAME
'SMB_CPU0_CPU1_SEC_SDA_R2'
 '@T6G_MB_LIB.T6G(SCH_1):SMB_CPU0_CPU1_SEC_SDA_R2':
 C_SIGNAL='@t6g_mb_lib.t6g(sch_1):smb_cpu0_cpu1_sec_sda_r2';
NODE_NAME     R148 1
 '@T6G_MB_LIB.T6G(SCH_1):PAGE138_I6@PURE_QUANTA.Q_RES(CHIPS)':
 'A': CDS_PINID='A';
NODE_NAME     R144 1
 '@T6G_MB_LIB.T6G(SCH_1):PAGE138_I15@PURE_QUANTA.Q_RES(CHIPS)':
 'A': CDS_PINID='A';
NODE_NAME     R1154 2
 '@T6G_MB_LIB.T6G(SCH_1):PAGE137_I15@PURE_QUANTA.Q_RES(CHIPS)':
 'B': CDS_PINID='B';
NODE_NAME     R406 2
 '@T6G_MB_LIB.T6G(SCH_1):PAGE137_I46@PURE_QUANTA.Q_RES(CHIPS)':
 'B': CDS_PINID='B';
NODE_NAME     U6 7
 '@T6G_MB_LIB.T6G(SCH_1):PAGE138_I67@PURE_QUANTA.PI3CSW12ZUAEX(CHIPS)':
 'D-': CDS_PINID='\d-\';
NET_NAME
'SMB_CPU0_SEC_R_SCL'
 '@T6G_MB_LIB.T6G(SCH_1):SMB_CPU0_SEC_R_SCL':
 C_SIGNAL='@t6g_mb_lib.t6g(sch_1):smb_cpu0_sec_r_scl';
NODE_NAME     R145 2
 '@T6G_MB_LIB.T6G(SCH_1):PAGE138_I14@PURE_QUANTA.Q_RES(CHIPS)':
 'B': CDS_PINID='B';
NODE_NAME     U6 1
 '@T6G_MB_LIB.T6G(SCH_1):PAGE138_I67@PURE_QUANTA.PI3CSW12ZUAEX(CHIPS)':
 '1D+': CDS_PINID='\1d+\';
NODE_NAME     R1159 1
 '@T6G_MB_LIB.T6G(SCH_1):PAGE138_I76@PURE_QUANTA.Q_RES(CHIPS)':
 'A': CDS_PINID='A';
NET_NAME
'SMB_CPU0_SEC_R_SDA'
 '@T6G_MB_LIB.T6G(SCH_1):SMB_CPU0_SEC_R_SDA':
 C_SIGNAL='@t6g_mb_lib.t6g(sch_1):smb_cpu0_sec_r_sda';
NODE_NAME     R144 2
 '@T6G_MB_LIB.T6G(SCH_1):PAGE138_I15@PURE_QUANTA.Q_RES(CHIPS)':
 'B': CDS_PINID='B';
NODE_NAME     U6 2
 '@T6G_MB_LIB.T6G(SCH_1):PAGE138_I67@PURE_QUANTA.PI3CSW12ZUAEX(CHIPS)':
 '1D-': CDS_PINID='\1d-\';
NODE_NAME     R1160 1
 '@T6G_MB_LIB.T6G(SCH_1):PAGE138_I75@PURE_QUANTA.Q_RES(CHIPS)':
 'A': CDS_PINID='A';
NET_NAME
'SMB_CPU0_SEC_SCL'
 '@T6G_MB_LIB.T6G(SCH_1):SMB_CPU0_SEC_SCL':
 C_SIGNAL='@t6g_mb_lib.t6g(sch_1):smb_cpu0_sec_scl';
NODE_NAME     R367 2
 '@T6G_MB_LIB.T6G(SCH_1):PAGE138_I57@PURE_QUANTA.Q_RES(CHIPS)':
 'B': CDS_PINID='B';
NODE_NAME     U25 B14
 '@T6G_MB_LIB.T6G(SCH_1):PAGE28_I188@PURE_QUANTA.GENOA_SP5(CHIPS)':
 'SEC_SCL||AGPIO262': CDS_PINID='\sec_scl||agpio262\';
NODE_NAME     R1159 2
 '@T6G_MB_LIB.T6G(SCH_1):PAGE138_I76@PURE_QUANTA.Q_RES(CHIPS)':
 'B': CDS_PINID='B';
NET_NAME
'SMB_CPU0_SEC_SDA'
 '@T6G_MB_LIB.T6G(SCH_1):SMB_CPU0_SEC_SDA':
 C_SIGNAL='@t6g_mb_lib.t6g(sch_1):smb_cpu0_sec_sda';
NODE_NAME     R370 2
 '@T6G_MB_LIB.T6G(SCH_1):PAGE138_I60@PURE_QUANTA.Q_RES(CHIPS)':
 'B': CDS_PINID='B';
NODE_NAME     U25 D14
 '@T6G_MB_LIB.T6G(SCH_1):PAGE28_I188@PURE_QUANTA.GENOA_SP5(CHIPS)':
 'SEC_SDA||AGPIO263': CDS_PINID='\sec_sda||agpio263\';
NODE_NAME     R1160 2
 '@T6G_MB_LIB.T6G(SCH_1):PAGE138_I75@PURE_QUANTA.Q_RES(CHIPS)':
 'B': CDS_PINID='B';
NET_NAME
'SMB_CPU1_SEC_R_SCL'
 '@T6G_MB_LIB.T6G(SCH_1):SMB_CPU1_SEC_R_SCL':
 C_SIGNAL='@t6g_mb_lib.t6g(sch_1):smb_cpu1_sec_r_scl';
NODE_NAME     R358 2
 '@T6G_MB_LIB.T6G(SCH_1):PAGE138_I5@PURE_QUANTA.Q_RES(CHIPS)':
 'B': CDS_PINID='B';
NODE_NAME     R1161 1
 '@T6G_MB_LIB.T6G(SCH_1):PAGE138_I23@PURE_QUANTA.Q_RES(CHIPS)':
 'A': CDS_PINID='A';
NODE_NAME     U6 3
 '@T6G_MB_LIB.T6G(SCH_1):PAGE138_I67@PURE_QUANTA.PI3CSW12ZUAEX(CHIPS)':
 '2D+': CDS_PINID='\2d+\';
NET_NAME
'SMB_CPU1_SEC_R_SDA'
 '@T6G_MB_LIB.T6G(SCH_1):SMB_CPU1_SEC_R_SDA':
 C_SIGNAL='@t6g_mb_lib.t6g(sch_1):smb_cpu1_sec_r_sda';
NODE_NAME     R148 2
 '@T6G_MB_LIB.T6G(SCH_1):PAGE138_I6@PURE_QUANTA.Q_RES(CHIPS)':
 'B': CDS_PINID='B';
NODE_NAME     R1162 1
 '@T6G_MB_LIB.T6G(SCH_1):PAGE138_I22@PURE_QUANTA.Q_RES(CHIPS)':
 'A': CDS_PINID='A';
NODE_NAME     U6 4
 '@T6G_MB_LIB.T6G(SCH_1):PAGE138_I67@PURE_QUANTA.PI3CSW12ZUAEX(CHIPS)':
 '2D-': CDS_PINID='\2d-\';
NET_NAME
'SMB_CPU1_SEC_SCL'
 '@T6G_MB_LIB.T6G(SCH_1):SMB_CPU1_SEC_SCL':
 C_SIGNAL='@t6g_mb_lib.t6g(sch_1):smb_cpu1_sec_scl';
NODE_NAME     U26 B14
 '@T6G_MB_LIB.T6G(SCH_1):PAGE55_I182@PURE_QUANTA.GENOA_SP5(CHIPS)':
 'SEC_SCL||AGPIO262': CDS_PINID='\sec_scl||agpio262\';
NODE_NAME     R366 2
 '@T6G_MB_LIB.T6G(SCH_1):PAGE138_I54@PURE_QUANTA.Q_RES(CHIPS)':
 'B': CDS_PINID='B';
NODE_NAME     R1161 2
 '@T6G_MB_LIB.T6G(SCH_1):PAGE138_I23@PURE_QUANTA.Q_RES(CHIPS)':
 'B': CDS_PINID='B';
NET_NAME
'SMB_CPU1_SEC_SDA'
 '@T6G_MB_LIB.T6G(SCH_1):SMB_CPU1_SEC_SDA':
 C_SIGNAL='@t6g_mb_lib.t6g(sch_1):smb_cpu1_sec_sda';
NODE_NAME     U26 D14
 '@T6G_MB_LIB.T6G(SCH_1):PAGE55_I182@PURE_QUANTA.GENOA_SP5(CHIPS)':
 'SEC_SDA||AGPIO263': CDS_PINID='\sec_sda||agpio263\';
NODE_NAME     R369 2
 '@T6G_MB_LIB.T6G(SCH_1):PAGE138_I58@PURE_QUANTA.Q_RES(CHIPS)':
 'B': CDS_PINID='B';
NODE_NAME     R1162 2
 '@T6G_MB_LIB.T6G(SCH_1):PAGE138_I22@PURE_QUANTA.Q_RES(CHIPS)':
 'B': CDS_PINID='B';
NET_NAME
'SMB_CPU_5_R1_SCL'
 '@T6G_MB_LIB.T6G(SCH_1):SMB_CPU_5_R1_SCL':
 C_SIGNAL='@t6g_mb_lib.t6g(sch_1):smb_cpu_5_r1_scl';
NODE_NAME     R1447 2
 '@T6G_MB_LIB.T6G(SCH_1):PAGE349_I57@PURE_QUANTA.Q_RES(CHIPS)':
 'B': CDS_PINID='B';
NODE_NAME     U18 M20
 '@T6G_MB_LIB.T6G(SCH_1):PAGE80_I217@PURE_QUANTA.LCMXO3LF9400C5BG484C(CHIPS)':
 'PR17C': CDS_PINID='PR17C';
NET_NAME
'SMB_CPU_5_R1_SDA'
 '@T6G_MB_LIB.T6G(SCH_1):SMB_CPU_5_R1_SDA':
 C_SIGNAL='@t6g_mb_lib.t6g(sch_1):smb_cpu_5_r1_sda';
NODE_NAME     U18 M19
 '@T6G_MB_LIB.T6G(SCH_1):PAGE80_I217@PURE_QUANTA.LCMXO3LF9400C5BG484C(CHIPS)':
 'PR17D': CDS_PINID='PR17D';
NODE_NAME     R1453 2
 '@T6G_MB_LIB.T6G(SCH_1):PAGE349_I56@PURE_QUANTA.Q_RES(CHIPS)':
 'B': CDS_PINID='B';
NET_NAME
'SMB_CPU_5_R_SCL'
 '@T6G_MB_LIB.T6G(SCH_1):SMB_CPU_5_R_SCL':
 C_SIGNAL='@t6g_mb_lib.t6g(sch_1):smb_cpu_5_r_scl';
NODE_NAME     R212 1
 '@T6G_MB_LIB.T6G(SCH_1):PAGE28_I96@PURE_QUANTA.Q_RES(CHIPS)':
 'A': CDS_PINID='A';
NODE_NAME     U25 DJ21
 '@T6G_MB_LIB.T6G(SCH_1):PAGE28_I188@PURE_QUANTA.GENOA_SP5(CHIPS)':
 'I2C5_SCL||BMC_SCL||SMBUS1_SCL||AGPIO19': CDS_PINID='\i2c5_scl||bmc_scl||smbus1_scl||agpio19\';
NET_NAME
'SMB_CPU_5_R_SDA'
 '@T6G_MB_LIB.T6G(SCH_1):SMB_CPU_5_R_SDA':
 C_SIGNAL='@t6g_mb_lib.t6g(sch_1):smb_cpu_5_r_sda';
NODE_NAME     R213 1
 '@T6G_MB_LIB.T6G(SCH_1):PAGE28_I95@PURE_QUANTA.Q_RES(CHIPS)':
 'A': CDS_PINID='A';
NODE_NAME     U25 DJ20
 '@T6G_MB_LIB.T6G(SCH_1):PAGE28_I188@PURE_QUANTA.GENOA_SP5(CHIPS)':
 'I2C5_SDA||BMC_SDA||SMBUS1_SDA||AGPIO20': CDS_PINID='\i2c5_sda||bmc_sda||smbus1_sda||agpio20\';
NET_NAME
'SMB_CPU_5_SCL'
 '@T6G_MB_LIB.T6G(SCH_1):SMB_CPU_5_SCL':
 C_SIGNAL='@t6g_mb_lib.t6g(sch_1):smb_cpu_5_scl';
NODE_NAME     R1447 1
 '@T6G_MB_LIB.T6G(SCH_1):PAGE349_I57@PURE_QUANTA.Q_RES(CHIPS)':
 'A': CDS_PINID='A';
NODE_NAME     R212 2
 '@T6G_MB_LIB.T6G(SCH_1):PAGE28_I96@PURE_QUANTA.Q_RES(CHIPS)':
 'B': CDS_PINID='B';
NODE_NAME     R632 2
 '@T6G_MB_LIB.T6G(SCH_1):PAGE349_I18@PURE_QUANTA.Q_RES(CHIPS)':
 'B': CDS_PINID='B';
NET_NAME
'SMB_CPU_5_SDA'
 '@T6G_MB_LIB.T6G(SCH_1):SMB_CPU_5_SDA':
 C_SIGNAL='@t6g_mb_lib.t6g(sch_1):smb_cpu_5_sda';
NODE_NAME     R633 2
 '@T6G_MB_LIB.T6G(SCH_1):PAGE349_I17@PURE_QUANTA.Q_RES(CHIPS)':
 'B': CDS_PINID='B';
NODE_NAME     R1453 1
 '@T6G_MB_LIB.T6G(SCH_1):PAGE349_I56@PURE_QUANTA.Q_RES(CHIPS)':
 'A': CDS_PINID='A';
NODE_NAME     R213 2
 '@T6G_MB_LIB.T6G(SCH_1):PAGE28_I95@PURE_QUANTA.Q_RES(CHIPS)':
 'B': CDS_PINID='B';
NET_NAME
'SMB_CPU_FRU_3V3AUX_SCL'
 '@T6G_MB_LIB.T6G(SCH_1):SMB_CPU_FRU_3V3AUX_SCL':
 C_SIGNAL='@t6g_mb_lib.t6g(sch_1):smb_cpu_fru_3v3aux_scl';
NODE_NAME     R4 2
 '@T6G_MB_LIB.T6G(SCH_1):PAGE361_I114@PURE_QUANTA.Q_RES(CHIPS)':
 'B': CDS_PINID='B';
NODE_NAME     U1 6
 '@T6G_MB_LIB.T6G(SCH_1):PAGE361_I97@PURE_QUANTA.M24128BWMN6TP(CHIPS)':
 'SCL': CDS_PINID='SCL';
NODE_NAME     R121 2
 '@T6G_MB_LIB.T6G(SCH_1):PAGE361_I122@PURE_QUANTA.Q_RES(CHIPS)':
 'B': CDS_PINID='B';
NET_NAME
'SMB_CPU_FRU_3V3AUX_SDA'
 '@T6G_MB_LIB.T6G(SCH_1):SMB_CPU_FRU_3V3AUX_SDA':
 C_SIGNAL='@t6g_mb_lib.t6g(sch_1):smb_cpu_fru_3v3aux_sda';
NODE_NAME     R24 2
 '@T6G_MB_LIB.T6G(SCH_1):PAGE361_I113@PURE_QUANTA.Q_RES(CHIPS)':
 'B': CDS_PINID='B';
NODE_NAME     U1 5
 '@T6G_MB_LIB.T6G(SCH_1):PAGE361_I97@PURE_QUANTA.M24128BWMN6TP(CHIPS)':
 'SDA': CDS_PINID='SDA';
NODE_NAME     R125 2
 '@T6G_MB_LIB.T6G(SCH_1):PAGE361_I123@PURE_QUANTA.Q_RES(CHIPS)':
 'B': CDS_PINID='B';
NET_NAME
'SMB_DIO_PVDDCR_CPU1_P0_R'
 '@T6G_MB_LIB.T6G(SCH_1):SMB_DIO_PVDDCR_CPU1_P0_R':
 C_SIGNAL='@t6g_mb_lib.t6g(sch_1):smb_dio_pvddcr_cpu1_p0_r';
NODE_NAME     R8072 2
 '@T6G_MB_LIB.T6G(SCH_1):PAGE175_I82@PURE_QUANTA.Q_RES(CHIPS)':
 'B': CDS_PINID='B';
NODE_NAME     PU12 13
 '@T6G_MB_LIB.T6G(SCH_1):PAGE175_I128@PURE_QUANTA.RAA229620GNPHA0(CHIPS)':
 'PMSDA': CDS_PINID='PMSDA';
NET_NAME
'SMB_DIO_PVDDCR_CPU1_P1_R'
 '@T6G_MB_LIB.T6G(SCH_1):SMB_DIO_PVDDCR_CPU1_P1_R':
 C_SIGNAL='@t6g_mb_lib.t6g(sch_1):smb_dio_pvddcr_cpu1_p1_r';
NODE_NAME     R8249 2
 '@T6G_MB_LIB.T6G(SCH_1):PAGE192_I81@PURE_QUANTA.Q_RES(CHIPS)':
 'B': CDS_PINID='B';
NODE_NAME     PU34 13
 '@T6G_MB_LIB.T6G(SCH_1):PAGE192_I128@PURE_QUANTA.RAA229620GNPHA0(CHIPS)':
 'PMSDA': CDS_PINID='PMSDA';
NET_NAME
'SMB_E1S_3V3AUX_ISO_SCL'
 '@T6G_MB_LIB.T6G(SCH_1):SMB_E1S_3V3AUX_ISO_SCL':
 C_SIGNAL='@t6g_mb_lib.t6g(sch_1):smb_e1s_3v3aux_iso_scl';
NODE_NAME     R3533 2
 '@T6G_MB_LIB.T6G(SCH_1):PAGE346_I76@PURE_QUANTA.Q_RES(CHIPS)':
 'B': CDS_PINID='B';
NODE_NAME     J90 A7
 '@T6G_MB_LIB.T6G(SCH_1):PAGE297_I90@PURE_QUANTA.SCONN56_123276793(CHIPS)':
 'SMBCLK': CDS_PINID='SMBCLK';
NET_NAME
'SMB_E1S_3V3AUX_ISO_SCL_R'
 '@T6G_MB_LIB.T6G(SCH_1):SMB_E1S_3V3AUX_ISO_SCL_R':
 C_SIGNAL='@t6g_mb_lib.t6g(sch_1):smb_e1s_3v3aux_iso_scl_r';
NODE_NAME     R3533 1
 '@T6G_MB_LIB.T6G(SCH_1):PAGE346_I76@PURE_QUANTA.Q_RES(CHIPS)':
 'A': CDS_PINID='A';
NODE_NAME     R3530 2
 '@T6G_MB_LIB.T6G(SCH_1):PAGE346_I80@PURE_QUANTA.Q_RES(CHIPS)':
 'B': CDS_PINID='B';
NODE_NAME     U279 2
 '@T6G_MB_LIB.T6G(SCH_1):PAGE346_I93@PURE_QUANTA.PCA9617ADP(CHIPS)':
 'SCLA': CDS_PINID='SCLA';
NET_NAME
'SMB_E1S_3V3AUX_ISO_SDA'
 '@T6G_MB_LIB.T6G(SCH_1):SMB_E1S_3V3AUX_ISO_SDA':
 C_SIGNAL='@t6g_mb_lib.t6g(sch_1):smb_e1s_3v3aux_iso_sda';
NODE_NAME     R3534 2
 '@T6G_MB_LIB.T6G(SCH_1):PAGE346_I77@PURE_QUANTA.Q_RES(CHIPS)':
 'B': CDS_PINID='B';
NODE_NAME     J90 A8
 '@T6G_MB_LIB.T6G(SCH_1):PAGE297_I90@PURE_QUANTA.SCONN56_123276793(CHIPS)':
 'SMBDAT': CDS_PINID='SMBDAT';
NET_NAME
'SMB_E1S_3V3AUX_ISO_SDA_R'
 '@T6G_MB_LIB.T6G(SCH_1):SMB_E1S_3V3AUX_ISO_SDA_R':
 C_SIGNAL='@t6g_mb_lib.t6g(sch_1):smb_e1s_3v3aux_iso_sda_r';
NODE_NAME     R3534 1
 '@T6G_MB_LIB.T6G(SCH_1):PAGE346_I77@PURE_QUANTA.Q_RES(CHIPS)':
 'A': CDS_PINID='A';
NODE_NAME     R3532 2
 '@T6G_MB_LIB.T6G(SCH_1):PAGE346_I78@PURE_QUANTA.Q_RES(CHIPS)':
 'B': CDS_PINID='B';
NODE_NAME     U279 3
 '@T6G_MB_LIB.T6G(SCH_1):PAGE346_I93@PURE_QUANTA.PCA9617ADP(CHIPS)':
 'SDAA': CDS_PINID='SDAA';
NET_NAME
'SMB_FAN_3V3AUX_BUF_R_SCL'
 '@T6G_MB_LIB.T6G(SCH_1):SMB_FAN_3V3AUX_BUF_R_SCL':
 C_SIGNAL='@t6g_mb_lib.t6g(sch_1):smb_fan_3v3aux_buf_r_scl';
NODE_NAME     R2811 2
 '@T6G_MB_LIB.T6G(SCH_1):PAGE363_I425@PURE_QUANTA.Q_RES(CHIPS)':
 'B': CDS_PINID='B';
NODE_NAME     J45 C1
 '@T6G_MB_LIB.T6G(SCH_1):PAGE363_I466@PURE_QUANTA.CONN60_101062636003K02LF(CHIPS)':
 'C1': CDS_PINID='C1';
NET_NAME
'SMB_FAN_3V3AUX_BUF_R_SDA'
 '@T6G_MB_LIB.T6G(SCH_1):SMB_FAN_3V3AUX_BUF_R_SDA':
 C_SIGNAL='@t6g_mb_lib.t6g(sch_1):smb_fan_3v3aux_buf_r_sda';
NODE_NAME     R2812 2
 '@T6G_MB_LIB.T6G(SCH_1):PAGE363_I426@PURE_QUANTA.Q_RES(CHIPS)':
 'B': CDS_PINID='B';
NODE_NAME     J45 C2
 '@T6G_MB_LIB.T6G(SCH_1):PAGE363_I466@PURE_QUANTA.CONN60_101062636003K02LF(CHIPS)':
 'C2': CDS_PINID='C2';
NET_NAME
'SMB_FAN_3V3AUX_BUF_SCL'
 '@T6G_MB_LIB.T6G(SCH_1):SMB_FAN_3V3AUX_BUF_SCL':
 C_SIGNAL='@t6g_mb_lib.t6g(sch_1):smb_fan_3v3aux_buf_scl';
NODE_NAME     U192 2
 '@T6G_MB_LIB.T6G(SCH_1):PAGE363_I398@PURE_QUANTA.LTC4307CMS8(CHIPS)':
 'SCL_OUT': CDS_PINID='SCL_OUT';
NODE_NAME     R2811 1
 '@T6G_MB_LIB.T6G(SCH_1):PAGE363_I425@PURE_QUANTA.Q_RES(CHIPS)':
 'A': CDS_PINID='A';
NODE_NAME     R2800 2
 '@T6G_MB_LIB.T6G(SCH_1):PAGE363_I429@PURE_QUANTA.Q_RES(CHIPS)':
 'B': CDS_PINID='B';
NODE_NAME     R2805 2
 '@T6G_MB_LIB.T6G(SCH_1):PAGE363_I436@PURE_QUANTA.Q_RES(CHIPS)':
 'B': CDS_PINID='B';
NET_NAME
'SMB_FAN_3V3AUX_BUF_SDA'
 '@T6G_MB_LIB.T6G(SCH_1):SMB_FAN_3V3AUX_BUF_SDA':
 C_SIGNAL='@t6g_mb_lib.t6g(sch_1):smb_fan_3v3aux_buf_sda';
NODE_NAME     U192 7
 '@T6G_MB_LIB.T6G(SCH_1):PAGE363_I398@PURE_QUANTA.LTC4307CMS8(CHIPS)':
 'SDA_OUT': CDS_PINID='SDA_OUT';
NODE_NAME     R2812 1
 '@T6G_MB_LIB.T6G(SCH_1):PAGE363_I426@PURE_QUANTA.Q_RES(CHIPS)':
 'A': CDS_PINID='A';
NODE_NAME     R2801 2
 '@T6G_MB_LIB.T6G(SCH_1):PAGE363_I430@PURE_QUANTA.Q_RES(CHIPS)':
 'B': CDS_PINID='B';
NODE_NAME     R2807 2
 '@T6G_MB_LIB.T6G(SCH_1):PAGE363_I438@PURE_QUANTA.Q_RES(CHIPS)':
 'B': CDS_PINID='B';
NET_NAME
'SMB_FAN_3V3AUX_R_SCL'
 '@T6G_MB_LIB.T6G(SCH_1):SMB_FAN_3V3AUX_R_SCL':
 C_SIGNAL='@t6g_mb_lib.t6g(sch_1):smb_fan_3v3aux_r_scl';
NODE_NAME     U192 3
 '@T6G_MB_LIB.T6G(SCH_1):PAGE363_I398@PURE_QUANTA.LTC4307CMS8(CHIPS)':
 'SCL_IN': CDS_PINID='SCL_IN';
NODE_NAME     R2800 1
 '@T6G_MB_LIB.T6G(SCH_1):PAGE363_I429@PURE_QUANTA.Q_RES(CHIPS)':
 'A': CDS_PINID='A';
NODE_NAME     R3113 2
 '@T6G_MB_LIB.T6G(SCH_1):PAGE363_I463@PURE_QUANTA.Q_RES(CHIPS)':
 'B': CDS_PINID='B';
NET_NAME
'SMB_FAN_3V3AUX_R_SDA'
 '@T6G_MB_LIB.T6G(SCH_1):SMB_FAN_3V3AUX_R_SDA':
 C_SIGNAL='@t6g_mb_lib.t6g(sch_1):smb_fan_3v3aux_r_sda';
NODE_NAME     U192 6
 '@T6G_MB_LIB.T6G(SCH_1):PAGE363_I398@PURE_QUANTA.LTC4307CMS8(CHIPS)':
 'SDA_IN': CDS_PINID='SDA_IN';
NODE_NAME     R2801 1
 '@T6G_MB_LIB.T6G(SCH_1):PAGE363_I430@PURE_QUANTA.Q_RES(CHIPS)':
 'A': CDS_PINID='A';
NODE_NAME     R3114 2
 '@T6G_MB_LIB.T6G(SCH_1):PAGE363_I464@PURE_QUANTA.Q_RES(CHIPS)':
 'B': CDS_PINID='B';
NET_NAME
'SMB_FAN_3V3AUX_SCL'
 '@T6G_MB_LIB.T6G(SCH_1):SMB_FAN_3V3AUX_SCL':
 C_SIGNAL='@t6g_mb_lib.t6g(sch_1):smb_fan_3v3aux_scl';
NODE_NAME     R3113 1
 '@T6G_MB_LIB.T6G(SCH_1):PAGE363_I463@PURE_QUANTA.Q_RES(CHIPS)':
 'A': CDS_PINID='A';
NODE_NAME     J41 A29
 '@T6G_MB_LIB.T6G(SCH_1):PAGE348_I176@PURE_QUANTA.SCONN168_ME1016810202011(CHIPS)':
 'GND_A29': CDS_PINID='GND_A29';
NODE_NAME     R330 1
 '@T6G_MB_LIB.T6G(SCH_1):PAGE349_I130@PURE_QUANTA.Q_RES(CHIPS)':
 'A': CDS_PINID='A';
NET_NAME
'SMB_FAN_3V3AUX_SDA'
 '@T6G_MB_LIB.T6G(SCH_1):SMB_FAN_3V3AUX_SDA':
 C_SIGNAL='@t6g_mb_lib.t6g(sch_1):smb_fan_3v3aux_sda';
NODE_NAME     R3114 1
 '@T6G_MB_LIB.T6G(SCH_1):PAGE363_I464@PURE_QUANTA.Q_RES(CHIPS)':
 'A': CDS_PINID='A';
NODE_NAME     J41 A30
 '@T6G_MB_LIB.T6G(SCH_1):PAGE348_I176@PURE_QUANTA.SCONN168_ME1016810202011(CHIPS)':
 'PERN4': CDS_PINID='PERN4';
NODE_NAME     R331 1
 '@T6G_MB_LIB.T6G(SCH_1):PAGE349_I129@PURE_QUANTA.Q_RES(CHIPS)':
 'A': CDS_PINID='A';
NET_NAME
'SMB_FRU_3V3AUX_R1_SCL'
 '@T6G_MB_LIB.T6G(SCH_1):SMB_FRU_3V3AUX_R1_SCL':
 C_SIGNAL='@t6g_mb_lib.t6g(sch_1):smb_fru_3v3aux_r1_scl';
NODE_NAME     U64 6
 '@T6G_MB_LIB.T6G(SCH_1):PAGE361_I35@PURE_QUANTA.M24128BWMN6TP(CHIPS)':
 'SCL': CDS_PINID='SCL';
NODE_NAME     R26 2
 '@T6G_MB_LIB.T6G(SCH_1):PAGE361_I95@PURE_QUANTA.Q_RES(CHIPS)':
 'B': CDS_PINID='B';
NODE_NAME     R85 2
 '@T6G_MB_LIB.T6G(SCH_1):PAGE361_I124@PURE_QUANTA.Q_RES(CHIPS)':
 'B': CDS_PINID='B';
NET_NAME
'SMB_FRU_3V3AUX_R1_SDA'
 '@T6G_MB_LIB.T6G(SCH_1):SMB_FRU_3V3AUX_R1_SDA':
 C_SIGNAL='@t6g_mb_lib.t6g(sch_1):smb_fru_3v3aux_r1_sda';
NODE_NAME     U64 5
 '@T6G_MB_LIB.T6G(SCH_1):PAGE361_I35@PURE_QUANTA.M24128BWMN6TP(CHIPS)':
 'SDA': CDS_PINID='SDA';
NODE_NAME     R43 2
 '@T6G_MB_LIB.T6G(SCH_1):PAGE361_I93@PURE_QUANTA.Q_RES(CHIPS)':
 'B': CDS_PINID='B';
NODE_NAME     R86 2
 '@T6G_MB_LIB.T6G(SCH_1):PAGE361_I125@PURE_QUANTA.Q_RES(CHIPS)':
 'B': CDS_PINID='B';
NET_NAME
'SMB_FRU_3V3AUX_SCL'
 '@T6G_MB_LIB.T6G(SCH_1):SMB_FRU_3V3AUX_SCL':
 C_SIGNAL='@t6g_mb_lib.t6g(sch_1):smb_fru_3v3aux_scl';
NODE_NAME     R66 2
 '@T6G_MB_LIB.T6G(SCH_1):PAGE252_I40@PURE_QUANTA.Q_RES(CHIPS)':
 'B': CDS_PINID='B';
NODE_NAME     R2565 2
 '@T6G_MB_LIB.T6G(SCH_1):PAGE252_I67@PURE_QUANTA.Q_RES(CHIPS)':
 'B': CDS_PINID='B';
NODE_NAME     R121 1
 '@T6G_MB_LIB.T6G(SCH_1):PAGE361_I122@PURE_QUANTA.Q_RES(CHIPS)':
 'A': CDS_PINID='A';
NODE_NAME     R85 1
 '@T6G_MB_LIB.T6G(SCH_1):PAGE361_I124@PURE_QUANTA.Q_RES(CHIPS)':
 'A': CDS_PINID='A';
NET_NAME
'SMB_FRU_3V3AUX_SCL_R'
 '@T6G_MB_LIB.T6G(SCH_1):SMB_FRU_3V3AUX_SCL_R':
 C_SIGNAL='@t6g_mb_lib.t6g(sch_1):smb_fru_3v3aux_scl_r';
NODE_NAME     U36 16
 '@T6G_MB_LIB.T6G(SCH_1):PAGE252_I33@PURE_QUANTA.TCA9548APWR(CHIPS)':
 'SC5': CDS_PINID='SC5';
NODE_NAME     R2565 1
 '@T6G_MB_LIB.T6G(SCH_1):PAGE252_I67@PURE_QUANTA.Q_RES(CHIPS)':
 'A': CDS_PINID='A';
NET_NAME
'SMB_FRU_3V3AUX_SDA'
 '@T6G_MB_LIB.T6G(SCH_1):SMB_FRU_3V3AUX_SDA':
 C_SIGNAL='@t6g_mb_lib.t6g(sch_1):smb_fru_3v3aux_sda';
NODE_NAME     R67 2
 '@T6G_MB_LIB.T6G(SCH_1):PAGE252_I39@PURE_QUANTA.Q_RES(CHIPS)':
 'B': CDS_PINID='B';
NODE_NAME     R2566 2
 '@T6G_MB_LIB.T6G(SCH_1):PAGE252_I72@PURE_QUANTA.Q_RES(CHIPS)':
 'B': CDS_PINID='B';
NODE_NAME     R125 1
 '@T6G_MB_LIB.T6G(SCH_1):PAGE361_I123@PURE_QUANTA.Q_RES(CHIPS)':
 'A': CDS_PINID='A';
NODE_NAME     R86 1
 '@T6G_MB_LIB.T6G(SCH_1):PAGE361_I125@PURE_QUANTA.Q_RES(CHIPS)':
 'A': CDS_PINID='A';
NET_NAME
'SMB_FRU_3V3AUX_SDA_R'
 '@T6G_MB_LIB.T6G(SCH_1):SMB_FRU_3V3AUX_SDA_R':
 C_SIGNAL='@t6g_mb_lib.t6g(sch_1):smb_fru_3v3aux_sda_r';
NODE_NAME     U36 15
 '@T6G_MB_LIB.T6G(SCH_1):PAGE252_I33@PURE_QUANTA.TCA9548APWR(CHIPS)':
 'SD5': CDS_PINID='SD5';
NODE_NAME     R2566 1
 '@T6G_MB_LIB.T6G(SCH_1):PAGE252_I72@PURE_QUANTA.Q_RES(CHIPS)':
 'A': CDS_PINID='A';
NET_NAME
'SMB_HOST_CLK_3V3AUX_SCL'
 '@T6G_MB_LIB.T6G(SCH_1):SMB_HOST_CLK_3V3AUX_SCL':
 C_SIGNAL='@t6g_mb_lib.t6g(sch_1):smb_host_clk_3v3aux_scl';
NODE_NAME     R2212 1
 '@T6G_MB_LIB.T6G(SCH_1):PAGE349_I126@PURE_QUANTA.Q_RES(CHIPS)':
 'A': CDS_PINID='A';
NODE_NAME     R2417 1
 '@T6G_MB_LIB.T6G(SCH_1):PAGE348_I35@PURE_QUANTA.Q_RES(CHIPS)':
 'A': CDS_PINID='A';
NODE_NAME     R3340 1
 '@T6G_MB_LIB.T6G(SCH_1):PAGE349_I81@PURE_QUANTA.Q_RES(CHIPS)':
 'A': CDS_PINID='A';
NODE_NAME     R1516 1
 '@T6G_MB_LIB.T6G(SCH_1):PAGE349_I222@PURE_QUANTA.Q_RES(CHIPS)':
 'A': CDS_PINID='A';
NET_NAME
'SMB_HOST_CLK_3V3AUX_SCL_R0'
 '@T6G_MB_LIB.T6G(SCH_1):SMB_HOST_CLK_3V3AUX_SCL_R0':
 C_SIGNAL='@t6g_mb_lib.t6g(sch_1):smb_host_clk_3v3aux_scl_r0';
NODE_NAME     J41 A40
 '@T6G_MB_LIB.T6G(SCH_1):PAGE348_I176@PURE_QUANTA.SCONN168_ME1016810202011(CHIPS)':
 'PERP7': CDS_PINID='PERP7';
NODE_NAME     R2417 2
 '@T6G_MB_LIB.T6G(SCH_1):PAGE348_I35@PURE_QUANTA.Q_RES(CHIPS)':
 'B': CDS_PINID='B';
NET_NAME
'SMB_HOST_CLK_3V3AUX_SCL_R1'
 '@T6G_MB_LIB.T6G(SCH_1):SMB_HOST_CLK_3V3AUX_SCL_R1':
 C_SIGNAL='@t6g_mb_lib.t6g(sch_1):smb_host_clk_3v3aux_scl_r1';
NODE_NAME     R6862 1
 '@T6G_MB_LIB.T6G(SCH_1):PAGE349_I218@PURE_QUANTA.Q_RES(CHIPS)':
 'A': CDS_PINID='A';
NODE_NAME     R6864 1
 '@T6G_MB_LIB.T6G(SCH_1):PAGE349_I220@PURE_QUANTA.Q_RES(CHIPS)':
 'A': CDS_PINID='A';
NODE_NAME     R1516 2
 '@T6G_MB_LIB.T6G(SCH_1):PAGE349_I222@PURE_QUANTA.Q_RES(CHIPS)':
 'B': CDS_PINID='B';
NODE_NAME     R6782 2
 '@T6G_MB_LIB.T6G(SCH_1):PAGE349_I228@PURE_QUANTA.Q_RES(CHIPS)':
 'B': CDS_PINID='B';
NET_NAME
'SMB_HOST_CLK_3V3AUX_SDA'
 '@T6G_MB_LIB.T6G(SCH_1):SMB_HOST_CLK_3V3AUX_SDA':
 C_SIGNAL='@t6g_mb_lib.t6g(sch_1):smb_host_clk_3v3aux_sda';
NODE_NAME     R2213 1
 '@T6G_MB_LIB.T6G(SCH_1):PAGE349_I125@PURE_QUANTA.Q_RES(CHIPS)':
 'A': CDS_PINID='A';
NODE_NAME     R2418 1
 '@T6G_MB_LIB.T6G(SCH_1):PAGE348_I34@PURE_QUANTA.Q_RES(CHIPS)':
 'A': CDS_PINID='A';
NODE_NAME     R3341 1
 '@T6G_MB_LIB.T6G(SCH_1):PAGE349_I82@PURE_QUANTA.Q_RES(CHIPS)':
 'A': CDS_PINID='A';
NODE_NAME     R1517 1
 '@T6G_MB_LIB.T6G(SCH_1):PAGE349_I223@PURE_QUANTA.Q_RES(CHIPS)':
 'A': CDS_PINID='A';
NET_NAME
'SMB_HOST_CLK_3V3AUX_SDA_R0'
 '@T6G_MB_LIB.T6G(SCH_1):SMB_HOST_CLK_3V3AUX_SDA_R0':
 C_SIGNAL='@t6g_mb_lib.t6g(sch_1):smb_host_clk_3v3aux_sda_r0';
NODE_NAME     J41 A41
 '@T6G_MB_LIB.T6G(SCH_1):PAGE348_I176@PURE_QUANTA.SCONN168_ME1016810202011(CHIPS)':
 'GND_A41': CDS_PINID='GND_A41';
NODE_NAME     R2418 2
 '@T6G_MB_LIB.T6G(SCH_1):PAGE348_I34@PURE_QUANTA.Q_RES(CHIPS)':
 'B': CDS_PINID='B';
NET_NAME
'SMB_HOST_CLK_3V3AUX_SDA_R1'
 '@T6G_MB_LIB.T6G(SCH_1):SMB_HOST_CLK_3V3AUX_SDA_R1':
 C_SIGNAL='@t6g_mb_lib.t6g(sch_1):smb_host_clk_3v3aux_sda_r1';
NODE_NAME     R6863 1
 '@T6G_MB_LIB.T6G(SCH_1):PAGE349_I219@PURE_QUANTA.Q_RES(CHIPS)':
 'A': CDS_PINID='A';
NODE_NAME     R6865 1
 '@T6G_MB_LIB.T6G(SCH_1):PAGE349_I221@PURE_QUANTA.Q_RES(CHIPS)':
 'A': CDS_PINID='A';
NODE_NAME     R1517 2
 '@T6G_MB_LIB.T6G(SCH_1):PAGE349_I223@PURE_QUANTA.Q_RES(CHIPS)':
 'B': CDS_PINID='B';
NODE_NAME     R6783 2
 '@T6G_MB_LIB.T6G(SCH_1):PAGE349_I229@PURE_QUANTA.Q_RES(CHIPS)':
 'B': CDS_PINID='B';
NET_NAME
'SMB_HOST_CLK_GEN2_3V3AUX_SCL'
 '@T6G_MB_LIB.T6G(SCH_1):SMB_HOST_CLK_GEN2_3V3AUX_SCL':
 C_SIGNAL='@t6g_mb_lib.t6g(sch_1):smb_host_clk_gen2_3v3aux_scl';
NODE_NAME     R3340 2
 '@T6G_MB_LIB.T6G(SCH_1):PAGE349_I81@PURE_QUANTA.Q_RES(CHIPS)':
 'B': CDS_PINID='B';
NODE_NAME     U247 8
 '@T6G_MB_LIB.T6G(SCH_1):PAGE232_I77@PURE_QUANTA.9FGL0251DKILFT(CHIPS)':
 'SCLK_3.3': CDS_PINID='\sclk_3.3\';
NET_NAME
'SMB_HOST_CLK_GEN2_3V3AUX_SDA'
 '@T6G_MB_LIB.T6G(SCH_1):SMB_HOST_CLK_GEN2_3V3AUX_SDA':
 C_SIGNAL='@t6g_mb_lib.t6g(sch_1):smb_host_clk_gen2_3v3aux_sda';
NODE_NAME     R3341 2
 '@T6G_MB_LIB.T6G(SCH_1):PAGE349_I82@PURE_QUANTA.Q_RES(CHIPS)':
 'B': CDS_PINID='B';
NODE_NAME     U247 9
 '@T6G_MB_LIB.T6G(SCH_1):PAGE232_I77@PURE_QUANTA.9FGL0251DKILFT(CHIPS)':
 'SDATA_3.3': CDS_PINID='\sdata_3.3\';
NET_NAME
'SMB_HSC_TYPE_ADC_SCL'
 '@T6G_MB_LIB.T6G(SCH_1):SMB_HSC_TYPE_ADC_SCL':
 C_SIGNAL='@t6g_mb_lib.t6g(sch_1):smb_hsc_type_adc_scl';
NODE_NAME     R6252 2
 '@T6G_MB_LIB.T6G(SCH_1):PAGE271_I9@PURE_QUANTA.Q_RES(CHIPS)':
 'B': CDS_PINID='B';
NODE_NAME     U6005 5
 '@T6G_MB_LIB.T6G(SCH_1):PAGE271_I28@PURE_QUANTA.ISL28022FRZT(CHIPS)':
 'SCL|||SMBCLK': CDS_PINID='\scl|||smbclk\';
NET_NAME
'SMB_HSC_TYPE_ADC_SDA'
 '@T6G_MB_LIB.T6G(SCH_1):SMB_HSC_TYPE_ADC_SDA':
 C_SIGNAL='@t6g_mb_lib.t6g(sch_1):smb_hsc_type_adc_sda';
NODE_NAME     R6253 2
 '@T6G_MB_LIB.T6G(SCH_1):PAGE271_I10@PURE_QUANTA.Q_RES(CHIPS)':
 'B': CDS_PINID='B';
NODE_NAME     U6005 4
 '@T6G_MB_LIB.T6G(SCH_1):PAGE271_I28@PURE_QUANTA.ISL28022FRZT(CHIPS)':
 'SDA||SMBDAT': CDS_PINID='\sda||smbdat\';
NODE_NAME     R6254 2
 '@T6G_MB_LIB.T6G(SCH_1):PAGE271_I29@PURE_QUANTA.Q_RES(CHIPS)':
 'B': CDS_PINID='B';
NET_NAME
'SMB_INA230_1_3V3AUX_SCL_R'
 '@T6G_MB_LIB.T6G(SCH_1):SMB_INA230_1_3V3AUX_SCL_R':
 C_SIGNAL='@t6g_mb_lib.t6g(sch_1):smb_ina230_1_3v3aux_scl_r';
NODE_NAME     R3586 2
 '@T6G_MB_LIB.T6G(SCH_1):PAGE253_I12@PURE_QUANTA.Q_RES(CHIPS)':
 'B': CDS_PINID='B';
NODE_NAME     R3600 1
 '@T6G_MB_LIB.T6G(SCH_1):PAGE295_I152@PURE_QUANTA.Q_RES(CHIPS)':
 'A': CDS_PINID='A';
NET_NAME
'SMB_INA230_1_3V3AUX_SCL_R1'
 '@T6G_MB_LIB.T6G(SCH_1):SMB_INA230_1_3V3AUX_SCL_R1':
 C_SIGNAL='@t6g_mb_lib.t6g(sch_1):smb_ina230_1_3v3aux_scl_r1';
NODE_NAME     U266 5
 '@T6G_MB_LIB.T6G(SCH_1):PAGE295_I30@PURE_QUANTA.ISL28022FRZT(CHIPS)':
 'SCL|||SMBCLK': CDS_PINID='\scl|||smbclk\';
NODE_NAME     R3600 2
 '@T6G_MB_LIB.T6G(SCH_1):PAGE295_I152@PURE_QUANTA.Q_RES(CHIPS)':
 'B': CDS_PINID='B';
NET_NAME
'SMB_INA230_1_3V3AUX_SDA_R'
 '@T6G_MB_LIB.T6G(SCH_1):SMB_INA230_1_3V3AUX_SDA_R':
 C_SIGNAL='@t6g_mb_lib.t6g(sch_1):smb_ina230_1_3v3aux_sda_r';
NODE_NAME     R3587 2
 '@T6G_MB_LIB.T6G(SCH_1):PAGE253_I11@PURE_QUANTA.Q_RES(CHIPS)':
 'B': CDS_PINID='B';
NODE_NAME     R3601 1
 '@T6G_MB_LIB.T6G(SCH_1):PAGE295_I153@PURE_QUANTA.Q_RES(CHIPS)':
 'A': CDS_PINID='A';
NET_NAME
'SMB_INA230_1_3V3AUX_SDA_R1'
 '@T6G_MB_LIB.T6G(SCH_1):SMB_INA230_1_3V3AUX_SDA_R1':
 C_SIGNAL='@t6g_mb_lib.t6g(sch_1):smb_ina230_1_3v3aux_sda_r1';
NODE_NAME     U266 4
 '@T6G_MB_LIB.T6G(SCH_1):PAGE295_I30@PURE_QUANTA.ISL28022FRZT(CHIPS)':
 'SDA||SMBDAT': CDS_PINID='\sda||smbdat\';
NODE_NAME     R3601 2
 '@T6G_MB_LIB.T6G(SCH_1):PAGE295_I153@PURE_QUANTA.Q_RES(CHIPS)':
 'B': CDS_PINID='B';
NET_NAME
'SMB_INA230_2_3V3AUX_SCL_R'
 '@T6G_MB_LIB.T6G(SCH_1):SMB_INA230_2_3V3AUX_SCL_R':
 C_SIGNAL='@t6g_mb_lib.t6g(sch_1):smb_ina230_2_3v3aux_scl_r';
NODE_NAME     R3588 2
 '@T6G_MB_LIB.T6G(SCH_1):PAGE253_I10@PURE_QUANTA.Q_RES(CHIPS)':
 'B': CDS_PINID='B';
NODE_NAME     R3754 1
 '@T6G_MB_LIB.T6G(SCH_1):PAGE295_I155@PURE_QUANTA.Q_RES(CHIPS)':
 'A': CDS_PINID='A';
NET_NAME
'SMB_INA230_2_3V3AUX_SCL_R1'
 '@T6G_MB_LIB.T6G(SCH_1):SMB_INA230_2_3V3AUX_SCL_R1':
 C_SIGNAL='@t6g_mb_lib.t6g(sch_1):smb_ina230_2_3v3aux_scl_r1';
NODE_NAME     U276 5
 '@T6G_MB_LIB.T6G(SCH_1):PAGE295_I129@PURE_QUANTA.ISL28022FRZT(CHIPS)':
 'SCL|||SMBCLK': CDS_PINID='\scl|||smbclk\';
NODE_NAME     R3754 2
 '@T6G_MB_LIB.T6G(SCH_1):PAGE295_I155@PURE_QUANTA.Q_RES(CHIPS)':
 'B': CDS_PINID='B';
NET_NAME
'SMB_INA230_2_3V3AUX_SDA_R'
 '@T6G_MB_LIB.T6G(SCH_1):SMB_INA230_2_3V3AUX_SDA_R':
 C_SIGNAL='@t6g_mb_lib.t6g(sch_1):smb_ina230_2_3v3aux_sda_r';
NODE_NAME     R3589 2
 '@T6G_MB_LIB.T6G(SCH_1):PAGE253_I9@PURE_QUANTA.Q_RES(CHIPS)':
 'B': CDS_PINID='B';
NODE_NAME     R3756 1
 '@T6G_MB_LIB.T6G(SCH_1):PAGE295_I154@PURE_QUANTA.Q_RES(CHIPS)':
 'A': CDS_PINID='A';
NET_NAME
'SMB_INA230_2_3V3AUX_SDA_R1'
 '@T6G_MB_LIB.T6G(SCH_1):SMB_INA230_2_3V3AUX_SDA_R1':
 C_SIGNAL='@t6g_mb_lib.t6g(sch_1):smb_ina230_2_3v3aux_sda_r1';
NODE_NAME     U276 4
 '@T6G_MB_LIB.T6G(SCH_1):PAGE295_I129@PURE_QUANTA.ISL28022FRZT(CHIPS)':
 'SDA||SMBDAT': CDS_PINID='\sda||smbdat\';
NODE_NAME     R3751 2
 '@T6G_MB_LIB.T6G(SCH_1):PAGE295_I146@PURE_QUANTA.Q_RES(CHIPS)':
 'B': CDS_PINID='B';
NODE_NAME     R3756 2
 '@T6G_MB_LIB.T6G(SCH_1):PAGE295_I154@PURE_QUANTA.Q_RES(CHIPS)':
 'B': CDS_PINID='B';
NET_NAME
'SMB_INA230_3V3AUX_SCL'
 '@T6G_MB_LIB.T6G(SCH_1):SMB_INA230_3V3AUX_SCL':
 C_SIGNAL='@t6g_mb_lib.t6g(sch_1):smb_ina230_3v3aux_scl';
NODE_NAME     R3395 2
 '@T6G_MB_LIB.T6G(SCH_1):PAGE252_I47@PURE_QUANTA.Q_RES(CHIPS)':
 'B': CDS_PINID='B';
NODE_NAME     R3580 2
 '@T6G_MB_LIB.T6G(SCH_1):PAGE252_I69@PURE_QUANTA.Q_RES(CHIPS)':
 'B': CDS_PINID='B';
NODE_NAME     R3592 1
 '@T6G_MB_LIB.T6G(SCH_1):PAGE253_I4@PURE_QUANTA.Q_RES(CHIPS)':
 'A': CDS_PINID='A';
NODE_NAME     R3594 1
 '@T6G_MB_LIB.T6G(SCH_1):PAGE253_I6@PURE_QUANTA.Q_RES(CHIPS)':
 'A': CDS_PINID='A';
NODE_NAME     R3590 1
 '@T6G_MB_LIB.T6G(SCH_1):PAGE253_I8@PURE_QUANTA.Q_RES(CHIPS)':
 'A': CDS_PINID='A';
NODE_NAME     R3588 1
 '@T6G_MB_LIB.T6G(SCH_1):PAGE253_I10@PURE_QUANTA.Q_RES(CHIPS)':
 'A': CDS_PINID='A';
NODE_NAME     R3586 1
 '@T6G_MB_LIB.T6G(SCH_1):PAGE253_I12@PURE_QUANTA.Q_RES(CHIPS)':
 'A': CDS_PINID='A';
NODE_NAME     R1344 1
 '@T6G_MB_LIB.T6G(SCH_1):PAGE253_I23@PURE_QUANTA.Q_RES(CHIPS)':
 'A': CDS_PINID='A';
NODE_NAME     R1346 1
 '@T6G_MB_LIB.T6G(SCH_1):PAGE253_I25@PURE_QUANTA.Q_RES(CHIPS)':
 'A': CDS_PINID='A';
NODE_NAME     R1348 1
 '@T6G_MB_LIB.T6G(SCH_1):PAGE253_I27@PURE_QUANTA.Q_RES(CHIPS)':
 'A': CDS_PINID='A';
NET_NAME
'SMB_INA230_3V3AUX_SCL_R'
 '@T6G_MB_LIB.T6G(SCH_1):SMB_INA230_3V3AUX_SCL_R':
 C_SIGNAL='@t6g_mb_lib.t6g(sch_1):smb_ina230_3v3aux_scl_r';
NODE_NAME     U36 18
 '@T6G_MB_LIB.T6G(SCH_1):PAGE252_I33@PURE_QUANTA.TCA9548APWR(CHIPS)':
 'SC6': CDS_PINID='SC6';
NODE_NAME     R3580 1
 '@T6G_MB_LIB.T6G(SCH_1):PAGE252_I69@PURE_QUANTA.Q_RES(CHIPS)':
 'A': CDS_PINID='A';
NET_NAME
'SMB_INA230_3V3AUX_SDA'
 '@T6G_MB_LIB.T6G(SCH_1):SMB_INA230_3V3AUX_SDA':
 C_SIGNAL='@t6g_mb_lib.t6g(sch_1):smb_ina230_3v3aux_sda';
NODE_NAME     R3396 2
 '@T6G_MB_LIB.T6G(SCH_1):PAGE252_I48@PURE_QUANTA.Q_RES(CHIPS)':
 'B': CDS_PINID='B';
NODE_NAME     R3581 2
 '@T6G_MB_LIB.T6G(SCH_1):PAGE252_I68@PURE_QUANTA.Q_RES(CHIPS)':
 'B': CDS_PINID='B';
NODE_NAME     R3593 1
 '@T6G_MB_LIB.T6G(SCH_1):PAGE253_I3@PURE_QUANTA.Q_RES(CHIPS)':
 'A': CDS_PINID='A';
NODE_NAME     R3595 1
 '@T6G_MB_LIB.T6G(SCH_1):PAGE253_I5@PURE_QUANTA.Q_RES(CHIPS)':
 'A': CDS_PINID='A';
NODE_NAME     R3591 1
 '@T6G_MB_LIB.T6G(SCH_1):PAGE253_I7@PURE_QUANTA.Q_RES(CHIPS)':
 'A': CDS_PINID='A';
NODE_NAME     R3589 1
 '@T6G_MB_LIB.T6G(SCH_1):PAGE253_I9@PURE_QUANTA.Q_RES(CHIPS)':
 'A': CDS_PINID='A';
NODE_NAME     R3587 1
 '@T6G_MB_LIB.T6G(SCH_1):PAGE253_I11@PURE_QUANTA.Q_RES(CHIPS)':
 'A': CDS_PINID='A';
NODE_NAME     R1345 1
 '@T6G_MB_LIB.T6G(SCH_1):PAGE253_I24@PURE_QUANTA.Q_RES(CHIPS)':
 'A': CDS_PINID='A';
NODE_NAME     R1347 1
 '@T6G_MB_LIB.T6G(SCH_1):PAGE253_I26@PURE_QUANTA.Q_RES(CHIPS)':
 'A': CDS_PINID='A';
NODE_NAME     R1349 1
 '@T6G_MB_LIB.T6G(SCH_1):PAGE253_I28@PURE_QUANTA.Q_RES(CHIPS)':
 'A': CDS_PINID='A';
NET_NAME
'SMB_INA230_3V3AUX_SDA_R'
 '@T6G_MB_LIB.T6G(SCH_1):SMB_INA230_3V3AUX_SDA_R':
 C_SIGNAL='@t6g_mb_lib.t6g(sch_1):smb_ina230_3v3aux_sda_r';
NODE_NAME     U36 17
 '@T6G_MB_LIB.T6G(SCH_1):PAGE252_I33@PURE_QUANTA.TCA9548APWR(CHIPS)':
 'SD6': CDS_PINID='SD6';
NODE_NAME     R3581 1
 '@T6G_MB_LIB.T6G(SCH_1):PAGE252_I68@PURE_QUANTA.Q_RES(CHIPS)':
 'A': CDS_PINID='A';
NET_NAME
'SMB_INA230_3_3V3AUX_SCL_R'
 '@T6G_MB_LIB.T6G(SCH_1):SMB_INA230_3_3V3AUX_SCL_R':
 C_SIGNAL='@t6g_mb_lib.t6g(sch_1):smb_ina230_3_3v3aux_scl_r';
NODE_NAME     R3590 2
 '@T6G_MB_LIB.T6G(SCH_1):PAGE253_I8@PURE_QUANTA.Q_RES(CHIPS)':
 'B': CDS_PINID='B';
NODE_NAME     R3568 1
 '@T6G_MB_LIB.T6G(SCH_1):PAGE360_I128@PURE_QUANTA.Q_RES(CHIPS)':
 'A': CDS_PINID='A';
NET_NAME
'SMB_INA230_3_3V3AUX_SCL_R1'
 '@T6G_MB_LIB.T6G(SCH_1):SMB_INA230_3_3V3AUX_SCL_R1':
 C_SIGNAL='@t6g_mb_lib.t6g(sch_1):smb_ina230_3_3v3aux_scl_r1';
NODE_NAME     U263 5
 '@T6G_MB_LIB.T6G(SCH_1):PAGE360_I94@PURE_QUANTA.ISL28022FRZT(CHIPS)':
 'SCL|||SMBCLK': CDS_PINID='\scl|||smbclk\';
NODE_NAME     R3620 2
 '@T6G_MB_LIB.T6G(SCH_1):PAGE360_I100@PURE_QUANTA.Q_RES(CHIPS)':
 'B': CDS_PINID='B';
NODE_NAME     R3568 2
 '@T6G_MB_LIB.T6G(SCH_1):PAGE360_I128@PURE_QUANTA.Q_RES(CHIPS)':
 'B': CDS_PINID='B';
NET_NAME
'SMB_INA230_3_3V3AUX_SDA_R'
 '@T6G_MB_LIB.T6G(SCH_1):SMB_INA230_3_3V3AUX_SDA_R':
 C_SIGNAL='@t6g_mb_lib.t6g(sch_1):smb_ina230_3_3v3aux_sda_r';
NODE_NAME     R3591 2
 '@T6G_MB_LIB.T6G(SCH_1):PAGE253_I7@PURE_QUANTA.Q_RES(CHIPS)':
 'B': CDS_PINID='B';
NODE_NAME     R3569 1
 '@T6G_MB_LIB.T6G(SCH_1):PAGE360_I127@PURE_QUANTA.Q_RES(CHIPS)':
 'A': CDS_PINID='A';
NET_NAME
'SMB_INA230_3_3V3AUX_SDA_R1'
 '@T6G_MB_LIB.T6G(SCH_1):SMB_INA230_3_3V3AUX_SDA_R1':
 C_SIGNAL='@t6g_mb_lib.t6g(sch_1):smb_ina230_3_3v3aux_sda_r1';
NODE_NAME     U263 4
 '@T6G_MB_LIB.T6G(SCH_1):PAGE360_I94@PURE_QUANTA.ISL28022FRZT(CHIPS)':
 'SDA||SMBDAT': CDS_PINID='\sda||smbdat\';
NODE_NAME     R3569 2
 '@T6G_MB_LIB.T6G(SCH_1):PAGE360_I127@PURE_QUANTA.Q_RES(CHIPS)':
 'B': CDS_PINID='B';
NET_NAME
'SMB_INA230_4_3V3AUX_SCL_R'
 '@T6G_MB_LIB.T6G(SCH_1):SMB_INA230_4_3V3AUX_SCL_R':
 C_SIGNAL='@t6g_mb_lib.t6g(sch_1):smb_ina230_4_3v3aux_scl_r';
NODE_NAME     R3594 2
 '@T6G_MB_LIB.T6G(SCH_1):PAGE253_I6@PURE_QUANTA.Q_RES(CHIPS)':
 'B': CDS_PINID='B';
NODE_NAME     R3572 1
 '@T6G_MB_LIB.T6G(SCH_1):PAGE360_I130@PURE_QUANTA.Q_RES(CHIPS)':
 'A': CDS_PINID='A';
NET_NAME
'SMB_INA230_4_3V3AUX_SCL_R1'
 '@T6G_MB_LIB.T6G(SCH_1):SMB_INA230_4_3V3AUX_SCL_R1':
 C_SIGNAL='@t6g_mb_lib.t6g(sch_1):smb_ina230_4_3v3aux_scl_r1';
NODE_NAME     U264 5
 '@T6G_MB_LIB.T6G(SCH_1):PAGE360_I46@PURE_QUANTA.ISL28022FRZT(CHIPS)':
 'SCL|||SMBCLK': CDS_PINID='\scl|||smbclk\';
NODE_NAME     R3572 2
 '@T6G_MB_LIB.T6G(SCH_1):PAGE360_I130@PURE_QUANTA.Q_RES(CHIPS)':
 'B': CDS_PINID='B';
NET_NAME
'SMB_INA230_4_3V3AUX_SDA_R'
 '@T6G_MB_LIB.T6G(SCH_1):SMB_INA230_4_3V3AUX_SDA_R':
 C_SIGNAL='@t6g_mb_lib.t6g(sch_1):smb_ina230_4_3v3aux_sda_r';
NODE_NAME     R3595 2
 '@T6G_MB_LIB.T6G(SCH_1):PAGE253_I5@PURE_QUANTA.Q_RES(CHIPS)':
 'B': CDS_PINID='B';
NODE_NAME     R3573 1
 '@T6G_MB_LIB.T6G(SCH_1):PAGE360_I129@PURE_QUANTA.Q_RES(CHIPS)':
 'A': CDS_PINID='A';
NET_NAME
'SMB_INA230_4_3V3AUX_SDA_R1'
 '@T6G_MB_LIB.T6G(SCH_1):SMB_INA230_4_3V3AUX_SDA_R1':
 C_SIGNAL='@t6g_mb_lib.t6g(sch_1):smb_ina230_4_3v3aux_sda_r1';
NODE_NAME     U264 4
 '@T6G_MB_LIB.T6G(SCH_1):PAGE360_I46@PURE_QUANTA.ISL28022FRZT(CHIPS)':
 'SDA||SMBDAT': CDS_PINID='\sda||smbdat\';
NODE_NAME     R3573 2
 '@T6G_MB_LIB.T6G(SCH_1):PAGE360_I129@PURE_QUANTA.Q_RES(CHIPS)':
 'B': CDS_PINID='B';
NET_NAME
'SMB_INA230_5_3V3AUX_SCL_R'
 '@T6G_MB_LIB.T6G(SCH_1):SMB_INA230_5_3V3AUX_SCL_R':
 C_SIGNAL='@t6g_mb_lib.t6g(sch_1):smb_ina230_5_3v3aux_scl_r';
NODE_NAME     R3592 2
 '@T6G_MB_LIB.T6G(SCH_1):PAGE253_I4@PURE_QUANTA.Q_RES(CHIPS)':
 'B': CDS_PINID='B';
NODE_NAME     R3576 1
 '@T6G_MB_LIB.T6G(SCH_1):PAGE360_I131@PURE_QUANTA.Q_RES(CHIPS)':
 'A': CDS_PINID='A';
NET_NAME
'SMB_INA230_5_3V3AUX_SCL_R1'
 '@T6G_MB_LIB.T6G(SCH_1):SMB_INA230_5_3V3AUX_SCL_R1':
 C_SIGNAL='@t6g_mb_lib.t6g(sch_1):smb_ina230_5_3v3aux_scl_r1';
NODE_NAME     U265 5
 '@T6G_MB_LIB.T6G(SCH_1):PAGE360_I69@PURE_QUANTA.ISL28022FRZT(CHIPS)':
 'SCL|||SMBCLK': CDS_PINID='\scl|||smbclk\';
NODE_NAME     R3576 2
 '@T6G_MB_LIB.T6G(SCH_1):PAGE360_I131@PURE_QUANTA.Q_RES(CHIPS)':
 'B': CDS_PINID='B';
NET_NAME
'SMB_INA230_5_3V3AUX_SDA_R'
 '@T6G_MB_LIB.T6G(SCH_1):SMB_INA230_5_3V3AUX_SDA_R':
 C_SIGNAL='@t6g_mb_lib.t6g(sch_1):smb_ina230_5_3v3aux_sda_r';
NODE_NAME     R3593 2
 '@T6G_MB_LIB.T6G(SCH_1):PAGE253_I3@PURE_QUANTA.Q_RES(CHIPS)':
 'B': CDS_PINID='B';
NODE_NAME     R3577 1
 '@T6G_MB_LIB.T6G(SCH_1):PAGE360_I132@PURE_QUANTA.Q_RES(CHIPS)':
 'A': CDS_PINID='A';
NET_NAME
'SMB_INA230_5_3V3AUX_SDA_R1'
 '@T6G_MB_LIB.T6G(SCH_1):SMB_INA230_5_3V3AUX_SDA_R1':
 C_SIGNAL='@t6g_mb_lib.t6g(sch_1):smb_ina230_5_3v3aux_sda_r1';
NODE_NAME     U265 4
 '@T6G_MB_LIB.T6G(SCH_1):PAGE360_I69@PURE_QUANTA.ISL28022FRZT(CHIPS)':
 'SDA||SMBDAT': CDS_PINID='\sda||smbdat\';
NODE_NAME     R3577 2
 '@T6G_MB_LIB.T6G(SCH_1):PAGE360_I132@PURE_QUANTA.Q_RES(CHIPS)':
 'B': CDS_PINID='B';
NET_NAME
'SMB_INA230_6_3V3AUX_SCL_R'
 '@T6G_MB_LIB.T6G(SCH_1):SMB_INA230_6_3V3AUX_SCL_R':
 C_SIGNAL='@t6g_mb_lib.t6g(sch_1):smb_ina230_6_3v3aux_scl_r';
NODE_NAME     R1273 1
 '@T6G_MB_LIB.T6G(SCH_1):PAGE466_I27@PURE_QUANTA.Q_RES(CHIPS)':
 'A': CDS_PINID='A';
NODE_NAME     R1344 2
 '@T6G_MB_LIB.T6G(SCH_1):PAGE253_I23@PURE_QUANTA.Q_RES(CHIPS)':
 'B': CDS_PINID='B';
NET_NAME
'SMB_INA230_6_3V3AUX_SCL_R1'
 '@T6G_MB_LIB.T6G(SCH_1):SMB_INA230_6_3V3AUX_SCL_R1':
 C_SIGNAL='@t6g_mb_lib.t6g(sch_1):smb_ina230_6_3v3aux_scl_r1';
NODE_NAME     R1273 2
 '@T6G_MB_LIB.T6G(SCH_1):PAGE466_I27@PURE_QUANTA.Q_RES(CHIPS)':
 'B': CDS_PINID='B';
NODE_NAME     U55 5
 '@T6G_MB_LIB.T6G(SCH_1):PAGE466_I28@PURE_QUANTA.ISL28022FRZT(CHIPS)':
 'SCL|||SMBCLK': CDS_PINID='\scl|||smbclk\';
NET_NAME
'SMB_INA230_6_3V3AUX_SDA_R'
 '@T6G_MB_LIB.T6G(SCH_1):SMB_INA230_6_3V3AUX_SDA_R':
 C_SIGNAL='@t6g_mb_lib.t6g(sch_1):smb_ina230_6_3v3aux_sda_r';
NODE_NAME     R1276 1
 '@T6G_MB_LIB.T6G(SCH_1):PAGE466_I14@PURE_QUANTA.Q_RES(CHIPS)':
 'A': CDS_PINID='A';
NODE_NAME     R1345 2
 '@T6G_MB_LIB.T6G(SCH_1):PAGE253_I24@PURE_QUANTA.Q_RES(CHIPS)':
 'B': CDS_PINID='B';
NET_NAME
'SMB_INA230_6_3V3AUX_SDA_R1'
 '@T6G_MB_LIB.T6G(SCH_1):SMB_INA230_6_3V3AUX_SDA_R1':
 C_SIGNAL='@t6g_mb_lib.t6g(sch_1):smb_ina230_6_3v3aux_sda_r1';
NODE_NAME     R1276 2
 '@T6G_MB_LIB.T6G(SCH_1):PAGE466_I14@PURE_QUANTA.Q_RES(CHIPS)':
 'B': CDS_PINID='B';
NODE_NAME     U55 4
 '@T6G_MB_LIB.T6G(SCH_1):PAGE466_I28@PURE_QUANTA.ISL28022FRZT(CHIPS)':
 'SDA||SMBDAT': CDS_PINID='\sda||smbdat\';
NODE_NAME     R1355 2
 '@T6G_MB_LIB.T6G(SCH_1):PAGE466_I92@PURE_QUANTA.Q_RES(CHIPS)':
 'B': CDS_PINID='B';
NET_NAME
'SMB_INA230_7_3V3AUX_SCL_R'
 '@T6G_MB_LIB.T6G(SCH_1):SMB_INA230_7_3V3AUX_SCL_R':
 C_SIGNAL='@t6g_mb_lib.t6g(sch_1):smb_ina230_7_3v3aux_scl_r';
NODE_NAME     R1274 1
 '@T6G_MB_LIB.T6G(SCH_1):PAGE466_I42@PURE_QUANTA.Q_RES(CHIPS)':
 'A': CDS_PINID='A';
NODE_NAME     R1346 2
 '@T6G_MB_LIB.T6G(SCH_1):PAGE253_I25@PURE_QUANTA.Q_RES(CHIPS)':
 'B': CDS_PINID='B';
NET_NAME
'SMB_INA230_7_3V3AUX_SCL_R1'
 '@T6G_MB_LIB.T6G(SCH_1):SMB_INA230_7_3V3AUX_SCL_R1':
 C_SIGNAL='@t6g_mb_lib.t6g(sch_1):smb_ina230_7_3v3aux_scl_r1';
NODE_NAME     U56 5
 '@T6G_MB_LIB.T6G(SCH_1):PAGE466_I29@PURE_QUANTA.ISL28022FRZT(CHIPS)':
 'SCL|||SMBCLK': CDS_PINID='\scl|||smbclk\';
NODE_NAME     R1274 2
 '@T6G_MB_LIB.T6G(SCH_1):PAGE466_I42@PURE_QUANTA.Q_RES(CHIPS)':
 'B': CDS_PINID='B';
NODE_NAME     R1360 2
 '@T6G_MB_LIB.T6G(SCH_1):PAGE466_I93@PURE_QUANTA.Q_RES(CHIPS)':
 'B': CDS_PINID='B';
NET_NAME
'SMB_INA230_7_3V3AUX_SDA_R'
 '@T6G_MB_LIB.T6G(SCH_1):SMB_INA230_7_3V3AUX_SDA_R':
 C_SIGNAL='@t6g_mb_lib.t6g(sch_1):smb_ina230_7_3v3aux_sda_r';
NODE_NAME     R1277 1
 '@T6G_MB_LIB.T6G(SCH_1):PAGE466_I41@PURE_QUANTA.Q_RES(CHIPS)':
 'A': CDS_PINID='A';
NODE_NAME     R1347 2
 '@T6G_MB_LIB.T6G(SCH_1):PAGE253_I26@PURE_QUANTA.Q_RES(CHIPS)':
 'B': CDS_PINID='B';
NET_NAME
'SMB_INA230_7_3V3AUX_SDA_R1'
 '@T6G_MB_LIB.T6G(SCH_1):SMB_INA230_7_3V3AUX_SDA_R1':
 C_SIGNAL='@t6g_mb_lib.t6g(sch_1):smb_ina230_7_3v3aux_sda_r1';
NODE_NAME     U56 4
 '@T6G_MB_LIB.T6G(SCH_1):PAGE466_I29@PURE_QUANTA.ISL28022FRZT(CHIPS)':
 'SDA||SMBDAT': CDS_PINID='\sda||smbdat\';
NODE_NAME     R1277 2
 '@T6G_MB_LIB.T6G(SCH_1):PAGE466_I41@PURE_QUANTA.Q_RES(CHIPS)':
 'B': CDS_PINID='B';
NET_NAME
'SMB_INA230_8_3V3AUX_SCL_R'
 '@T6G_MB_LIB.T6G(SCH_1):SMB_INA230_8_3V3AUX_SCL_R':
 C_SIGNAL='@t6g_mb_lib.t6g(sch_1):smb_ina230_8_3v3aux_scl_r';
NODE_NAME     R1272 1
 '@T6G_MB_LIB.T6G(SCH_1):PAGE466_I71@PURE_QUANTA.Q_RES(CHIPS)':
 'A': CDS_PINID='A';
NODE_NAME     R1348 2
 '@T6G_MB_LIB.T6G(SCH_1):PAGE253_I27@PURE_QUANTA.Q_RES(CHIPS)':
 'B': CDS_PINID='B';
NET_NAME
'SMB_INA230_8_3V3AUX_SCL_R1'
 '@T6G_MB_LIB.T6G(SCH_1):SMB_INA230_8_3V3AUX_SCL_R1':
 C_SIGNAL='@t6g_mb_lib.t6g(sch_1):smb_ina230_8_3v3aux_scl_r1';
NODE_NAME     U52 5
 '@T6G_MB_LIB.T6G(SCH_1):PAGE466_I57@PURE_QUANTA.ISL28022FRZT(CHIPS)':
 'SCL|||SMBCLK': CDS_PINID='\scl|||smbclk\';
NODE_NAME     R1272 2
 '@T6G_MB_LIB.T6G(SCH_1):PAGE466_I71@PURE_QUANTA.Q_RES(CHIPS)':
 'B': CDS_PINID='B';
NET_NAME
'SMB_INA230_8_3V3AUX_SDA_R'
 '@T6G_MB_LIB.T6G(SCH_1):SMB_INA230_8_3V3AUX_SDA_R':
 C_SIGNAL='@t6g_mb_lib.t6g(sch_1):smb_ina230_8_3v3aux_sda_r';
NODE_NAME     R1275 1
 '@T6G_MB_LIB.T6G(SCH_1):PAGE466_I70@PURE_QUANTA.Q_RES(CHIPS)':
 'A': CDS_PINID='A';
NODE_NAME     R1349 2
 '@T6G_MB_LIB.T6G(SCH_1):PAGE253_I28@PURE_QUANTA.Q_RES(CHIPS)':
 'B': CDS_PINID='B';
NET_NAME
'SMB_INA230_8_3V3AUX_SDA_R1'
 '@T6G_MB_LIB.T6G(SCH_1):SMB_INA230_8_3V3AUX_SDA_R1':
 C_SIGNAL='@t6g_mb_lib.t6g(sch_1):smb_ina230_8_3v3aux_sda_r1';
NODE_NAME     U52 4
 '@T6G_MB_LIB.T6G(SCH_1):PAGE466_I57@PURE_QUANTA.ISL28022FRZT(CHIPS)':
 'SDA||SMBDAT': CDS_PINID='\sda||smbdat\';
NODE_NAME     R1275 2
 '@T6G_MB_LIB.T6G(SCH_1):PAGE466_I70@PURE_QUANTA.Q_RES(CHIPS)':
 'B': CDS_PINID='B';
NODE_NAME     R1350 2
 '@T6G_MB_LIB.T6G(SCH_1):PAGE466_I94@PURE_QUANTA.Q_RES(CHIPS)':
 'B': CDS_PINID='B';
NET_NAME
'SMB_IOEXP_3V3AUX_SCL'
 '@T6G_MB_LIB.T6G(SCH_1):SMB_IOEXP_3V3AUX_SCL':
 C_SIGNAL='@t6g_mb_lib.t6g(sch_1):smb_ioexp_3v3aux_scl';
NODE_NAME     R3393 2
 '@T6G_MB_LIB.T6G(SCH_1):PAGE252_I27@PURE_QUANTA.Q_RES(CHIPS)':
 'B': CDS_PINID='B';
NODE_NAME     R3582 2
 '@T6G_MB_LIB.T6G(SCH_1):PAGE252_I46@PURE_QUANTA.Q_RES(CHIPS)':
 'B': CDS_PINID='B';
NODE_NAME     R2982 1
 '@T6G_MB_LIB.T6G(SCH_1):PAGE246_I82@PURE_QUANTA.Q_RES(CHIPS)':
 'A': CDS_PINID='A';
NET_NAME
'SMB_IOEXP_3V3AUX_SCL_R'
 '@T6G_MB_LIB.T6G(SCH_1):SMB_IOEXP_3V3AUX_SCL_R':
 C_SIGNAL='@t6g_mb_lib.t6g(sch_1):smb_ioexp_3v3aux_scl_r';
NODE_NAME     R3393 1
 '@T6G_MB_LIB.T6G(SCH_1):PAGE252_I27@PURE_QUANTA.Q_RES(CHIPS)':
 'A': CDS_PINID='A';
NODE_NAME     U36 7
 '@T6G_MB_LIB.T6G(SCH_1):PAGE252_I33@PURE_QUANTA.TCA9548APWR(CHIPS)':
 'SC1': CDS_PINID='SC1';
NET_NAME
'SMB_IOEXP_3V3AUX_SCL_R1'
 '@T6G_MB_LIB.T6G(SCH_1):SMB_IOEXP_3V3AUX_SCL_R1':
 C_SIGNAL='@t6g_mb_lib.t6g(sch_1):smb_ioexp_3v3aux_scl_r1';
NODE_NAME     R2982 2
 '@T6G_MB_LIB.T6G(SCH_1):PAGE246_I82@PURE_QUANTA.Q_RES(CHIPS)':
 'B': CDS_PINID='B';
NODE_NAME     U181 22
 '@T6G_MB_LIB.T6G(SCH_1):PAGE246_I83@PURE_QUANTA.PCA9539RPW(CHIPS)':
 'SCL': CDS_PINID='SCL';
NET_NAME
'SMB_IOEXP_3V3AUX_SDA'
 '@T6G_MB_LIB.T6G(SCH_1):SMB_IOEXP_3V3AUX_SDA':
 C_SIGNAL='@t6g_mb_lib.t6g(sch_1):smb_ioexp_3v3aux_sda';
NODE_NAME     R3394 2
 '@T6G_MB_LIB.T6G(SCH_1):PAGE252_I29@PURE_QUANTA.Q_RES(CHIPS)':
 'B': CDS_PINID='B';
NODE_NAME     R3583 2
 '@T6G_MB_LIB.T6G(SCH_1):PAGE252_I45@PURE_QUANTA.Q_RES(CHIPS)':
 'B': CDS_PINID='B';
NODE_NAME     R2983 1
 '@T6G_MB_LIB.T6G(SCH_1):PAGE246_I58@PURE_QUANTA.Q_RES(CHIPS)':
 'A': CDS_PINID='A';
NET_NAME
'SMB_IOEXP_3V3AUX_SDA_R'
 '@T6G_MB_LIB.T6G(SCH_1):SMB_IOEXP_3V3AUX_SDA_R':
 C_SIGNAL='@t6g_mb_lib.t6g(sch_1):smb_ioexp_3v3aux_sda_r';
NODE_NAME     R3394 1
 '@T6G_MB_LIB.T6G(SCH_1):PAGE252_I29@PURE_QUANTA.Q_RES(CHIPS)':
 'A': CDS_PINID='A';
NODE_NAME     U36 6
 '@T6G_MB_LIB.T6G(SCH_1):PAGE252_I33@PURE_QUANTA.TCA9548APWR(CHIPS)':
 'SD1': CDS_PINID='SD1';
NET_NAME
'SMB_IOEXP_3V3AUX_SDA_R1'
 '@T6G_MB_LIB.T6G(SCH_1):SMB_IOEXP_3V3AUX_SDA_R1':
 C_SIGNAL='@t6g_mb_lib.t6g(sch_1):smb_ioexp_3v3aux_sda_r1';
NODE_NAME     R2983 2
 '@T6G_MB_LIB.T6G(SCH_1):PAGE246_I58@PURE_QUANTA.Q_RES(CHIPS)':
 'B': CDS_PINID='B';
NODE_NAME     U181 23
 '@T6G_MB_LIB.T6G(SCH_1):PAGE246_I83@PURE_QUANTA.PCA9539RPW(CHIPS)':
 'SDA': CDS_PINID='SDA';
NET_NAME
'SMB_LM75_0_3V3AUX_SCL'
 '@T6G_MB_LIB.T6G(SCH_1):SMB_LM75_0_3V3AUX_SCL':
 C_SIGNAL='@t6g_mb_lib.t6g(sch_1):smb_lm75_0_3v3aux_scl';
NODE_NAME     R4180 1
 '@T6G_MB_LIB.T6G(SCH_1):PAGE359_I77@PURE_QUANTA.Q_RES(CHIPS)':
 'A': CDS_PINID='A';
NODE_NAME     R3715 2
 '@T6G_MB_LIB.T6G(SCH_1):PAGE251_I31@PURE_QUANTA.Q_RES(CHIPS)':
 'B': CDS_PINID='B';
NODE_NAME     R3725 2
 '@T6G_MB_LIB.T6G(SCH_1):PAGE251_I50@PURE_QUANTA.Q_RES(CHIPS)':
 'B': CDS_PINID='B';
NODE_NAME     R6252 1
 '@T6G_MB_LIB.T6G(SCH_1):PAGE271_I9@PURE_QUANTA.Q_RES(CHIPS)':
 'A': CDS_PINID='A';
NET_NAME
'SMB_LM75_0_3V3AUX_SCL_R'
 '@T6G_MB_LIB.T6G(SCH_1):SMB_LM75_0_3V3AUX_SCL_R':
 C_SIGNAL='@t6g_mb_lib.t6g(sch_1):smb_lm75_0_3v3aux_scl_r';
NODE_NAME     R3715 1
 '@T6G_MB_LIB.T6G(SCH_1):PAGE251_I31@PURE_QUANTA.Q_RES(CHIPS)':
 'A': CDS_PINID='A';
NODE_NAME     U39 7
 '@T6G_MB_LIB.T6G(SCH_1):PAGE251_I74@PURE_QUANTA.TCA9548APWR(CHIPS)':
 'SC1': CDS_PINID='SC1';
NET_NAME
'SMB_LM75_0_3V3AUX_SCL_R1'
 '@T6G_MB_LIB.T6G(SCH_1):SMB_LM75_0_3V3AUX_SCL_R1':
 C_SIGNAL='@t6g_mb_lib.t6g(sch_1):smb_lm75_0_3v3aux_scl_r1';
NODE_NAME     R4180 2
 '@T6G_MB_LIB.T6G(SCH_1):PAGE359_I77@PURE_QUANTA.Q_RES(CHIPS)':
 'B': CDS_PINID='B';
NODE_NAME     U270 2
 '@T6G_MB_LIB.T6G(SCH_1):PAGE359_I164@PURE_QUANTA.LM75BD(CHIPS)':
 'SCL': CDS_PINID='SCL';
NET_NAME
'SMB_LM75_0_3V3AUX_SDA'
 '@T6G_MB_LIB.T6G(SCH_1):SMB_LM75_0_3V3AUX_SDA':
 C_SIGNAL='@t6g_mb_lib.t6g(sch_1):smb_lm75_0_3v3aux_sda';
NODE_NAME     R4183 1
 '@T6G_MB_LIB.T6G(SCH_1):PAGE359_I78@PURE_QUANTA.Q_RES(CHIPS)':
 'A': CDS_PINID='A';
NODE_NAME     R3716 2
 '@T6G_MB_LIB.T6G(SCH_1):PAGE251_I30@PURE_QUANTA.Q_RES(CHIPS)':
 'B': CDS_PINID='B';
NODE_NAME     R3726 2
 '@T6G_MB_LIB.T6G(SCH_1):PAGE251_I49@PURE_QUANTA.Q_RES(CHIPS)':
 'B': CDS_PINID='B';
NODE_NAME     R6253 1
 '@T6G_MB_LIB.T6G(SCH_1):PAGE271_I10@PURE_QUANTA.Q_RES(CHIPS)':
 'A': CDS_PINID='A';
NET_NAME
'SMB_LM75_0_3V3AUX_SDA_R'
 '@T6G_MB_LIB.T6G(SCH_1):SMB_LM75_0_3V3AUX_SDA_R':
 C_SIGNAL='@t6g_mb_lib.t6g(sch_1):smb_lm75_0_3v3aux_sda_r';
NODE_NAME     R3716 1
 '@T6G_MB_LIB.T6G(SCH_1):PAGE251_I30@PURE_QUANTA.Q_RES(CHIPS)':
 'A': CDS_PINID='A';
NODE_NAME     U39 6
 '@T6G_MB_LIB.T6G(SCH_1):PAGE251_I74@PURE_QUANTA.TCA9548APWR(CHIPS)':
 'SD1': CDS_PINID='SD1';
NET_NAME
'SMB_LM75_0_3V3AUX_SDA_R1'
 '@T6G_MB_LIB.T6G(SCH_1):SMB_LM75_0_3V3AUX_SDA_R1':
 C_SIGNAL='@t6g_mb_lib.t6g(sch_1):smb_lm75_0_3v3aux_sda_r1';
NODE_NAME     R4183 2
 '@T6G_MB_LIB.T6G(SCH_1):PAGE359_I78@PURE_QUANTA.Q_RES(CHIPS)':
 'B': CDS_PINID='B';
NODE_NAME     U270 1
 '@T6G_MB_LIB.T6G(SCH_1):PAGE359_I164@PURE_QUANTA.LM75BD(CHIPS)':
 'SDA': CDS_PINID='SDA';
NET_NAME
'SMB_LM75_1_3V3AUX_SCL'
 '@T6G_MB_LIB.T6G(SCH_1):SMB_LM75_1_3V3AUX_SCL':
 C_SIGNAL='@t6g_mb_lib.t6g(sch_1):smb_lm75_1_3v3aux_scl';
NODE_NAME     R4179 1
 '@T6G_MB_LIB.T6G(SCH_1):PAGE359_I109@PURE_QUANTA.Q_RES(CHIPS)':
 'A': CDS_PINID='A';
NODE_NAME     R3717 2
 '@T6G_MB_LIB.T6G(SCH_1):PAGE251_I20@PURE_QUANTA.Q_RES(CHIPS)':
 'B': CDS_PINID='B';
NODE_NAME     R3727 2
 '@T6G_MB_LIB.T6G(SCH_1):PAGE251_I48@PURE_QUANTA.Q_RES(CHIPS)':
 'B': CDS_PINID='B';
NET_NAME
'SMB_LM75_1_3V3AUX_SCL_R'
 '@T6G_MB_LIB.T6G(SCH_1):SMB_LM75_1_3V3AUX_SCL_R':
 C_SIGNAL='@t6g_mb_lib.t6g(sch_1):smb_lm75_1_3v3aux_scl_r';
NODE_NAME     R3717 1
 '@T6G_MB_LIB.T6G(SCH_1):PAGE251_I20@PURE_QUANTA.Q_RES(CHIPS)':
 'A': CDS_PINID='A';
NODE_NAME     U39 9
 '@T6G_MB_LIB.T6G(SCH_1):PAGE251_I74@PURE_QUANTA.TCA9548APWR(CHIPS)':
 'SC2': CDS_PINID='SC2';
NET_NAME
'SMB_LM75_1_3V3AUX_SCL_R1'
 '@T6G_MB_LIB.T6G(SCH_1):SMB_LM75_1_3V3AUX_SCL_R1':
 C_SIGNAL='@t6g_mb_lib.t6g(sch_1):smb_lm75_1_3v3aux_scl_r1';
NODE_NAME     R4179 2
 '@T6G_MB_LIB.T6G(SCH_1):PAGE359_I109@PURE_QUANTA.Q_RES(CHIPS)':
 'B': CDS_PINID='B';
NODE_NAME     U271 2
 '@T6G_MB_LIB.T6G(SCH_1):PAGE359_I165@PURE_QUANTA.LM75BD(CHIPS)':
 'SCL': CDS_PINID='SCL';
NET_NAME
'SMB_LM75_1_3V3AUX_SDA'
 '@T6G_MB_LIB.T6G(SCH_1):SMB_LM75_1_3V3AUX_SDA':
 C_SIGNAL='@t6g_mb_lib.t6g(sch_1):smb_lm75_1_3v3aux_sda';
NODE_NAME     R4182 1
 '@T6G_MB_LIB.T6G(SCH_1):PAGE359_I107@PURE_QUANTA.Q_RES(CHIPS)':
 'A': CDS_PINID='A';
NODE_NAME     R3718 2
 '@T6G_MB_LIB.T6G(SCH_1):PAGE251_I21@PURE_QUANTA.Q_RES(CHIPS)':
 'B': CDS_PINID='B';
NODE_NAME     R3728 2
 '@T6G_MB_LIB.T6G(SCH_1):PAGE251_I47@PURE_QUANTA.Q_RES(CHIPS)':
 'B': CDS_PINID='B';
NET_NAME
'SMB_LM75_1_3V3AUX_SDA_R'
 '@T6G_MB_LIB.T6G(SCH_1):SMB_LM75_1_3V3AUX_SDA_R':
 C_SIGNAL='@t6g_mb_lib.t6g(sch_1):smb_lm75_1_3v3aux_sda_r';
NODE_NAME     R3718 1
 '@T6G_MB_LIB.T6G(SCH_1):PAGE251_I21@PURE_QUANTA.Q_RES(CHIPS)':
 'A': CDS_PINID='A';
NODE_NAME     U39 8
 '@T6G_MB_LIB.T6G(SCH_1):PAGE251_I74@PURE_QUANTA.TCA9548APWR(CHIPS)':
 'SD2': CDS_PINID='SD2';
NET_NAME
'SMB_LM75_1_3V3AUX_SDA_R1'
 '@T6G_MB_LIB.T6G(SCH_1):SMB_LM75_1_3V3AUX_SDA_R1':
 C_SIGNAL='@t6g_mb_lib.t6g(sch_1):smb_lm75_1_3v3aux_sda_r1';
NODE_NAME     R4182 2
 '@T6G_MB_LIB.T6G(SCH_1):PAGE359_I107@PURE_QUANTA.Q_RES(CHIPS)':
 'B': CDS_PINID='B';
NODE_NAME     U271 1
 '@T6G_MB_LIB.T6G(SCH_1):PAGE359_I165@PURE_QUANTA.LM75BD(CHIPS)':
 'SDA': CDS_PINID='SDA';
NET_NAME
'SMB_LM75_2_3V3AUX_SCL'
 '@T6G_MB_LIB.T6G(SCH_1):SMB_LM75_2_3V3AUX_SCL':
 C_SIGNAL='@t6g_mb_lib.t6g(sch_1):smb_lm75_2_3v3aux_scl';
NODE_NAME     R4178 1
 '@T6G_MB_LIB.T6G(SCH_1):PAGE359_I114@PURE_QUANTA.Q_RES(CHIPS)':
 'A': CDS_PINID='A';
NODE_NAME     R3719 2
 '@T6G_MB_LIB.T6G(SCH_1):PAGE251_I18@PURE_QUANTA.Q_RES(CHIPS)':
 'B': CDS_PINID='B';
NODE_NAME     R3729 2
 '@T6G_MB_LIB.T6G(SCH_1):PAGE251_I44@PURE_QUANTA.Q_RES(CHIPS)':
 'B': CDS_PINID='B';
NET_NAME
'SMB_LM75_2_3V3AUX_SCL_R'
 '@T6G_MB_LIB.T6G(SCH_1):SMB_LM75_2_3V3AUX_SCL_R':
 C_SIGNAL='@t6g_mb_lib.t6g(sch_1):smb_lm75_2_3v3aux_scl_r';
NODE_NAME     R3719 1
 '@T6G_MB_LIB.T6G(SCH_1):PAGE251_I18@PURE_QUANTA.Q_RES(CHIPS)':
 'A': CDS_PINID='A';
NODE_NAME     U39 11
 '@T6G_MB_LIB.T6G(SCH_1):PAGE251_I74@PURE_QUANTA.TCA9548APWR(CHIPS)':
 'SC3': CDS_PINID='SC3';
NET_NAME
'SMB_LM75_2_3V3AUX_SCL_R1'
 '@T6G_MB_LIB.T6G(SCH_1):SMB_LM75_2_3V3AUX_SCL_R1':
 C_SIGNAL='@t6g_mb_lib.t6g(sch_1):smb_lm75_2_3v3aux_scl_r1';
NODE_NAME     R4178 2
 '@T6G_MB_LIB.T6G(SCH_1):PAGE359_I114@PURE_QUANTA.Q_RES(CHIPS)':
 'B': CDS_PINID='B';
NODE_NAME     U272 2
 '@T6G_MB_LIB.T6G(SCH_1):PAGE359_I166@PURE_QUANTA.LM75BD(CHIPS)':
 'SCL': CDS_PINID='SCL';
NET_NAME
'SMB_LM75_2_3V3AUX_SDA'
 '@T6G_MB_LIB.T6G(SCH_1):SMB_LM75_2_3V3AUX_SDA':
 C_SIGNAL='@t6g_mb_lib.t6g(sch_1):smb_lm75_2_3v3aux_sda';
NODE_NAME     R4181 1
 '@T6G_MB_LIB.T6G(SCH_1):PAGE359_I116@PURE_QUANTA.Q_RES(CHIPS)':
 'A': CDS_PINID='A';
NODE_NAME     R3720 2
 '@T6G_MB_LIB.T6G(SCH_1):PAGE251_I19@PURE_QUANTA.Q_RES(CHIPS)':
 'B': CDS_PINID='B';
NODE_NAME     R3730 2
 '@T6G_MB_LIB.T6G(SCH_1):PAGE251_I45@PURE_QUANTA.Q_RES(CHIPS)':
 'B': CDS_PINID='B';
NET_NAME
'SMB_LM75_2_3V3AUX_SDA_R'
 '@T6G_MB_LIB.T6G(SCH_1):SMB_LM75_2_3V3AUX_SDA_R':
 C_SIGNAL='@t6g_mb_lib.t6g(sch_1):smb_lm75_2_3v3aux_sda_r';
NODE_NAME     R3720 1
 '@T6G_MB_LIB.T6G(SCH_1):PAGE251_I19@PURE_QUANTA.Q_RES(CHIPS)':
 'A': CDS_PINID='A';
NODE_NAME     U39 10
 '@T6G_MB_LIB.T6G(SCH_1):PAGE251_I74@PURE_QUANTA.TCA9548APWR(CHIPS)':
 'SD3': CDS_PINID='SD3';
NET_NAME
'SMB_LM75_2_3V3AUX_SDA_R1'
 '@T6G_MB_LIB.T6G(SCH_1):SMB_LM75_2_3V3AUX_SDA_R1':
 C_SIGNAL='@t6g_mb_lib.t6g(sch_1):smb_lm75_2_3v3aux_sda_r1';
NODE_NAME     R4181 2
 '@T6G_MB_LIB.T6G(SCH_1):PAGE359_I116@PURE_QUANTA.Q_RES(CHIPS)':
 'B': CDS_PINID='B';
NODE_NAME     U272 1
 '@T6G_MB_LIB.T6G(SCH_1):PAGE359_I166@PURE_QUANTA.LM75BD(CHIPS)':
 'SDA': CDS_PINID='SDA';
NET_NAME
'SMB_LM75_3_3V3AUX_SCL'
 '@T6G_MB_LIB.T6G(SCH_1):SMB_LM75_3_3V3AUX_SCL':
 C_SIGNAL='@t6g_mb_lib.t6g(sch_1):smb_lm75_3_3v3aux_scl';
NODE_NAME     R3553 1
 '@T6G_MB_LIB.T6G(SCH_1):PAGE359_I134@PURE_QUANTA.Q_RES(CHIPS)':
 'A': CDS_PINID='A';
NODE_NAME     R3731 2
 '@T6G_MB_LIB.T6G(SCH_1):PAGE251_I43@PURE_QUANTA.Q_RES(CHIPS)':
 'B': CDS_PINID='B';
NODE_NAME     R3721 2
 '@T6G_MB_LIB.T6G(SCH_1):PAGE251_I67@PURE_QUANTA.Q_RES(CHIPS)':
 'B': CDS_PINID='B';
NET_NAME
'SMB_LM75_3_3V3AUX_SCL_R'
 '@T6G_MB_LIB.T6G(SCH_1):SMB_LM75_3_3V3AUX_SCL_R':
 C_SIGNAL='@t6g_mb_lib.t6g(sch_1):smb_lm75_3_3v3aux_scl_r';
NODE_NAME     R3721 1
 '@T6G_MB_LIB.T6G(SCH_1):PAGE251_I67@PURE_QUANTA.Q_RES(CHIPS)':
 'A': CDS_PINID='A';
NODE_NAME     U39 14
 '@T6G_MB_LIB.T6G(SCH_1):PAGE251_I74@PURE_QUANTA.TCA9548APWR(CHIPS)':
 'SC4': CDS_PINID='SC4';
NET_NAME
'SMB_LM75_3_3V3AUX_SCL_R1'
 '@T6G_MB_LIB.T6G(SCH_1):SMB_LM75_3_3V3AUX_SCL_R1':
 C_SIGNAL='@t6g_mb_lib.t6g(sch_1):smb_lm75_3_3v3aux_scl_r1';
NODE_NAME     R3553 2
 '@T6G_MB_LIB.T6G(SCH_1):PAGE359_I134@PURE_QUANTA.Q_RES(CHIPS)':
 'B': CDS_PINID='B';
NODE_NAME     U273 2
 '@T6G_MB_LIB.T6G(SCH_1):PAGE359_I167@PURE_QUANTA.LM75BD(CHIPS)':
 'SCL': CDS_PINID='SCL';
NET_NAME
'SMB_LM75_3_3V3AUX_SDA'
 '@T6G_MB_LIB.T6G(SCH_1):SMB_LM75_3_3V3AUX_SDA':
 C_SIGNAL='@t6g_mb_lib.t6g(sch_1):smb_lm75_3_3v3aux_sda';
NODE_NAME     R3554 1
 '@T6G_MB_LIB.T6G(SCH_1):PAGE359_I136@PURE_QUANTA.Q_RES(CHIPS)':
 'A': CDS_PINID='A';
NODE_NAME     R3732 2
 '@T6G_MB_LIB.T6G(SCH_1):PAGE251_I42@PURE_QUANTA.Q_RES(CHIPS)':
 'B': CDS_PINID='B';
NODE_NAME     R3722 2
 '@T6G_MB_LIB.T6G(SCH_1):PAGE251_I66@PURE_QUANTA.Q_RES(CHIPS)':
 'B': CDS_PINID='B';
NET_NAME
'SMB_LM75_3_3V3AUX_SDA_R'
 '@T6G_MB_LIB.T6G(SCH_1):SMB_LM75_3_3V3AUX_SDA_R':
 C_SIGNAL='@t6g_mb_lib.t6g(sch_1):smb_lm75_3_3v3aux_sda_r';
NODE_NAME     R3722 1
 '@T6G_MB_LIB.T6G(SCH_1):PAGE251_I66@PURE_QUANTA.Q_RES(CHIPS)':
 'A': CDS_PINID='A';
NODE_NAME     U39 13
 '@T6G_MB_LIB.T6G(SCH_1):PAGE251_I74@PURE_QUANTA.TCA9548APWR(CHIPS)':
 'SD4': CDS_PINID='SD4';
NET_NAME
'SMB_LM75_3_3V3AUX_SDA_R1'
 '@T6G_MB_LIB.T6G(SCH_1):SMB_LM75_3_3V3AUX_SDA_R1':
 C_SIGNAL='@t6g_mb_lib.t6g(sch_1):smb_lm75_3_3v3aux_sda_r1';
NODE_NAME     R3554 2
 '@T6G_MB_LIB.T6G(SCH_1):PAGE359_I136@PURE_QUANTA.Q_RES(CHIPS)':
 'B': CDS_PINID='B';
NODE_NAME     U273 1
 '@T6G_MB_LIB.T6G(SCH_1):PAGE359_I167@PURE_QUANTA.LM75BD(CHIPS)':
 'SDA': CDS_PINID='SDA';
NET_NAME
'SMB_M2_P1_1V8AUX_SCL'
 '@T6G_MB_LIB.T6G(SCH_1):SMB_M2_P1_1V8AUX_SCL':
 C_SIGNAL='@t6g_mb_lib.t6g(sch_1):smb_m2_p1_1v8aux_scl';
NODE_NAME     J59 40
 '@T6G_MB_LIB.T6G(SCH_1):PAGE345_I88@PURE_QUANTA.SCONN75K_APCI0155P004A(CHIPS)':
 'NC12': CDS_PINID='NC12';
NODE_NAME     R2411 2
 '@T6G_MB_LIB.T6G(SCH_1):PAGE346_I66@PURE_QUANTA.Q_RES(CHIPS)':
 'B': CDS_PINID='B';
NET_NAME
'SMB_M2_P1_1V8AUX_SCL_R'
 '@T6G_MB_LIB.T6G(SCH_1):SMB_M2_P1_1V8AUX_SCL_R':
 C_SIGNAL='@t6g_mb_lib.t6g(sch_1):smb_m2_p1_1v8aux_scl_r';
NODE_NAME     U98 3
 '@T6G_MB_LIB.T6G(SCH_1):PAGE346_I27@PURE_QUANTA.PCA9306DP1(CHIPS)':
 'SCL1': CDS_PINID='SCL1';
NODE_NAME     R1703 2
 '@T6G_MB_LIB.T6G(SCH_1):PAGE346_I45@PURE_QUANTA.Q_RES(CHIPS)':
 'B': CDS_PINID='B';
NODE_NAME     R2411 1
 '@T6G_MB_LIB.T6G(SCH_1):PAGE346_I66@PURE_QUANTA.Q_RES(CHIPS)':
 'A': CDS_PINID='A';
NET_NAME
'SMB_M2_P1_1V8AUX_SDA'
 '@T6G_MB_LIB.T6G(SCH_1):SMB_M2_P1_1V8AUX_SDA':
 C_SIGNAL='@t6g_mb_lib.t6g(sch_1):smb_m2_p1_1v8aux_sda';
NODE_NAME     J59 42
 '@T6G_MB_LIB.T6G(SCH_1):PAGE345_I88@PURE_QUANTA.SCONN75K_APCI0155P004A(CHIPS)':
 'NC13': CDS_PINID='NC13';
NODE_NAME     R2410 2
 '@T6G_MB_LIB.T6G(SCH_1):PAGE346_I65@PURE_QUANTA.Q_RES(CHIPS)':
 'B': CDS_PINID='B';
NET_NAME
'SMB_M2_P1_1V8AUX_SDA_R'
 '@T6G_MB_LIB.T6G(SCH_1):SMB_M2_P1_1V8AUX_SDA_R':
 C_SIGNAL='@t6g_mb_lib.t6g(sch_1):smb_m2_p1_1v8aux_sda_r';
NODE_NAME     U98 4
 '@T6G_MB_LIB.T6G(SCH_1):PAGE346_I27@PURE_QUANTA.PCA9306DP1(CHIPS)':
 'SDA1': CDS_PINID='SDA1';
NODE_NAME     R1702 2
 '@T6G_MB_LIB.T6G(SCH_1):PAGE346_I43@PURE_QUANTA.Q_RES(CHIPS)':
 'B': CDS_PINID='B';
NODE_NAME     R2410 1
 '@T6G_MB_LIB.T6G(SCH_1):PAGE346_I65@PURE_QUANTA.Q_RES(CHIPS)':
 'A': CDS_PINID='A';
NET_NAME
'SMB_MUX_RT_R1_SCL'
 '@T6G_MB_LIB.T6G(SCH_1):SMB_MUX_RT_R1_SCL':
 C_SIGNAL='@t6g_mb_lib.t6g(sch_1):smb_mux_rt_r1_scl';
NODE_NAME     R6784 1
 '@T6G_MB_LIB.T6G(SCH_1):PAGE349_I198@PURE_QUANTA.Q_RES(CHIPS)':
 'A': CDS_PINID='A';
NODE_NAME     R1514 1
 '@T6G_MB_LIB.T6G(SCH_1):PAGE378_I118@PURE_QUANTA.Q_RES(CHIPS)':
 'A': CDS_PINID='A';
NODE_NAME     R6780 2
 '@T6G_MB_LIB.T6G(SCH_1):PAGE378_I120@PURE_QUANTA.Q_RES(CHIPS)':
 'B': CDS_PINID='B';
NET_NAME
'SMB_MUX_RT_R1_SDA'
 '@T6G_MB_LIB.T6G(SCH_1):SMB_MUX_RT_R1_SDA':
 C_SIGNAL='@t6g_mb_lib.t6g(sch_1):smb_mux_rt_r1_sda';
NODE_NAME     R6785 1
 '@T6G_MB_LIB.T6G(SCH_1):PAGE349_I199@PURE_QUANTA.Q_RES(CHIPS)':
 'A': CDS_PINID='A';
NODE_NAME     R1515 1
 '@T6G_MB_LIB.T6G(SCH_1):PAGE378_I117@PURE_QUANTA.Q_RES(CHIPS)':
 'A': CDS_PINID='A';
NODE_NAME     R6779 2
 '@T6G_MB_LIB.T6G(SCH_1):PAGE378_I119@PURE_QUANTA.Q_RES(CHIPS)':
 'B': CDS_PINID='B';
NET_NAME
'SMB_MUX_RT_R2_SCL'
 '@T6G_MB_LIB.T6G(SCH_1):SMB_MUX_RT_R2_SCL':
 C_SIGNAL='@t6g_mb_lib.t6g(sch_1):smb_mux_rt_r2_scl';
NODE_NAME     JP6500 1
 '@T6G_MB_LIB.T6G(SCH_1):PAGE378_I116@PURE_QUANTA.CONN3_210HP1030BR1(CHIPS)':
 '1': CDS_PINID='\1\';
NODE_NAME     R1514 2
 '@T6G_MB_LIB.T6G(SCH_1):PAGE378_I118@PURE_QUANTA.Q_RES(CHIPS)':
 'B': CDS_PINID='B';
NET_NAME
'SMB_MUX_RT_R2_SDA'
 '@T6G_MB_LIB.T6G(SCH_1):SMB_MUX_RT_R2_SDA':
 C_SIGNAL='@t6g_mb_lib.t6g(sch_1):smb_mux_rt_r2_sda';
NODE_NAME     JP6500 2
 '@T6G_MB_LIB.T6G(SCH_1):PAGE378_I116@PURE_QUANTA.CONN3_210HP1030BR1(CHIPS)':
 '2': CDS_PINID='\2\';
NODE_NAME     R1515 2
 '@T6G_MB_LIB.T6G(SCH_1):PAGE378_I117@PURE_QUANTA.Q_RES(CHIPS)':
 'B': CDS_PINID='B';
NET_NAME
'SMB_MUX_RT_ROM_R1_SCL'
 '@T6G_MB_LIB.T6G(SCH_1):SMB_MUX_RT_ROM_R1_SCL':
 C_SIGNAL='@t6g_mb_lib.t6g(sch_1):smb_mux_rt_rom_r1_scl';
NODE_NAME     R851 2
 '@T6G_MB_LIB.T6G(SCH_1):PAGE377_I82@PURE_QUANTA.Q_RES(CHIPS)':
 'B': CDS_PINID='B';
NODE_NAME     R6782 1
 '@T6G_MB_LIB.T6G(SCH_1):PAGE349_I228@PURE_QUANTA.Q_RES(CHIPS)':
 'A': CDS_PINID='A';
NET_NAME
'SMB_MUX_RT_ROM_R1_SDA'
 '@T6G_MB_LIB.T6G(SCH_1):SMB_MUX_RT_ROM_R1_SDA':
 C_SIGNAL='@t6g_mb_lib.t6g(sch_1):smb_mux_rt_rom_r1_sda';
NODE_NAME     R850 2
 '@T6G_MB_LIB.T6G(SCH_1):PAGE377_I81@PURE_QUANTA.Q_RES(CHIPS)':
 'B': CDS_PINID='B';
NODE_NAME     R6783 1
 '@T6G_MB_LIB.T6G(SCH_1):PAGE349_I229@PURE_QUANTA.Q_RES(CHIPS)':
 'A': CDS_PINID='A';
NET_NAME
'SMB_MUX_RT_ROM_SCL'
 '@T6G_MB_LIB.T6G(SCH_1):SMB_MUX_RT_ROM_SCL':
 C_SIGNAL='@t6g_mb_lib.t6g(sch_1):smb_mux_rt_rom_scl';
NODE_NAME     R851 1
 '@T6G_MB_LIB.T6G(SCH_1):PAGE377_I82@PURE_QUANTA.Q_RES(CHIPS)':
 'A': CDS_PINID='A';
NODE_NAME     U22 22
 '@T6G_MB_LIB.T6G(SCH_1):PAGE377_I94@PURE_QUANTA.TCA9548APWR(CHIPS)':
 'SCL': CDS_PINID='SCL';
NET_NAME
'SMB_MUX_RT_ROM_SDA'
 '@T6G_MB_LIB.T6G(SCH_1):SMB_MUX_RT_ROM_SDA':
 C_SIGNAL='@t6g_mb_lib.t6g(sch_1):smb_mux_rt_rom_sda';
NODE_NAME     R850 1
 '@T6G_MB_LIB.T6G(SCH_1):PAGE377_I81@PURE_QUANTA.Q_RES(CHIPS)':
 'A': CDS_PINID='A';
NODE_NAME     U22 23
 '@T6G_MB_LIB.T6G(SCH_1):PAGE377_I94@PURE_QUANTA.TCA9548APWR(CHIPS)':
 'SDA': CDS_PINID='SDA';
NET_NAME
'SMB_MUX_RT_SCL'
 '@T6G_MB_LIB.T6G(SCH_1):SMB_MUX_RT_SCL':
 C_SIGNAL='@t6g_mb_lib.t6g(sch_1):smb_mux_rt_scl';
NODE_NAME     U6020 22
 '@T6G_MB_LIB.T6G(SCH_1):PAGE378_I1@PURE_QUANTA.TCA9548APWR(CHIPS)':
 'SCL': CDS_PINID='SCL';
NODE_NAME     R6780 1
 '@T6G_MB_LIB.T6G(SCH_1):PAGE378_I120@PURE_QUANTA.Q_RES(CHIPS)':
 'A': CDS_PINID='A';
NET_NAME
'SMB_MUX_RT_SDA'
 '@T6G_MB_LIB.T6G(SCH_1):SMB_MUX_RT_SDA':
 C_SIGNAL='@t6g_mb_lib.t6g(sch_1):smb_mux_rt_sda';
NODE_NAME     U6020 23
 '@T6G_MB_LIB.T6G(SCH_1):PAGE378_I1@PURE_QUANTA.TCA9548APWR(CHIPS)':
 'SDA': CDS_PINID='SDA';
NODE_NAME     R6779 1
 '@T6G_MB_LIB.T6G(SCH_1):PAGE378_I119@PURE_QUANTA.Q_RES(CHIPS)':
 'A': CDS_PINID='A';
NET_NAME
'SMB_OCP_SFF_3V3AUX_BUF_R_SCL'
 '@T6G_MB_LIB.T6G(SCH_1):SMB_OCP_SFF_3V3AUX_BUF_R_SCL':
 C_SIGNAL='@t6g_mb_lib.t6g(sch_1):smb_ocp_sff_3v3aux_buf_r_scl';
NODE_NAME     J38 A7
 '@T6G_MB_LIB.T6G(SCH_1):PAGE335_I168@PURE_QUANTA.SCONN168_ME1016810202011(CHIPS)':
 'SMCLK': CDS_PINID='SMCLK';
NODE_NAME     R47 1
 '@T6G_MB_LIB.T6G(SCH_1):PAGE335_I171@PURE_QUANTA.Q_RES(CHIPS)':
 'A': CDS_PINID='A';
NET_NAME
'SMB_OCP_SFF_3V3AUX_BUF_R_SDA'
 '@T6G_MB_LIB.T6G(SCH_1):SMB_OCP_SFF_3V3AUX_BUF_R_SDA':
 C_SIGNAL='@t6g_mb_lib.t6g(sch_1):smb_ocp_sff_3v3aux_buf_r_sda';
NODE_NAME     J38 A8
 '@T6G_MB_LIB.T6G(SCH_1):PAGE335_I168@PURE_QUANTA.SCONN168_ME1016810202011(CHIPS)':
 'SMDAT': CDS_PINID='SMDAT';
NODE_NAME     R48 1
 '@T6G_MB_LIB.T6G(SCH_1):PAGE335_I170@PURE_QUANTA.Q_RES(CHIPS)':
 'A': CDS_PINID='A';
NET_NAME
'SMB_OCP_SFF_3V3AUX_BUF_SCL'
 '@T6G_MB_LIB.T6G(SCH_1):SMB_OCP_SFF_3V3AUX_BUF_SCL':
 C_SIGNAL='@t6g_mb_lib.t6g(sch_1):smb_ocp_sff_3v3aux_buf_scl';
NODE_NAME     U236 7
 '@T6G_MB_LIB.T6G(SCH_1):PAGE248_I14@PURE_QUANTA.PCA9617ADP(CHIPS)':
 'SCLB': CDS_PINID='SCLB';
NODE_NAME     R3500 2
 '@T6G_MB_LIB.T6G(SCH_1):PAGE248_I27@PURE_QUANTA.Q_RES(CHIPS)':
 'B': CDS_PINID='B';
NODE_NAME     R47 2
 '@T6G_MB_LIB.T6G(SCH_1):PAGE335_I171@PURE_QUANTA.Q_RES(CHIPS)':
 'B': CDS_PINID='B';
NET_NAME
'SMB_OCP_SFF_3V3AUX_BUF_SDA'
 '@T6G_MB_LIB.T6G(SCH_1):SMB_OCP_SFF_3V3AUX_BUF_SDA':
 C_SIGNAL='@t6g_mb_lib.t6g(sch_1):smb_ocp_sff_3v3aux_buf_sda';
NODE_NAME     U236 6
 '@T6G_MB_LIB.T6G(SCH_1):PAGE248_I14@PURE_QUANTA.PCA9617ADP(CHIPS)':
 'SDAB': CDS_PINID='SDAB';
NODE_NAME     R3501 2
 '@T6G_MB_LIB.T6G(SCH_1):PAGE248_I31@PURE_QUANTA.Q_RES(CHIPS)':
 'B': CDS_PINID='B';
NODE_NAME     R48 2
 '@T6G_MB_LIB.T6G(SCH_1):PAGE335_I170@PURE_QUANTA.Q_RES(CHIPS)':
 'B': CDS_PINID='B';
NET_NAME
'SMB_OCP_SFF_3V3AUX_SCL'
 '@T6G_MB_LIB.T6G(SCH_1):SMB_OCP_SFF_3V3AUX_SCL':
 C_SIGNAL='@t6g_mb_lib.t6g(sch_1):smb_ocp_sff_3v3aux_scl';
NODE_NAME     R3240 1
 '@T6G_MB_LIB.T6G(SCH_1):PAGE349_I120@PURE_QUANTA.Q_RES(CHIPS)':
 'A': CDS_PINID='A';
NODE_NAME     U236 2
 '@T6G_MB_LIB.T6G(SCH_1):PAGE248_I14@PURE_QUANTA.PCA9617ADP(CHIPS)':
 'SCLA': CDS_PINID='SCLA';
NODE_NAME     R3238 1
 '@T6G_MB_LIB.T6G(SCH_1):PAGE348_I103@PURE_QUANTA.Q_RES(CHIPS)':
 'A': CDS_PINID='A';
NET_NAME
'SMB_OCP_SFF_3V3AUX_SCL_R0'
 '@T6G_MB_LIB.T6G(SCH_1):SMB_OCP_SFF_3V3AUX_SCL_R0':
 C_SIGNAL='@t6g_mb_lib.t6g(sch_1):smb_ocp_sff_3v3aux_scl_r0';
NODE_NAME     J41 A1
 '@T6G_MB_LIB.T6G(SCH_1):PAGE348_I176@PURE_QUANTA.SCONN168_ME1016810202011(CHIPS)':
 'GND_A1': CDS_PINID='GND_A1';
NODE_NAME     R3238 2
 '@T6G_MB_LIB.T6G(SCH_1):PAGE348_I103@PURE_QUANTA.Q_RES(CHIPS)':
 'B': CDS_PINID='B';
NET_NAME
'SMB_OCP_SFF_3V3AUX_SDA'
 '@T6G_MB_LIB.T6G(SCH_1):SMB_OCP_SFF_3V3AUX_SDA':
 C_SIGNAL='@t6g_mb_lib.t6g(sch_1):smb_ocp_sff_3v3aux_sda';
NODE_NAME     U236 3
 '@T6G_MB_LIB.T6G(SCH_1):PAGE248_I14@PURE_QUANTA.PCA9617ADP(CHIPS)':
 'SDAA': CDS_PINID='SDAA';
NODE_NAME     R3239 1
 '@T6G_MB_LIB.T6G(SCH_1):PAGE348_I102@PURE_QUANTA.Q_RES(CHIPS)':
 'A': CDS_PINID='A';
NODE_NAME     R3241 1
 '@T6G_MB_LIB.T6G(SCH_1):PAGE349_I149@PURE_QUANTA.Q_RES(CHIPS)':
 'A': CDS_PINID='A';
NET_NAME
'SMB_OCP_SFF_3V3AUX_SDA_R0'
 '@T6G_MB_LIB.T6G(SCH_1):SMB_OCP_SFF_3V3AUX_SDA_R0':
 C_SIGNAL='@t6g_mb_lib.t6g(sch_1):smb_ocp_sff_3v3aux_sda_r0';
NODE_NAME     J41 A2
 '@T6G_MB_LIB.T6G(SCH_1):PAGE348_I176@PURE_QUANTA.SCONN168_ME1016810202011(CHIPS)':
 'GND_A2': CDS_PINID='GND_A2';
NODE_NAME     R3239 2
 '@T6G_MB_LIB.T6G(SCH_1):PAGE348_I102@PURE_QUANTA.Q_RES(CHIPS)':
 'B': CDS_PINID='B';
NET_NAME
'SMB_OCP_V3_2_3V3AUX_BUF_R_SCL'
 '@T6G_MB_LIB.T6G(SCH_1):SMB_OCP_V3_2_3V3AUX_BUF_R_SCL':
 C_SIGNAL='@t6g_mb_lib.t6g(sch_1):smb_ocp_v3_2_3v3aux_buf_r_scl';
NODE_NAME     J35 A7
 '@T6G_MB_LIB.T6G(SCH_1):PAGE341_I168@PURE_QUANTA.SCONN168_ME1016810202011(CHIPS)':
 'SMCLK': CDS_PINID='SMCLK';
NODE_NAME     R3228 1
 '@T6G_MB_LIB.T6G(SCH_1):PAGE341_I171@PURE_QUANTA.Q_RES(CHIPS)':
 'A': CDS_PINID='A';
NET_NAME
'SMB_OCP_V3_2_3V3AUX_BUF_R_SDA'
 '@T6G_MB_LIB.T6G(SCH_1):SMB_OCP_V3_2_3V3AUX_BUF_R_SDA':
 C_SIGNAL='@t6g_mb_lib.t6g(sch_1):smb_ocp_v3_2_3v3aux_buf_r_sda';
NODE_NAME     J35 A8
 '@T6G_MB_LIB.T6G(SCH_1):PAGE341_I168@PURE_QUANTA.SCONN168_ME1016810202011(CHIPS)':
 'SMDAT': CDS_PINID='SMDAT';
NODE_NAME     R3229 1
 '@T6G_MB_LIB.T6G(SCH_1):PAGE341_I170@PURE_QUANTA.Q_RES(CHIPS)':
 'A': CDS_PINID='A';
NET_NAME
'SMB_OCP_V3_2_3V3AUX_BUF_SCL'
 '@T6G_MB_LIB.T6G(SCH_1):SMB_OCP_V3_2_3V3AUX_BUF_SCL':
 C_SIGNAL='@t6g_mb_lib.t6g(sch_1):smb_ocp_v3_2_3v3aux_buf_scl';
NODE_NAME     U235 7
 '@T6G_MB_LIB.T6G(SCH_1):PAGE248_I6@PURE_QUANTA.PCA9617ADP(CHIPS)':
 'SCLB': CDS_PINID='SCLB';
NODE_NAME     R3519 2
 '@T6G_MB_LIB.T6G(SCH_1):PAGE248_I34@PURE_QUANTA.Q_RES(CHIPS)':
 'B': CDS_PINID='B';
NODE_NAME     R3228 2
 '@T6G_MB_LIB.T6G(SCH_1):PAGE341_I171@PURE_QUANTA.Q_RES(CHIPS)':
 'B': CDS_PINID='B';
NET_NAME
'SMB_OCP_V3_2_3V3AUX_BUF_SDA'
 '@T6G_MB_LIB.T6G(SCH_1):SMB_OCP_V3_2_3V3AUX_BUF_SDA':
 C_SIGNAL='@t6g_mb_lib.t6g(sch_1):smb_ocp_v3_2_3v3aux_buf_sda';
NODE_NAME     U235 6
 '@T6G_MB_LIB.T6G(SCH_1):PAGE248_I6@PURE_QUANTA.PCA9617ADP(CHIPS)':
 'SDAB': CDS_PINID='SDAB';
NODE_NAME     R3520 2
 '@T6G_MB_LIB.T6G(SCH_1):PAGE248_I23@PURE_QUANTA.Q_RES(CHIPS)':
 'B': CDS_PINID='B';
NODE_NAME     R3229 2
 '@T6G_MB_LIB.T6G(SCH_1):PAGE341_I170@PURE_QUANTA.Q_RES(CHIPS)':
 'B': CDS_PINID='B';
NET_NAME
'SMB_OCP_V3_2_3V3AUX_SCL'
 '@T6G_MB_LIB.T6G(SCH_1):SMB_OCP_V3_2_3V3AUX_SCL':
 C_SIGNAL='@t6g_mb_lib.t6g(sch_1):smb_ocp_v3_2_3v3aux_scl';
NODE_NAME     R2425 1
 '@T6G_MB_LIB.T6G(SCH_1):PAGE348_I97@PURE_QUANTA.Q_RES(CHIPS)':
 'A': CDS_PINID='A';
NODE_NAME     U235 2
 '@T6G_MB_LIB.T6G(SCH_1):PAGE248_I6@PURE_QUANTA.PCA9617ADP(CHIPS)':
 'SCLA': CDS_PINID='SCLA';
NODE_NAME     R3242 1
 '@T6G_MB_LIB.T6G(SCH_1):PAGE349_I119@PURE_QUANTA.Q_RES(CHIPS)':
 'A': CDS_PINID='A';
NET_NAME
'SMB_OCP_V3_2_3V3AUX_SCL_R0'
 '@T6G_MB_LIB.T6G(SCH_1):SMB_OCP_V3_2_3V3AUX_SCL_R0':
 C_SIGNAL='@t6g_mb_lib.t6g(sch_1):smb_ocp_v3_2_3v3aux_scl_r0';
NODE_NAME     R2425 2
 '@T6G_MB_LIB.T6G(SCH_1):PAGE348_I97@PURE_QUANTA.Q_RES(CHIPS)':
 'B': CDS_PINID='B';
NODE_NAME     J41 A11
 '@T6G_MB_LIB.T6G(SCH_1):PAGE348_I176@PURE_QUANTA.SCONN168_ME1016810202011(CHIPS)':
 'PERST1#': CDS_PINID='\perst1#\';
NET_NAME
'SMB_OCP_V3_2_3V3AUX_SDA'
 '@T6G_MB_LIB.T6G(SCH_1):SMB_OCP_V3_2_3V3AUX_SDA':
 C_SIGNAL='@t6g_mb_lib.t6g(sch_1):smb_ocp_v3_2_3v3aux_sda';
NODE_NAME     R3858 1
 '@T6G_MB_LIB.T6G(SCH_1):PAGE348_I96@PURE_QUANTA.Q_RES(CHIPS)':
 'A': CDS_PINID='A';
NODE_NAME     R3243 1
 '@T6G_MB_LIB.T6G(SCH_1):PAGE349_I115@PURE_QUANTA.Q_RES(CHIPS)':
 'A': CDS_PINID='A';
NODE_NAME     U235 3
 '@T6G_MB_LIB.T6G(SCH_1):PAGE248_I6@PURE_QUANTA.PCA9617ADP(CHIPS)':
 'SDAA': CDS_PINID='SDAA';
NET_NAME
'SMB_OCP_V3_2_3V3AUX_SDA_R0'
 '@T6G_MB_LIB.T6G(SCH_1):SMB_OCP_V3_2_3V3AUX_SDA_R0':
 C_SIGNAL='@t6g_mb_lib.t6g(sch_1):smb_ocp_v3_2_3v3aux_sda_r0';
NODE_NAME     R3858 2
 '@T6G_MB_LIB.T6G(SCH_1):PAGE348_I96@PURE_QUANTA.Q_RES(CHIPS)':
 'B': CDS_PINID='B';
NODE_NAME     J41 A12
 '@T6G_MB_LIB.T6G(SCH_1):PAGE348_I176@PURE_QUANTA.SCONN168_ME1016810202011(CHIPS)':
 'PRSNTB2#': CDS_PINID='\prsntb2#\';
NET_NAME
'SMB_P12V_HSC_SCL'
 '@T6G_MB_LIB.T6G(SCH_1):SMB_P12V_HSC_SCL':
 C_SIGNAL='@t6g_mb_lib.t6g(sch_1):smb_p12v_hsc_scl';
NODE_NAME     R2626 2
 '@T6G_MB_LIB.T6G(SCH_1):PAGE371_I40@PURE_QUANTA.Q_RES(CHIPS)':
 'B': CDS_PINID='B';
NODE_NAME     R6229 2
 '@T6G_MB_LIB.T6G(SCH_1):PAGE251_I76@PURE_QUANTA.Q_RES(CHIPS)':
 'B': CDS_PINID='B';
NODE_NAME     R6231 2
 '@T6G_MB_LIB.T6G(SCH_1):PAGE371_I46@PURE_QUANTA.Q_RES(CHIPS)':
 'B': CDS_PINID='B';
NET_NAME
'SMB_P12V_HSC_SCL_R'
 '@T6G_MB_LIB.T6G(SCH_1):SMB_P12V_HSC_SCL_R':
 C_SIGNAL='@t6g_mb_lib.t6g(sch_1):smb_p12v_hsc_scl_r';
NODE_NAME     U39 16
 '@T6G_MB_LIB.T6G(SCH_1):PAGE251_I74@PURE_QUANTA.TCA9548APWR(CHIPS)':
 'SC5': CDS_PINID='SC5';
NODE_NAME     R6229 1
 '@T6G_MB_LIB.T6G(SCH_1):PAGE251_I76@PURE_QUANTA.Q_RES(CHIPS)':
 'A': CDS_PINID='A';
NET_NAME
'SMB_P12V_HSC_SDA'
 '@T6G_MB_LIB.T6G(SCH_1):SMB_P12V_HSC_SDA':
 C_SIGNAL='@t6g_mb_lib.t6g(sch_1):smb_p12v_hsc_sda';
NODE_NAME     R2627 2
 '@T6G_MB_LIB.T6G(SCH_1):PAGE371_I39@PURE_QUANTA.Q_RES(CHIPS)':
 'B': CDS_PINID='B';
NODE_NAME     R6228 2
 '@T6G_MB_LIB.T6G(SCH_1):PAGE251_I75@PURE_QUANTA.Q_RES(CHIPS)':
 'B': CDS_PINID='B';
NODE_NAME     R6230 2
 '@T6G_MB_LIB.T6G(SCH_1):PAGE371_I45@PURE_QUANTA.Q_RES(CHIPS)':
 'B': CDS_PINID='B';
NET_NAME
'SMB_P12V_HSC_SDA_R'
 '@T6G_MB_LIB.T6G(SCH_1):SMB_P12V_HSC_SDA_R':
 C_SIGNAL='@t6g_mb_lib.t6g(sch_1):smb_p12v_hsc_sda_r';
NODE_NAME     U39 15
 '@T6G_MB_LIB.T6G(SCH_1):PAGE251_I74@PURE_QUANTA.TCA9548APWR(CHIPS)':
 'SD5': CDS_PINID='SD5';
NODE_NAME     R6228 1
 '@T6G_MB_LIB.T6G(SCH_1):PAGE251_I75@PURE_QUANTA.Q_RES(CHIPS)':
 'A': CDS_PINID='A';
NET_NAME
'SMB_P12V_HSC_TEMP_SCL'
 '@T6G_MB_LIB.T6G(SCH_1):SMB_P12V_HSC_TEMP_SCL':
 C_SIGNAL='@t6g_mb_lib.t6g(sch_1):smb_p12v_hsc_temp_scl';
NODE_NAME     U143 8
 '@T6G_MB_LIB.T6G(SCH_1):PAGE371_I8@PURE_QUANTA.NCT7718W(CHIPS)':
 'SCL': CDS_PINID='SCL';
NODE_NAME     R2626 1
 '@T6G_MB_LIB.T6G(SCH_1):PAGE371_I40@PURE_QUANTA.Q_RES(CHIPS)':
 'A': CDS_PINID='A';
NET_NAME
'SMB_P12V_HSC_TEMP_SDA'
 '@T6G_MB_LIB.T6G(SCH_1):SMB_P12V_HSC_TEMP_SDA':
 C_SIGNAL='@t6g_mb_lib.t6g(sch_1):smb_p12v_hsc_temp_sda';
NODE_NAME     U143 7
 '@T6G_MB_LIB.T6G(SCH_1):PAGE371_I8@PURE_QUANTA.NCT7718W(CHIPS)':
 'SDA': CDS_PINID='SDA';
NODE_NAME     R2627 1
 '@T6G_MB_LIB.T6G(SCH_1):PAGE371_I39@PURE_QUANTA.Q_RES(CHIPS)':
 'A': CDS_PINID='A';
NET_NAME
'SMB_PCIE0_3V3AUX_SCL'
 '@T6G_MB_LIB.T6G(SCH_1):SMB_PCIE0_3V3AUX_SCL':
 C_SIGNAL='@t6g_mb_lib.t6g(sch_1):smb_pcie0_3v3aux_scl';
NODE_NAME     J41 A23
 '@T6G_MB_LIB.T6G(SCH_1):PAGE348_I176@PURE_QUANTA.SCONN168_ME1016810202011(CHIPS)':
 'PERN2': CDS_PINID='PERN2';
NODE_NAME     R2204 2
 '@T6G_MB_LIB.T6G(SCH_1):PAGE252_I50@PURE_QUANTA.Q_RES(CHIPS)':
 'B': CDS_PINID='B';
NODE_NAME     R65 1
 '@T6G_MB_LIB.T6G(SCH_1):PAGE252_I74@PURE_QUANTA.Q_RES(CHIPS)':
 'A': CDS_PINID='A';
NET_NAME
'SMB_PCIE0_3V3AUX_SCL_R'
 '@T6G_MB_LIB.T6G(SCH_1):SMB_PCIE0_3V3AUX_SCL_R':
 C_SIGNAL='@t6g_mb_lib.t6g(sch_1):smb_pcie0_3v3aux_scl_r';
NODE_NAME     U36 22
 '@T6G_MB_LIB.T6G(SCH_1):PAGE252_I33@PURE_QUANTA.TCA9548APWR(CHIPS)':
 'SCL': CDS_PINID='SCL';
NODE_NAME     R65 2
 '@T6G_MB_LIB.T6G(SCH_1):PAGE252_I74@PURE_QUANTA.Q_RES(CHIPS)':
 'B': CDS_PINID='B';
NET_NAME
'SMB_PCIE0_3V3AUX_SCL_R3'
 '@T6G_MB_LIB.T6G(SCH_1):SMB_PCIE0_3V3AUX_SCL_R3':
 C_SIGNAL='@t6g_mb_lib.t6g(sch_1):smb_pcie0_3v3aux_scl_r3';
NODE_NAME     R2967 1
 '@T6G_MB_LIB.T6G(SCH_1):PAGE252_I25@PURE_QUANTA.Q_RES(CHIPS)':
 'A': CDS_PINID='A';
NODE_NAME     U36 9
 '@T6G_MB_LIB.T6G(SCH_1):PAGE252_I33@PURE_QUANTA.TCA9548APWR(CHIPS)':
 'SC2': CDS_PINID='SC2';
NET_NAME
'SMB_PCIE0_3V3AUX_SCL_R5'
 '@T6G_MB_LIB.T6G(SCH_1):SMB_PCIE0_3V3AUX_SCL_R5':
 C_SIGNAL='@t6g_mb_lib.t6g(sch_1):smb_pcie0_3v3aux_scl_r5';
NODE_NAME     R3526 1
 '@T6G_MB_LIB.T6G(SCH_1):PAGE252_I23@PURE_QUANTA.Q_RES(CHIPS)':
 'A': CDS_PINID='A';
NODE_NAME     U36 11
 '@T6G_MB_LIB.T6G(SCH_1):PAGE252_I33@PURE_QUANTA.TCA9548APWR(CHIPS)':
 'SC3': CDS_PINID='SC3';
NET_NAME
'SMB_PCIE0_3V3AUX_SDA'
 '@T6G_MB_LIB.T6G(SCH_1):SMB_PCIE0_3V3AUX_SDA':
 C_SIGNAL='@t6g_mb_lib.t6g(sch_1):smb_pcie0_3v3aux_sda';
NODE_NAME     J41 A24
 '@T6G_MB_LIB.T6G(SCH_1):PAGE348_I176@PURE_QUANTA.SCONN168_ME1016810202011(CHIPS)':
 'PERP2': CDS_PINID='PERP2';
NODE_NAME     R2205 2
 '@T6G_MB_LIB.T6G(SCH_1):PAGE252_I49@PURE_QUANTA.Q_RES(CHIPS)':
 'B': CDS_PINID='B';
NODE_NAME     R55 1
 '@T6G_MB_LIB.T6G(SCH_1):PAGE252_I73@PURE_QUANTA.Q_RES(CHIPS)':
 'A': CDS_PINID='A';
NET_NAME
'SMB_PCIE0_3V3AUX_SDA_R'
 '@T6G_MB_LIB.T6G(SCH_1):SMB_PCIE0_3V3AUX_SDA_R':
 C_SIGNAL='@t6g_mb_lib.t6g(sch_1):smb_pcie0_3v3aux_sda_r';
NODE_NAME     U36 23
 '@T6G_MB_LIB.T6G(SCH_1):PAGE252_I33@PURE_QUANTA.TCA9548APWR(CHIPS)':
 'SDA': CDS_PINID='SDA';
NODE_NAME     R55 2
 '@T6G_MB_LIB.T6G(SCH_1):PAGE252_I73@PURE_QUANTA.Q_RES(CHIPS)':
 'B': CDS_PINID='B';
NET_NAME
'SMB_PCIE0_3V3AUX_SDA_R3'
 '@T6G_MB_LIB.T6G(SCH_1):SMB_PCIE0_3V3AUX_SDA_R3':
 C_SIGNAL='@t6g_mb_lib.t6g(sch_1):smb_pcie0_3v3aux_sda_r3';
NODE_NAME     R2968 1
 '@T6G_MB_LIB.T6G(SCH_1):PAGE252_I26@PURE_QUANTA.Q_RES(CHIPS)':
 'A': CDS_PINID='A';
NODE_NAME     U36 8
 '@T6G_MB_LIB.T6G(SCH_1):PAGE252_I33@PURE_QUANTA.TCA9548APWR(CHIPS)':
 'SD2': CDS_PINID='SD2';
NET_NAME
'SMB_PCIE0_3V3AUX_SDA_R5'
 '@T6G_MB_LIB.T6G(SCH_1):SMB_PCIE0_3V3AUX_SDA_R5':
 C_SIGNAL='@t6g_mb_lib.t6g(sch_1):smb_pcie0_3v3aux_sda_r5';
NODE_NAME     R3527 1
 '@T6G_MB_LIB.T6G(SCH_1):PAGE252_I24@PURE_QUANTA.Q_RES(CHIPS)':
 'A': CDS_PINID='A';
NODE_NAME     U36 10
 '@T6G_MB_LIB.T6G(SCH_1):PAGE252_I33@PURE_QUANTA.TCA9548APWR(CHIPS)':
 'SD3': CDS_PINID='SD3';
NET_NAME
'SMB_PCIE2_3V3AUX_SCL_R0'
 '@T6G_MB_LIB.T6G(SCH_1):SMB_PCIE2_3V3AUX_SCL_R0':
 C_SIGNAL='@t6g_mb_lib.t6g(sch_1):smb_pcie2_3v3aux_scl_r0';
NODE_NAME     R2413 2
 '@T6G_MB_LIB.T6G(SCH_1):PAGE348_I86@PURE_QUANTA.Q_RES(CHIPS)':
 'B': CDS_PINID='B';
NODE_NAME     J41 A31
 '@T6G_MB_LIB.T6G(SCH_1):PAGE348_I176@PURE_QUANTA.SCONN168_ME1016810202011(CHIPS)':
 'PERP4': CDS_PINID='PERP4';
NET_NAME
'SMB_PCIE2_3V3AUX_SDA_R0'
 '@T6G_MB_LIB.T6G(SCH_1):SMB_PCIE2_3V3AUX_SDA_R0':
 C_SIGNAL='@t6g_mb_lib.t6g(sch_1):smb_pcie2_3v3aux_sda_r0';
NODE_NAME     R2414 2
 '@T6G_MB_LIB.T6G(SCH_1):PAGE348_I85@PURE_QUANTA.Q_RES(CHIPS)':
 'B': CDS_PINID='B';
NODE_NAME     J41 A32
 '@T6G_MB_LIB.T6G(SCH_1):PAGE348_I176@PURE_QUANTA.SCONN168_ME1016810202011(CHIPS)':
 'GND_A32': CDS_PINID='GND_A32';
NET_NAME
'SMB_PCIE3_3V3AUX_SCL_R'
 '@T6G_MB_LIB.T6G(SCH_1):SMB_PCIE3_3V3AUX_SCL_R':
 C_SIGNAL='@t6g_mb_lib.t6g(sch_1):smb_pcie3_3v3aux_scl_r';
NODE_NAME     J41 A38
 '@T6G_MB_LIB.T6G(SCH_1):PAGE348_I176@PURE_QUANTA.SCONN168_ME1016810202011(CHIPS)':
 'GND_A38': CDS_PINID='GND_A38';
NODE_NAME     R2415 2
 '@T6G_MB_LIB.T6G(SCH_1):PAGE348_I60@PURE_QUANTA.Q_RES(CHIPS)':
 'B': CDS_PINID='B';
NET_NAME
'SMB_PCIE3_3V3AUX_SDA_R'
 '@T6G_MB_LIB.T6G(SCH_1):SMB_PCIE3_3V3AUX_SDA_R':
 C_SIGNAL='@t6g_mb_lib.t6g(sch_1):smb_pcie3_3v3aux_sda_r';
NODE_NAME     J41 A39
 '@T6G_MB_LIB.T6G(SCH_1):PAGE348_I176@PURE_QUANTA.SCONN168_ME1016810202011(CHIPS)':
 'PERN7': CDS_PINID='PERN7';
NODE_NAME     R2416 2
 '@T6G_MB_LIB.T6G(SCH_1):PAGE348_I33@PURE_QUANTA.Q_RES(CHIPS)':
 'B': CDS_PINID='B';
NET_NAME
'SMB_PCIE_E1S_ISO_EN'
 '@T6G_MB_LIB.T6G(SCH_1):SMB_PCIE_E1S_ISO_EN':
 C_SIGNAL='@t6g_mb_lib.t6g(sch_1):smb_pcie_e1s_iso_en';
NODE_NAME     R3531 1
 '@T6G_MB_LIB.T6G(SCH_1):PAGE346_I96@PURE_QUANTA.Q_RES(CHIPS)':
 'A': CDS_PINID='A';
NODE_NAME     R2114 2
 '@T6G_MB_LIB.T6G(SCH_1):PAGE297_I37@PURE_QUANTA.Q_RES(CHIPS)':
 'B': CDS_PINID='B';
NODE_NAME     R2125 2
 '@T6G_MB_LIB.T6G(SCH_1):PAGE297_I40@PURE_QUANTA.Q_RES(CHIPS)':
 'B': CDS_PINID='B';
NET_NAME
'SMB_PCIE_E1S_ISO_EN_R'
 '@T6G_MB_LIB.T6G(SCH_1):SMB_PCIE_E1S_ISO_EN_R':
 C_SIGNAL='@t6g_mb_lib.t6g(sch_1):smb_pcie_e1s_iso_en_r';
NODE_NAME     U279 5
 '@T6G_MB_LIB.T6G(SCH_1):PAGE346_I93@PURE_QUANTA.PCA9617ADP(CHIPS)':
 'EN': CDS_PINID='EN';
NODE_NAME     R3531 2
 '@T6G_MB_LIB.T6G(SCH_1):PAGE346_I96@PURE_QUANTA.Q_RES(CHIPS)':
 'B': CDS_PINID='B';
NODE_NAME     R3529 2
 '@T6G_MB_LIB.T6G(SCH_1):PAGE346_I99@PURE_QUANTA.Q_RES(CHIPS)':
 'B': CDS_PINID='B';
NET_NAME
'SMB_PCIE_E1S_ISO_EN_R2'
 '@T6G_MB_LIB.T6G(SCH_1):SMB_PCIE_E1S_ISO_EN_R2':
 C_SIGNAL='@t6g_mb_lib.t6g(sch_1):smb_pcie_e1s_iso_en_r2';
NODE_NAME     U134 4
 '@T6G_MB_LIB.T6G(SCH_1):PAGE297_I4@PURE_QUANTA.74LVC2G07DW7(CHIPS)':
 '2Y': CDS_PINID='\2y\';
NODE_NAME     R2114 1
 '@T6G_MB_LIB.T6G(SCH_1):PAGE297_I37@PURE_QUANTA.Q_RES(CHIPS)':
 'A': CDS_PINID='A';
NET_NAME
'SMB_PCIE_M2_0_EN'
 '@T6G_MB_LIB.T6G(SCH_1):SMB_PCIE_M2_0_EN':
 C_SIGNAL='@t6g_mb_lib.t6g(sch_1):smb_pcie_m2_0_en';
NODE_NAME     U98 8
 '@T6G_MB_LIB.T6G(SCH_1):PAGE346_I27@PURE_QUANTA.PCA9306DP1(CHIPS)':
 'EN': CDS_PINID='EN';
NODE_NAME     U98 7
 '@T6G_MB_LIB.T6G(SCH_1):PAGE346_I27@PURE_QUANTA.PCA9306DP1(CHIPS)':
 'VREF2': CDS_PINID='VREF2';
NODE_NAME     R2476 1
 '@T6G_MB_LIB.T6G(SCH_1):PAGE346_I70@PURE_QUANTA.Q_RES(CHIPS)':
 'A': CDS_PINID='A';
NODE_NAME     R1700 2
 '@T6G_MB_LIB.T6G(SCH_1):PAGE346_I72@PURE_QUANTA.Q_RES(CHIPS)':
 'B': CDS_PINID='B';
NET_NAME
'SMB_PMBUS_3V3AUX_SCL'
 '@T6G_MB_LIB.T6G(SCH_1):SMB_PMBUS_3V3AUX_SCL':
 C_SIGNAL='@t6g_mb_lib.t6g(sch_1):smb_pmbus_3v3aux_scl';
NODE_NAME     R1386 1
 '@T6G_MB_LIB.T6G(SCH_1):PAGE349_I134@PURE_QUANTA.Q_RES(CHIPS)':
 'A': CDS_PINID='A';
NODE_NAME     R2995 1
 '@T6G_MB_LIB.T6G(SCH_1):PAGE349_I91@PURE_QUANTA.Q_RES(CHIPS)':
 'A': CDS_PINID='A';
NODE_NAME     R2423 1
 '@T6G_MB_LIB.T6G(SCH_1):PAGE348_I196@PURE_QUANTA.Q_RES(CHIPS)':
 'A': CDS_PINID='A';
NET_NAME
'SMB_PMBUS_3V3AUX_SCL_R0'
 '@T6G_MB_LIB.T6G(SCH_1):SMB_PMBUS_3V3AUX_SCL_R0':
 C_SIGNAL='@t6g_mb_lib.t6g(sch_1):smb_pmbus_3v3aux_scl_r0';
NODE_NAME     J41 A25
 '@T6G_MB_LIB.T6G(SCH_1):PAGE348_I176@PURE_QUANTA.SCONN168_ME1016810202011(CHIPS)':
 'GND_A25': CDS_PINID='GND_A25';
NODE_NAME     R2423 2
 '@T6G_MB_LIB.T6G(SCH_1):PAGE348_I196@PURE_QUANTA.Q_RES(CHIPS)':
 'B': CDS_PINID='B';
NET_NAME
'SMB_PMBUS_3V3AUX_SDA'
 '@T6G_MB_LIB.T6G(SCH_1):SMB_PMBUS_3V3AUX_SDA':
 C_SIGNAL='@t6g_mb_lib.t6g(sch_1):smb_pmbus_3v3aux_sda';
NODE_NAME     R329 1
 '@T6G_MB_LIB.T6G(SCH_1):PAGE349_I133@PURE_QUANTA.Q_RES(CHIPS)':
 'A': CDS_PINID='A';
NODE_NAME     R2996 1
 '@T6G_MB_LIB.T6G(SCH_1):PAGE349_I92@PURE_QUANTA.Q_RES(CHIPS)':
 'A': CDS_PINID='A';
NODE_NAME     R2424 1
 '@T6G_MB_LIB.T6G(SCH_1):PAGE348_I195@PURE_QUANTA.Q_RES(CHIPS)':
 'A': CDS_PINID='A';
NET_NAME
'SMB_PMBUS_3V3AUX_SDA_R0'
 '@T6G_MB_LIB.T6G(SCH_1):SMB_PMBUS_3V3AUX_SDA_R0':
 C_SIGNAL='@t6g_mb_lib.t6g(sch_1):smb_pmbus_3v3aux_sda_r0';
NODE_NAME     J41 A26
 '@T6G_MB_LIB.T6G(SCH_1):PAGE348_I176@PURE_QUANTA.SCONN168_ME1016810202011(CHIPS)':
 'PERN3': CDS_PINID='PERN3';
NODE_NAME     R2424 2
 '@T6G_MB_LIB.T6G(SCH_1):PAGE348_I195@PURE_QUANTA.Q_RES(CHIPS)':
 'B': CDS_PINID='B';
NET_NAME
'SMB_RT_CPU0_P0_R2_SCL'
 '@T6G_MB_LIB.T6G(SCH_1):SMB_RT_CPU0_P0_R2_SCL':
 C_SIGNAL='@t6g_mb_lib.t6g(sch_1):smb_rt_cpu0_p0_r2_scl';
NODE_NAME     R976 2
 '@T6G_MB_LIB.T6G(SCH_1):PAGE385_I50@PURE_QUANTA.Q_RES(CHIPS)':
 'B': CDS_PINID='B';
NODE_NAME     U6010 B31
 '@T6G_MB_LIB.T6G(SCH_1):PAGE385_I53@PURE_QUANTA.PT5161LRS(CHIPS)':
 'SMBCLK': CDS_PINID='SMBCLK';
NET_NAME
'SMB_RT_CPU0_P0_R2_SDA'
 '@T6G_MB_LIB.T6G(SCH_1):SMB_RT_CPU0_P0_R2_SDA':
 C_SIGNAL='@t6g_mb_lib.t6g(sch_1):smb_rt_cpu0_p0_r2_sda';
NODE_NAME     R977 2
 '@T6G_MB_LIB.T6G(SCH_1):PAGE385_I49@PURE_QUANTA.Q_RES(CHIPS)':
 'B': CDS_PINID='B';
NODE_NAME     U6010 B28
 '@T6G_MB_LIB.T6G(SCH_1):PAGE385_I53@PURE_QUANTA.PT5161LRS(CHIPS)':
 'SMBDAT': CDS_PINID='SMBDAT';
NET_NAME
'SMB_RT_CPU0_P0_ROM_MUX_1D_R_SCL'
 '@T6G_MB_LIB.T6G(SCH_1):SMB_RT_CPU0_P0_ROM_MUX_1D_R_SCL':
 C_SIGNAL='@t6g_mb_lib.t6g(sch_1):smb_rt_cpu0_p0_rom_mux_1d_r_scl';
NODE_NAME     R666 2
 '@T6G_MB_LIB.T6G(SCH_1):PAGE385_I42@PURE_QUANTA.Q_RES(CHIPS)':
 'B': CDS_PINID='B';
NODE_NAME     U6010 FF5
 '@T6G_MB_LIB.T6G(SCH_1):PAGE385_I53@PURE_QUANTA.PT5161LRS(CHIPS)':
 'EE_CLK': CDS_PINID='EE_CLK';
NET_NAME
'SMB_RT_CPU0_P0_ROM_MUX_1D_R_SDA'
 '@T6G_MB_LIB.T6G(SCH_1):SMB_RT_CPU0_P0_ROM_MUX_1D_R_SDA':
 C_SIGNAL='@t6g_mb_lib.t6g(sch_1):smb_rt_cpu0_p0_rom_mux_1d_r_sda';
NODE_NAME     R667 2
 '@T6G_MB_LIB.T6G(SCH_1):PAGE385_I41@PURE_QUANTA.Q_RES(CHIPS)':
 'B': CDS_PINID='B';
NODE_NAME     U6010 FJ3
 '@T6G_MB_LIB.T6G(SCH_1):PAGE385_I53@PURE_QUANTA.PT5161LRS(CHIPS)':
 'EE_DAT': CDS_PINID='EE_DAT';
NET_NAME
'SMB_RT_CPU0_P0_ROM_MUX_1D_SCL'
 '@T6G_MB_LIB.T6G(SCH_1):SMB_RT_CPU0_P0_ROM_MUX_1D_SCL':
 C_SIGNAL='@t6g_mb_lib.t6g(sch_1):smb_rt_cpu0_p0_rom_mux_1d_scl';
NODE_NAME     R666 1
 '@T6G_MB_LIB.T6G(SCH_1):PAGE385_I42@PURE_QUANTA.Q_RES(CHIPS)':
 'A': CDS_PINID='A';
NODE_NAME     U49 1
 '@T6G_MB_LIB.T6G(SCH_1):PAGE376_I85@PURE_QUANTA.PI3CSW12ZUAEX(CHIPS)':
 '1D+': CDS_PINID='\1d+\';
NODE_NAME     R1411 2
 '@T6G_MB_LIB.T6G(SCH_1):PAGE377_I165@PURE_QUANTA.Q_RES(CHIPS)':
 'B': CDS_PINID='B';
NET_NAME
'SMB_RT_CPU0_P0_ROM_MUX_1D_SDA'
 '@T6G_MB_LIB.T6G(SCH_1):SMB_RT_CPU0_P0_ROM_MUX_1D_SDA':
 C_SIGNAL='@t6g_mb_lib.t6g(sch_1):smb_rt_cpu0_p0_rom_mux_1d_sda';
NODE_NAME     R667 1
 '@T6G_MB_LIB.T6G(SCH_1):PAGE385_I41@PURE_QUANTA.Q_RES(CHIPS)':
 'A': CDS_PINID='A';
NODE_NAME     U49 2
 '@T6G_MB_LIB.T6G(SCH_1):PAGE376_I85@PURE_QUANTA.PI3CSW12ZUAEX(CHIPS)':
 '1D-': CDS_PINID='\1d-\';
NODE_NAME     R1410 2
 '@T6G_MB_LIB.T6G(SCH_1):PAGE377_I164@PURE_QUANTA.Q_RES(CHIPS)':
 'B': CDS_PINID='B';
NET_NAME
'SMB_RT_CPU0_P0_ROM_MUX_2D_R_SCL'
 '@T6G_MB_LIB.T6G(SCH_1):SMB_RT_CPU0_P0_ROM_MUX_2D_R_SCL':
 C_SIGNAL='@t6g_mb_lib.t6g(sch_1):smb_rt_cpu0_p0_rom_mux_2d_r_scl';
NODE_NAME     R799 1
 '@T6G_MB_LIB.T6G(SCH_1):PAGE377_I79@PURE_QUANTA.Q_RES(CHIPS)':
 'A': CDS_PINID='A';
NODE_NAME     U22 14
 '@T6G_MB_LIB.T6G(SCH_1):PAGE377_I94@PURE_QUANTA.TCA9548APWR(CHIPS)':
 'SC4': CDS_PINID='SC4';
NODE_NAME     R1367 2
 '@T6G_MB_LIB.T6G(SCH_1):PAGE377_I121@PURE_QUANTA.Q_RES(CHIPS)':
 'B': CDS_PINID='B';
NET_NAME
'SMB_RT_CPU0_P0_ROM_MUX_2D_R_SDA'
 '@T6G_MB_LIB.T6G(SCH_1):SMB_RT_CPU0_P0_ROM_MUX_2D_R_SDA':
 C_SIGNAL='@t6g_mb_lib.t6g(sch_1):smb_rt_cpu0_p0_rom_mux_2d_r_sda';
NODE_NAME     R797 1
 '@T6G_MB_LIB.T6G(SCH_1):PAGE377_I80@PURE_QUANTA.Q_RES(CHIPS)':
 'A': CDS_PINID='A';
NODE_NAME     U22 13
 '@T6G_MB_LIB.T6G(SCH_1):PAGE377_I94@PURE_QUANTA.TCA9548APWR(CHIPS)':
 'SD4': CDS_PINID='SD4';
NODE_NAME     R1366 2
 '@T6G_MB_LIB.T6G(SCH_1):PAGE377_I122@PURE_QUANTA.Q_RES(CHIPS)':
 'B': CDS_PINID='B';
NET_NAME
'SMB_RT_CPU0_P0_ROM_MUX_2D_SCL'
 '@T6G_MB_LIB.T6G(SCH_1):SMB_RT_CPU0_P0_ROM_MUX_2D_SCL':
 C_SIGNAL='@t6g_mb_lib.t6g(sch_1):smb_rt_cpu0_p0_rom_mux_2d_scl';
NODE_NAME     R799 2
 '@T6G_MB_LIB.T6G(SCH_1):PAGE377_I79@PURE_QUANTA.Q_RES(CHIPS)':
 'B': CDS_PINID='B';
NODE_NAME     U49 3
 '@T6G_MB_LIB.T6G(SCH_1):PAGE376_I85@PURE_QUANTA.PI3CSW12ZUAEX(CHIPS)':
 '2D+': CDS_PINID='\2d+\';
NET_NAME
'SMB_RT_CPU0_P0_ROM_MUX_2D_SDA'
 '@T6G_MB_LIB.T6G(SCH_1):SMB_RT_CPU0_P0_ROM_MUX_2D_SDA':
 C_SIGNAL='@t6g_mb_lib.t6g(sch_1):smb_rt_cpu0_p0_rom_mux_2d_sda';
NODE_NAME     R797 2
 '@T6G_MB_LIB.T6G(SCH_1):PAGE377_I80@PURE_QUANTA.Q_RES(CHIPS)':
 'B': CDS_PINID='B';
NODE_NAME     U49 4
 '@T6G_MB_LIB.T6G(SCH_1):PAGE376_I85@PURE_QUANTA.PI3CSW12ZUAEX(CHIPS)':
 '2D-': CDS_PINID='\2d-\';
NET_NAME
'SMB_RT_CPU0_P0_ROM_R_SCL'
 '@T6G_MB_LIB.T6G(SCH_1):SMB_RT_CPU0_P0_ROM_R_SCL':
 C_SIGNAL='@t6g_mb_lib.t6g(sch_1):smb_rt_cpu0_p0_rom_r_scl';
NODE_NAME     R668 1
 '@T6G_MB_LIB.T6G(SCH_1):PAGE387_I6@PURE_QUANTA.Q_RES(CHIPS)':
 'A': CDS_PINID='A';
NODE_NAME     R835 2
 '@T6G_MB_LIB.T6G(SCH_1):PAGE377_I23@PURE_QUANTA.Q_RES(CHIPS)':
 'B': CDS_PINID='B';
NODE_NAME     U49 8
 '@T6G_MB_LIB.T6G(SCH_1):PAGE376_I85@PURE_QUANTA.PI3CSW12ZUAEX(CHIPS)':
 'D+': CDS_PINID='\d+\';
NET_NAME
'SMB_RT_CPU0_P0_ROM_R_SDA'
 '@T6G_MB_LIB.T6G(SCH_1):SMB_RT_CPU0_P0_ROM_R_SDA':
 C_SIGNAL='@t6g_mb_lib.t6g(sch_1):smb_rt_cpu0_p0_rom_r_sda';
NODE_NAME     R669 1
 '@T6G_MB_LIB.T6G(SCH_1):PAGE387_I7@PURE_QUANTA.Q_RES(CHIPS)':
 'A': CDS_PINID='A';
NODE_NAME     R834 2
 '@T6G_MB_LIB.T6G(SCH_1):PAGE377_I24@PURE_QUANTA.Q_RES(CHIPS)':
 'B': CDS_PINID='B';
NODE_NAME     U49 7
 '@T6G_MB_LIB.T6G(SCH_1):PAGE376_I85@PURE_QUANTA.PI3CSW12ZUAEX(CHIPS)':
 'D-': CDS_PINID='\d-\';
NET_NAME
'SMB_RT_CPU0_P0_ROM_SCL'
 '@T6G_MB_LIB.T6G(SCH_1):SMB_RT_CPU0_P0_ROM_SCL':
 C_SIGNAL='@t6g_mb_lib.t6g(sch_1):smb_rt_cpu0_p0_rom_scl';
NODE_NAME     U11 6
 '@T6G_MB_LIB.T6G(SCH_1):PAGE387_I3@PURE_QUANTA.M24M02DRMN6TP(CHIPS)':
 'SCL': CDS_PINID='SCL';
NODE_NAME     R668 2
 '@T6G_MB_LIB.T6G(SCH_1):PAGE387_I6@PURE_QUANTA.Q_RES(CHIPS)':
 'B': CDS_PINID='B';
NET_NAME
'SMB_RT_CPU0_P0_ROM_SDA'
 '@T6G_MB_LIB.T6G(SCH_1):SMB_RT_CPU0_P0_ROM_SDA':
 C_SIGNAL='@t6g_mb_lib.t6g(sch_1):smb_rt_cpu0_p0_rom_sda';
NODE_NAME     U11 5
 '@T6G_MB_LIB.T6G(SCH_1):PAGE387_I3@PURE_QUANTA.M24M02DRMN6TP(CHIPS)':
 'SDA': CDS_PINID='SDA';
NODE_NAME     R669 2
 '@T6G_MB_LIB.T6G(SCH_1):PAGE387_I7@PURE_QUANTA.Q_RES(CHIPS)':
 'B': CDS_PINID='B';
NET_NAME
'SMB_RT_CPU0_P0_R_SCL'
 '@T6G_MB_LIB.T6G(SCH_1):SMB_RT_CPU0_P0_R_SCL':
 C_SIGNAL='@t6g_mb_lib.t6g(sch_1):smb_rt_cpu0_p0_r_scl';
NODE_NAME     R6755 2
 '@T6G_MB_LIB.T6G(SCH_1):PAGE378_I54@PURE_QUANTA.Q_RES(CHIPS)':
 'B': CDS_PINID='B';
NODE_NAME     R6763 2
 '@T6G_MB_LIB.T6G(SCH_1):PAGE378_I78@PURE_QUANTA.Q_RES(CHIPS)':
 'B': CDS_PINID='B';
NODE_NAME     R976 1
 '@T6G_MB_LIB.T6G(SCH_1):PAGE385_I50@PURE_QUANTA.Q_RES(CHIPS)':
 'A': CDS_PINID='A';
NET_NAME
'SMB_RT_CPU0_P0_R_SDA'
 '@T6G_MB_LIB.T6G(SCH_1):SMB_RT_CPU0_P0_R_SDA':
 C_SIGNAL='@t6g_mb_lib.t6g(sch_1):smb_rt_cpu0_p0_r_sda';
NODE_NAME     R6754 2
 '@T6G_MB_LIB.T6G(SCH_1):PAGE378_I53@PURE_QUANTA.Q_RES(CHIPS)':
 'B': CDS_PINID='B';
NODE_NAME     R6762 2
 '@T6G_MB_LIB.T6G(SCH_1):PAGE378_I77@PURE_QUANTA.Q_RES(CHIPS)':
 'B': CDS_PINID='B';
NODE_NAME     R977 1
 '@T6G_MB_LIB.T6G(SCH_1):PAGE385_I49@PURE_QUANTA.Q_RES(CHIPS)':
 'A': CDS_PINID='A';
NET_NAME
'SMB_RT_CPU0_P0_SCL'
 '@T6G_MB_LIB.T6G(SCH_1):SMB_RT_CPU0_P0_SCL':
 C_SIGNAL='@t6g_mb_lib.t6g(sch_1):smb_rt_cpu0_p0_scl';
NODE_NAME     U6020 14
 '@T6G_MB_LIB.T6G(SCH_1):PAGE378_I1@PURE_QUANTA.TCA9548APWR(CHIPS)':
 'SC4': CDS_PINID='SC4';
NODE_NAME     R6755 1
 '@T6G_MB_LIB.T6G(SCH_1):PAGE378_I54@PURE_QUANTA.Q_RES(CHIPS)':
 'A': CDS_PINID='A';
NET_NAME
'SMB_RT_CPU0_P0_SDA'
 '@T6G_MB_LIB.T6G(SCH_1):SMB_RT_CPU0_P0_SDA':
 C_SIGNAL='@t6g_mb_lib.t6g(sch_1):smb_rt_cpu0_p0_sda';
NODE_NAME     U6020 13
 '@T6G_MB_LIB.T6G(SCH_1):PAGE378_I1@PURE_QUANTA.TCA9548APWR(CHIPS)':
 'SD4': CDS_PINID='SD4';
NODE_NAME     R6754 1
 '@T6G_MB_LIB.T6G(SCH_1):PAGE378_I53@PURE_QUANTA.Q_RES(CHIPS)':
 'A': CDS_PINID='A';
NET_NAME
'SMB_RT_CPU0_P1_R2_SCL'
 '@T6G_MB_LIB.T6G(SCH_1):SMB_RT_CPU0_P1_R2_SCL':
 C_SIGNAL='@t6g_mb_lib.t6g(sch_1):smb_rt_cpu0_p1_r2_scl';
NODE_NAME     R1025 2
 '@T6G_MB_LIB.T6G(SCH_1):PAGE408_I30@PURE_QUANTA.Q_RES(CHIPS)':
 'B': CDS_PINID='B';
NODE_NAME     U6011 B31
 '@T6G_MB_LIB.T6G(SCH_1):PAGE408_I83@PURE_QUANTA.PT5161LRS(CHIPS)':
 'SMBCLK': CDS_PINID='SMBCLK';
NET_NAME
'SMB_RT_CPU0_P1_R2_SDA'
 '@T6G_MB_LIB.T6G(SCH_1):SMB_RT_CPU0_P1_R2_SDA':
 C_SIGNAL='@t6g_mb_lib.t6g(sch_1):smb_rt_cpu0_p1_r2_sda';
NODE_NAME     R1026 2
 '@T6G_MB_LIB.T6G(SCH_1):PAGE408_I29@PURE_QUANTA.Q_RES(CHIPS)':
 'B': CDS_PINID='B';
NODE_NAME     U6011 B28
 '@T6G_MB_LIB.T6G(SCH_1):PAGE408_I83@PURE_QUANTA.PT5161LRS(CHIPS)':
 'SMBDAT': CDS_PINID='SMBDAT';
NET_NAME
'SMB_RT_CPU0_P1_ROM_MUX_1D_R_SCL'
 '@T6G_MB_LIB.T6G(SCH_1):SMB_RT_CPU0_P1_ROM_MUX_1D_R_SCL':
 C_SIGNAL='@t6g_mb_lib.t6g(sch_1):smb_rt_cpu0_p1_rom_mux_1d_r_scl';
NODE_NAME     R676 2
 '@T6G_MB_LIB.T6G(SCH_1):PAGE408_I22@PURE_QUANTA.Q_RES(CHIPS)':
 'B': CDS_PINID='B';
NODE_NAME     U6011 FF5
 '@T6G_MB_LIB.T6G(SCH_1):PAGE408_I83@PURE_QUANTA.PT5161LRS(CHIPS)':
 'EE_CLK': CDS_PINID='EE_CLK';
NET_NAME
'SMB_RT_CPU0_P1_ROM_MUX_1D_R_SDA'
 '@T6G_MB_LIB.T6G(SCH_1):SMB_RT_CPU0_P1_ROM_MUX_1D_R_SDA':
 C_SIGNAL='@t6g_mb_lib.t6g(sch_1):smb_rt_cpu0_p1_rom_mux_1d_r_sda';
NODE_NAME     R677 2
 '@T6G_MB_LIB.T6G(SCH_1):PAGE408_I21@PURE_QUANTA.Q_RES(CHIPS)':
 'B': CDS_PINID='B';
NODE_NAME     U6011 FJ3
 '@T6G_MB_LIB.T6G(SCH_1):PAGE408_I83@PURE_QUANTA.PT5161LRS(CHIPS)':
 'EE_DAT': CDS_PINID='EE_DAT';
NET_NAME
'SMB_RT_CPU0_P1_ROM_MUX_1D_SCL'
 '@T6G_MB_LIB.T6G(SCH_1):SMB_RT_CPU0_P1_ROM_MUX_1D_SCL':
 C_SIGNAL='@t6g_mb_lib.t6g(sch_1):smb_rt_cpu0_p1_rom_mux_1d_scl';
NODE_NAME     R676 1
 '@T6G_MB_LIB.T6G(SCH_1):PAGE408_I22@PURE_QUANTA.Q_RES(CHIPS)':
 'A': CDS_PINID='A';
NODE_NAME     U48 1
 '@T6G_MB_LIB.T6G(SCH_1):PAGE376_I76@PURE_QUANTA.PI3CSW12ZUAEX(CHIPS)':
 '1D+': CDS_PINID='\1d+\';
NODE_NAME     R1418 2
 '@T6G_MB_LIB.T6G(SCH_1):PAGE377_I167@PURE_QUANTA.Q_RES(CHIPS)':
 'B': CDS_PINID='B';
NET_NAME
'SMB_RT_CPU0_P1_ROM_MUX_1D_SDA'
 '@T6G_MB_LIB.T6G(SCH_1):SMB_RT_CPU0_P1_ROM_MUX_1D_SDA':
 C_SIGNAL='@t6g_mb_lib.t6g(sch_1):smb_rt_cpu0_p1_rom_mux_1d_sda';
NODE_NAME     R677 1
 '@T6G_MB_LIB.T6G(SCH_1):PAGE408_I21@PURE_QUANTA.Q_RES(CHIPS)':
 'A': CDS_PINID='A';
NODE_NAME     U48 2
 '@T6G_MB_LIB.T6G(SCH_1):PAGE376_I76@PURE_QUANTA.PI3CSW12ZUAEX(CHIPS)':
 '1D-': CDS_PINID='\1d-\';
NODE_NAME     R1415 2
 '@T6G_MB_LIB.T6G(SCH_1):PAGE377_I166@PURE_QUANTA.Q_RES(CHIPS)':
 'B': CDS_PINID='B';
NET_NAME
'SMB_RT_CPU0_P1_ROM_MUX_2D_R_SCL'
 '@T6G_MB_LIB.T6G(SCH_1):SMB_RT_CPU0_P1_ROM_MUX_2D_R_SCL':
 C_SIGNAL='@t6g_mb_lib.t6g(sch_1):smb_rt_cpu0_p1_rom_mux_2d_r_scl';
NODE_NAME     R829 1
 '@T6G_MB_LIB.T6G(SCH_1):PAGE377_I77@PURE_QUANTA.Q_RES(CHIPS)':
 'A': CDS_PINID='A';
NODE_NAME     U22 16
 '@T6G_MB_LIB.T6G(SCH_1):PAGE377_I94@PURE_QUANTA.TCA9548APWR(CHIPS)':
 'SC5': CDS_PINID='SC5';
NODE_NAME     R1374 2
 '@T6G_MB_LIB.T6G(SCH_1):PAGE377_I123@PURE_QUANTA.Q_RES(CHIPS)':
 'B': CDS_PINID='B';
NET_NAME
'SMB_RT_CPU0_P1_ROM_MUX_2D_R_SDA'
 '@T6G_MB_LIB.T6G(SCH_1):SMB_RT_CPU0_P1_ROM_MUX_2D_R_SDA':
 C_SIGNAL='@t6g_mb_lib.t6g(sch_1):smb_rt_cpu0_p1_rom_mux_2d_r_sda';
NODE_NAME     R828 1
 '@T6G_MB_LIB.T6G(SCH_1):PAGE377_I76@PURE_QUANTA.Q_RES(CHIPS)':
 'A': CDS_PINID='A';
NODE_NAME     U22 15
 '@T6G_MB_LIB.T6G(SCH_1):PAGE377_I94@PURE_QUANTA.TCA9548APWR(CHIPS)':
 'SD5': CDS_PINID='SD5';
NODE_NAME     R1371 2
 '@T6G_MB_LIB.T6G(SCH_1):PAGE377_I124@PURE_QUANTA.Q_RES(CHIPS)':
 'B': CDS_PINID='B';
NET_NAME
'SMB_RT_CPU0_P1_ROM_MUX_2D_SCL'
 '@T6G_MB_LIB.T6G(SCH_1):SMB_RT_CPU0_P1_ROM_MUX_2D_SCL':
 C_SIGNAL='@t6g_mb_lib.t6g(sch_1):smb_rt_cpu0_p1_rom_mux_2d_scl';
NODE_NAME     R829 2
 '@T6G_MB_LIB.T6G(SCH_1):PAGE377_I77@PURE_QUANTA.Q_RES(CHIPS)':
 'B': CDS_PINID='B';
NODE_NAME     U48 3
 '@T6G_MB_LIB.T6G(SCH_1):PAGE376_I76@PURE_QUANTA.PI3CSW12ZUAEX(CHIPS)':
 '2D+': CDS_PINID='\2d+\';
NET_NAME
'SMB_RT_CPU0_P1_ROM_MUX_2D_SDA'
 '@T6G_MB_LIB.T6G(SCH_1):SMB_RT_CPU0_P1_ROM_MUX_2D_SDA':
 C_SIGNAL='@t6g_mb_lib.t6g(sch_1):smb_rt_cpu0_p1_rom_mux_2d_sda';
NODE_NAME     R828 2
 '@T6G_MB_LIB.T6G(SCH_1):PAGE377_I76@PURE_QUANTA.Q_RES(CHIPS)':
 'B': CDS_PINID='B';
NODE_NAME     U48 4
 '@T6G_MB_LIB.T6G(SCH_1):PAGE376_I76@PURE_QUANTA.PI3CSW12ZUAEX(CHIPS)':
 '2D-': CDS_PINID='\2d-\';
NET_NAME
'SMB_RT_CPU0_P1_ROM_R_SCL'
 '@T6G_MB_LIB.T6G(SCH_1):SMB_RT_CPU0_P1_ROM_R_SCL':
 C_SIGNAL='@t6g_mb_lib.t6g(sch_1):smb_rt_cpu0_p1_rom_r_scl';
NODE_NAME     R678 1
 '@T6G_MB_LIB.T6G(SCH_1):PAGE410_I6@PURE_QUANTA.Q_RES(CHIPS)':
 'A': CDS_PINID='A';
NODE_NAME     R837 2
 '@T6G_MB_LIB.T6G(SCH_1):PAGE377_I21@PURE_QUANTA.Q_RES(CHIPS)':
 'B': CDS_PINID='B';
NODE_NAME     U48 8
 '@T6G_MB_LIB.T6G(SCH_1):PAGE376_I76@PURE_QUANTA.PI3CSW12ZUAEX(CHIPS)':
 'D+': CDS_PINID='\d+\';
NET_NAME
'SMB_RT_CPU0_P1_ROM_R_SDA'
 '@T6G_MB_LIB.T6G(SCH_1):SMB_RT_CPU0_P1_ROM_R_SDA':
 C_SIGNAL='@t6g_mb_lib.t6g(sch_1):smb_rt_cpu0_p1_rom_r_sda';
NODE_NAME     R679 1
 '@T6G_MB_LIB.T6G(SCH_1):PAGE410_I7@PURE_QUANTA.Q_RES(CHIPS)':
 'A': CDS_PINID='A';
NODE_NAME     R836 2
 '@T6G_MB_LIB.T6G(SCH_1):PAGE377_I22@PURE_QUANTA.Q_RES(CHIPS)':
 'B': CDS_PINID='B';
NODE_NAME     U48 7
 '@T6G_MB_LIB.T6G(SCH_1):PAGE376_I76@PURE_QUANTA.PI3CSW12ZUAEX(CHIPS)':
 'D-': CDS_PINID='\d-\';
NET_NAME
'SMB_RT_CPU0_P1_ROM_SCL'
 '@T6G_MB_LIB.T6G(SCH_1):SMB_RT_CPU0_P1_ROM_SCL':
 C_SIGNAL='@t6g_mb_lib.t6g(sch_1):smb_rt_cpu0_p1_rom_scl';
NODE_NAME     U15 6
 '@T6G_MB_LIB.T6G(SCH_1):PAGE410_I5@PURE_QUANTA.M24M02DRMN6TP(CHIPS)':
 'SCL': CDS_PINID='SCL';
NODE_NAME     R678 2
 '@T6G_MB_LIB.T6G(SCH_1):PAGE410_I6@PURE_QUANTA.Q_RES(CHIPS)':
 'B': CDS_PINID='B';
NET_NAME
'SMB_RT_CPU0_P1_ROM_SDA'
 '@T6G_MB_LIB.T6G(SCH_1):SMB_RT_CPU0_P1_ROM_SDA':
 C_SIGNAL='@t6g_mb_lib.t6g(sch_1):smb_rt_cpu0_p1_rom_sda';
NODE_NAME     U15 5
 '@T6G_MB_LIB.T6G(SCH_1):PAGE410_I5@PURE_QUANTA.M24M02DRMN6TP(CHIPS)':
 'SDA': CDS_PINID='SDA';
NODE_NAME     R679 2
 '@T6G_MB_LIB.T6G(SCH_1):PAGE410_I7@PURE_QUANTA.Q_RES(CHIPS)':
 'B': CDS_PINID='B';
NET_NAME
'SMB_RT_CPU0_P1_R_SCL'
 '@T6G_MB_LIB.T6G(SCH_1):SMB_RT_CPU0_P1_R_SCL':
 C_SIGNAL='@t6g_mb_lib.t6g(sch_1):smb_rt_cpu0_p1_r_scl';
NODE_NAME     R6757 2
 '@T6G_MB_LIB.T6G(SCH_1):PAGE378_I57@PURE_QUANTA.Q_RES(CHIPS)':
 'B': CDS_PINID='B';
NODE_NAME     R6765 2
 '@T6G_MB_LIB.T6G(SCH_1):PAGE378_I80@PURE_QUANTA.Q_RES(CHIPS)':
 'B': CDS_PINID='B';
NODE_NAME     R1025 1
 '@T6G_MB_LIB.T6G(SCH_1):PAGE408_I30@PURE_QUANTA.Q_RES(CHIPS)':
 'A': CDS_PINID='A';
NET_NAME
'SMB_RT_CPU0_P1_R_SDA'
 '@T6G_MB_LIB.T6G(SCH_1):SMB_RT_CPU0_P1_R_SDA':
 C_SIGNAL='@t6g_mb_lib.t6g(sch_1):smb_rt_cpu0_p1_r_sda';
NODE_NAME     R6756 2
 '@T6G_MB_LIB.T6G(SCH_1):PAGE378_I56@PURE_QUANTA.Q_RES(CHIPS)':
 'B': CDS_PINID='B';
NODE_NAME     R6764 2
 '@T6G_MB_LIB.T6G(SCH_1):PAGE378_I79@PURE_QUANTA.Q_RES(CHIPS)':
 'B': CDS_PINID='B';
NODE_NAME     R1026 1
 '@T6G_MB_LIB.T6G(SCH_1):PAGE408_I29@PURE_QUANTA.Q_RES(CHIPS)':
 'A': CDS_PINID='A';
NET_NAME
'SMB_RT_CPU0_P1_SCL'
 '@T6G_MB_LIB.T6G(SCH_1):SMB_RT_CPU0_P1_SCL':
 C_SIGNAL='@t6g_mb_lib.t6g(sch_1):smb_rt_cpu0_p1_scl';
NODE_NAME     U6020 16
 '@T6G_MB_LIB.T6G(SCH_1):PAGE378_I1@PURE_QUANTA.TCA9548APWR(CHIPS)':
 'SC5': CDS_PINID='SC5';
NODE_NAME     R6757 1
 '@T6G_MB_LIB.T6G(SCH_1):PAGE378_I57@PURE_QUANTA.Q_RES(CHIPS)':
 'A': CDS_PINID='A';
NET_NAME
'SMB_RT_CPU0_P1_SDA'
 '@T6G_MB_LIB.T6G(SCH_1):SMB_RT_CPU0_P1_SDA':
 C_SIGNAL='@t6g_mb_lib.t6g(sch_1):smb_rt_cpu0_p1_sda';
NODE_NAME     U6020 15
 '@T6G_MB_LIB.T6G(SCH_1):PAGE378_I1@PURE_QUANTA.TCA9548APWR(CHIPS)':
 'SD5': CDS_PINID='SD5';
NODE_NAME     R6756 1
 '@T6G_MB_LIB.T6G(SCH_1):PAGE378_I56@PURE_QUANTA.Q_RES(CHIPS)':
 'A': CDS_PINID='A';
NET_NAME
'SMB_RT_CPU0_P2_R2_SCL'
 '@T6G_MB_LIB.T6G(SCH_1):SMB_RT_CPU0_P2_R2_SCL':
 C_SIGNAL='@t6g_mb_lib.t6g(sch_1):smb_rt_cpu0_p2_r2_scl';
NODE_NAME     R1067 2
 '@T6G_MB_LIB.T6G(SCH_1):PAGE419_I29@PURE_QUANTA.Q_RES(CHIPS)':
 'B': CDS_PINID='B';
NODE_NAME     U6012 B31
 '@T6G_MB_LIB.T6G(SCH_1):PAGE419_I83@PURE_QUANTA.PT5161LRS(CHIPS)':
 'SMBCLK': CDS_PINID='SMBCLK';
NET_NAME
'SMB_RT_CPU0_P2_R2_SDA'
 '@T6G_MB_LIB.T6G(SCH_1):SMB_RT_CPU0_P2_R2_SDA':
 C_SIGNAL='@t6g_mb_lib.t6g(sch_1):smb_rt_cpu0_p2_r2_sda';
NODE_NAME     R1068 2
 '@T6G_MB_LIB.T6G(SCH_1):PAGE419_I30@PURE_QUANTA.Q_RES(CHIPS)':
 'B': CDS_PINID='B';
NODE_NAME     U6012 B28
 '@T6G_MB_LIB.T6G(SCH_1):PAGE419_I83@PURE_QUANTA.PT5161LRS(CHIPS)':
 'SMBDAT': CDS_PINID='SMBDAT';
NET_NAME
'SMB_RT_CPU0_P2_ROM_MUX_1D_R_SCL'
 '@T6G_MB_LIB.T6G(SCH_1):SMB_RT_CPU0_P2_ROM_MUX_1D_R_SCL':
 C_SIGNAL='@t6g_mb_lib.t6g(sch_1):smb_rt_cpu0_p2_rom_mux_1d_r_scl';
NODE_NAME     R680 2
 '@T6G_MB_LIB.T6G(SCH_1):PAGE419_I22@PURE_QUANTA.Q_RES(CHIPS)':
 'B': CDS_PINID='B';
NODE_NAME     U6012 FF5
 '@T6G_MB_LIB.T6G(SCH_1):PAGE419_I83@PURE_QUANTA.PT5161LRS(CHIPS)':
 'EE_CLK': CDS_PINID='EE_CLK';
NET_NAME
'SMB_RT_CPU0_P2_ROM_MUX_1D_R_SDA'
 '@T6G_MB_LIB.T6G(SCH_1):SMB_RT_CPU0_P2_ROM_MUX_1D_R_SDA':
 C_SIGNAL='@t6g_mb_lib.t6g(sch_1):smb_rt_cpu0_p2_rom_mux_1d_r_sda';
NODE_NAME     R681 2
 '@T6G_MB_LIB.T6G(SCH_1):PAGE419_I21@PURE_QUANTA.Q_RES(CHIPS)':
 'B': CDS_PINID='B';
NODE_NAME     U6012 FJ3
 '@T6G_MB_LIB.T6G(SCH_1):PAGE419_I83@PURE_QUANTA.PT5161LRS(CHIPS)':
 'EE_DAT': CDS_PINID='EE_DAT';
NET_NAME
'SMB_RT_CPU0_P2_ROM_MUX_1D_SCL'
 '@T6G_MB_LIB.T6G(SCH_1):SMB_RT_CPU0_P2_ROM_MUX_1D_SCL':
 C_SIGNAL='@t6g_mb_lib.t6g(sch_1):smb_rt_cpu0_p2_rom_mux_1d_scl';
NODE_NAME     R680 1
 '@T6G_MB_LIB.T6G(SCH_1):PAGE419_I22@PURE_QUANTA.Q_RES(CHIPS)':
 'A': CDS_PINID='A';
NODE_NAME     U47 1
 '@T6G_MB_LIB.T6G(SCH_1):PAGE376_I121@PURE_QUANTA.PI3CSW12ZUAEX(CHIPS)':
 '1D+': CDS_PINID='\1d+\';
NODE_NAME     R1432 2
 '@T6G_MB_LIB.T6G(SCH_1):PAGE377_I171@PURE_QUANTA.Q_RES(CHIPS)':
 'B': CDS_PINID='B';
NET_NAME
'SMB_RT_CPU0_P2_ROM_MUX_1D_SDA'
 '@T6G_MB_LIB.T6G(SCH_1):SMB_RT_CPU0_P2_ROM_MUX_1D_SDA':
 C_SIGNAL='@t6g_mb_lib.t6g(sch_1):smb_rt_cpu0_p2_rom_mux_1d_sda';
NODE_NAME     R681 1
 '@T6G_MB_LIB.T6G(SCH_1):PAGE419_I21@PURE_QUANTA.Q_RES(CHIPS)':
 'A': CDS_PINID='A';
NODE_NAME     U47 2
 '@T6G_MB_LIB.T6G(SCH_1):PAGE376_I121@PURE_QUANTA.PI3CSW12ZUAEX(CHIPS)':
 '1D-': CDS_PINID='\1d-\';
NODE_NAME     R1431 2
 '@T6G_MB_LIB.T6G(SCH_1):PAGE377_I170@PURE_QUANTA.Q_RES(CHIPS)':
 'B': CDS_PINID='B';
NET_NAME
'SMB_RT_CPU0_P2_ROM_MUX_2D_R_SCL'
 '@T6G_MB_LIB.T6G(SCH_1):SMB_RT_CPU0_P2_ROM_MUX_2D_R_SCL':
 C_SIGNAL='@t6g_mb_lib.t6g(sch_1):smb_rt_cpu0_p2_rom_mux_2d_r_scl';
NODE_NAME     R833 1
 '@T6G_MB_LIB.T6G(SCH_1):PAGE377_I73@PURE_QUANTA.Q_RES(CHIPS)':
 'A': CDS_PINID='A';
NODE_NAME     U22 20
 '@T6G_MB_LIB.T6G(SCH_1):PAGE377_I94@PURE_QUANTA.TCA9548APWR(CHIPS)':
 'SC7': CDS_PINID='SC7';
NODE_NAME     R1383 2
 '@T6G_MB_LIB.T6G(SCH_1):PAGE377_I128@PURE_QUANTA.Q_RES(CHIPS)':
 'B': CDS_PINID='B';
NET_NAME
'SMB_RT_CPU0_P2_ROM_MUX_2D_R_SDA'
 '@T6G_MB_LIB.T6G(SCH_1):SMB_RT_CPU0_P2_ROM_MUX_2D_R_SDA':
 C_SIGNAL='@t6g_mb_lib.t6g(sch_1):smb_rt_cpu0_p2_rom_mux_2d_r_sda';
NODE_NAME     R832 1
 '@T6G_MB_LIB.T6G(SCH_1):PAGE377_I75@PURE_QUANTA.Q_RES(CHIPS)':
 'A': CDS_PINID='A';
NODE_NAME     U22 19
 '@T6G_MB_LIB.T6G(SCH_1):PAGE377_I94@PURE_QUANTA.TCA9548APWR(CHIPS)':
 'SD7': CDS_PINID='SD7';
NODE_NAME     R1382 2
 '@T6G_MB_LIB.T6G(SCH_1):PAGE377_I127@PURE_QUANTA.Q_RES(CHIPS)':
 'B': CDS_PINID='B';
NET_NAME
'SMB_RT_CPU0_P2_ROM_MUX_2D_SCL'
 '@T6G_MB_LIB.T6G(SCH_1):SMB_RT_CPU0_P2_ROM_MUX_2D_SCL':
 C_SIGNAL='@t6g_mb_lib.t6g(sch_1):smb_rt_cpu0_p2_rom_mux_2d_scl';
NODE_NAME     R833 2
 '@T6G_MB_LIB.T6G(SCH_1):PAGE377_I73@PURE_QUANTA.Q_RES(CHIPS)':
 'B': CDS_PINID='B';
NODE_NAME     U47 3
 '@T6G_MB_LIB.T6G(SCH_1):PAGE376_I121@PURE_QUANTA.PI3CSW12ZUAEX(CHIPS)':
 '2D+': CDS_PINID='\2d+\';
NET_NAME
'SMB_RT_CPU0_P2_ROM_MUX_2D_SDA'
 '@T6G_MB_LIB.T6G(SCH_1):SMB_RT_CPU0_P2_ROM_MUX_2D_SDA':
 C_SIGNAL='@t6g_mb_lib.t6g(sch_1):smb_rt_cpu0_p2_rom_mux_2d_sda';
NODE_NAME     R832 2
 '@T6G_MB_LIB.T6G(SCH_1):PAGE377_I75@PURE_QUANTA.Q_RES(CHIPS)':
 'B': CDS_PINID='B';
NODE_NAME     U47 4
 '@T6G_MB_LIB.T6G(SCH_1):PAGE376_I121@PURE_QUANTA.PI3CSW12ZUAEX(CHIPS)':
 '2D-': CDS_PINID='\2d-\';
NET_NAME
'SMB_RT_CPU0_P2_ROM_R_SCL'
 '@T6G_MB_LIB.T6G(SCH_1):SMB_RT_CPU0_P2_ROM_R_SCL':
 C_SIGNAL='@t6g_mb_lib.t6g(sch_1):smb_rt_cpu0_p2_rom_r_scl';
NODE_NAME     R682 1
 '@T6G_MB_LIB.T6G(SCH_1):PAGE421_I3@PURE_QUANTA.Q_RES(CHIPS)':
 'A': CDS_PINID='A';
NODE_NAME     R841 2
 '@T6G_MB_LIB.T6G(SCH_1):PAGE377_I17@PURE_QUANTA.Q_RES(CHIPS)':
 'B': CDS_PINID='B';
NODE_NAME     U47 8
 '@T6G_MB_LIB.T6G(SCH_1):PAGE376_I121@PURE_QUANTA.PI3CSW12ZUAEX(CHIPS)':
 'D+': CDS_PINID='\d+\';
NET_NAME
'SMB_RT_CPU0_P2_ROM_R_SDA'
 '@T6G_MB_LIB.T6G(SCH_1):SMB_RT_CPU0_P2_ROM_R_SDA':
 C_SIGNAL='@t6g_mb_lib.t6g(sch_1):smb_rt_cpu0_p2_rom_r_sda';
NODE_NAME     R683 1
 '@T6G_MB_LIB.T6G(SCH_1):PAGE421_I4@PURE_QUANTA.Q_RES(CHIPS)':
 'A': CDS_PINID='A';
NODE_NAME     R840 2
 '@T6G_MB_LIB.T6G(SCH_1):PAGE377_I18@PURE_QUANTA.Q_RES(CHIPS)':
 'B': CDS_PINID='B';
NODE_NAME     U47 7
 '@T6G_MB_LIB.T6G(SCH_1):PAGE376_I121@PURE_QUANTA.PI3CSW12ZUAEX(CHIPS)':
 'D-': CDS_PINID='\d-\';
NET_NAME
'SMB_RT_CPU0_P2_ROM_SCL'
 '@T6G_MB_LIB.T6G(SCH_1):SMB_RT_CPU0_P2_ROM_SCL':
 C_SIGNAL='@t6g_mb_lib.t6g(sch_1):smb_rt_cpu0_p2_rom_scl';
NODE_NAME     R682 2
 '@T6G_MB_LIB.T6G(SCH_1):PAGE421_I3@PURE_QUANTA.Q_RES(CHIPS)':
 'B': CDS_PINID='B';
NODE_NAME     U16 6
 '@T6G_MB_LIB.T6G(SCH_1):PAGE421_I5@PURE_QUANTA.M24M02DRMN6TP(CHIPS)':
 'SCL': CDS_PINID='SCL';
NET_NAME
'SMB_RT_CPU0_P2_ROM_SDA'
 '@T6G_MB_LIB.T6G(SCH_1):SMB_RT_CPU0_P2_ROM_SDA':
 C_SIGNAL='@t6g_mb_lib.t6g(sch_1):smb_rt_cpu0_p2_rom_sda';
NODE_NAME     R683 2
 '@T6G_MB_LIB.T6G(SCH_1):PAGE421_I4@PURE_QUANTA.Q_RES(CHIPS)':
 'B': CDS_PINID='B';
NODE_NAME     U16 5
 '@T6G_MB_LIB.T6G(SCH_1):PAGE421_I5@PURE_QUANTA.M24M02DRMN6TP(CHIPS)':
 'SDA': CDS_PINID='SDA';
NET_NAME
'SMB_RT_CPU0_P2_R_SCL'
 '@T6G_MB_LIB.T6G(SCH_1):SMB_RT_CPU0_P2_R_SCL':
 C_SIGNAL='@t6g_mb_lib.t6g(sch_1):smb_rt_cpu0_p2_r_scl';
NODE_NAME     R6761 2
 '@T6G_MB_LIB.T6G(SCH_1):PAGE378_I60@PURE_QUANTA.Q_RES(CHIPS)':
 'B': CDS_PINID='B';
NODE_NAME     R6769 2
 '@T6G_MB_LIB.T6G(SCH_1):PAGE378_I85@PURE_QUANTA.Q_RES(CHIPS)':
 'B': CDS_PINID='B';
NODE_NAME     R1067 1
 '@T6G_MB_LIB.T6G(SCH_1):PAGE419_I29@PURE_QUANTA.Q_RES(CHIPS)':
 'A': CDS_PINID='A';
NET_NAME
'SMB_RT_CPU0_P2_R_SDA'
 '@T6G_MB_LIB.T6G(SCH_1):SMB_RT_CPU0_P2_R_SDA':
 C_SIGNAL='@t6g_mb_lib.t6g(sch_1):smb_rt_cpu0_p2_r_sda';
NODE_NAME     R6760 2
 '@T6G_MB_LIB.T6G(SCH_1):PAGE378_I58@PURE_QUANTA.Q_RES(CHIPS)':
 'B': CDS_PINID='B';
NODE_NAME     R6768 2
 '@T6G_MB_LIB.T6G(SCH_1):PAGE378_I84@PURE_QUANTA.Q_RES(CHIPS)':
 'B': CDS_PINID='B';
NODE_NAME     R1068 1
 '@T6G_MB_LIB.T6G(SCH_1):PAGE419_I30@PURE_QUANTA.Q_RES(CHIPS)':
 'A': CDS_PINID='A';
NET_NAME
'SMB_RT_CPU0_P2_SCL'
 '@T6G_MB_LIB.T6G(SCH_1):SMB_RT_CPU0_P2_SCL':
 C_SIGNAL='@t6g_mb_lib.t6g(sch_1):smb_rt_cpu0_p2_scl';
NODE_NAME     U6020 20
 '@T6G_MB_LIB.T6G(SCH_1):PAGE378_I1@PURE_QUANTA.TCA9548APWR(CHIPS)':
 'SC7': CDS_PINID='SC7';
NODE_NAME     R6761 1
 '@T6G_MB_LIB.T6G(SCH_1):PAGE378_I60@PURE_QUANTA.Q_RES(CHIPS)':
 'A': CDS_PINID='A';
NET_NAME
'SMB_RT_CPU0_P2_SDA'
 '@T6G_MB_LIB.T6G(SCH_1):SMB_RT_CPU0_P2_SDA':
 C_SIGNAL='@t6g_mb_lib.t6g(sch_1):smb_rt_cpu0_p2_sda';
NODE_NAME     U6020 19
 '@T6G_MB_LIB.T6G(SCH_1):PAGE378_I1@PURE_QUANTA.TCA9548APWR(CHIPS)':
 'SD7': CDS_PINID='SD7';
NODE_NAME     R6760 1
 '@T6G_MB_LIB.T6G(SCH_1):PAGE378_I58@PURE_QUANTA.Q_RES(CHIPS)':
 'A': CDS_PINID='A';
NET_NAME
'SMB_RT_CPU0_P3_R2_SCL'
 '@T6G_MB_LIB.T6G(SCH_1):SMB_RT_CPU0_P3_R2_SCL':
 C_SIGNAL='@t6g_mb_lib.t6g(sch_1):smb_rt_cpu0_p3_r2_scl';
NODE_NAME     R1109 2
 '@T6G_MB_LIB.T6G(SCH_1):PAGE430_I32@PURE_QUANTA.Q_RES(CHIPS)':
 'B': CDS_PINID='B';
NODE_NAME     U6013 B31
 '@T6G_MB_LIB.T6G(SCH_1):PAGE430_I83@PURE_QUANTA.PT5161LRS(CHIPS)':
 'SMBCLK': CDS_PINID='SMBCLK';
NET_NAME
'SMB_RT_CPU0_P3_R2_SDA'
 '@T6G_MB_LIB.T6G(SCH_1):SMB_RT_CPU0_P3_R2_SDA':
 C_SIGNAL='@t6g_mb_lib.t6g(sch_1):smb_rt_cpu0_p3_r2_sda';
NODE_NAME     R1110 2
 '@T6G_MB_LIB.T6G(SCH_1):PAGE430_I33@PURE_QUANTA.Q_RES(CHIPS)':
 'B': CDS_PINID='B';
NODE_NAME     U6013 B28
 '@T6G_MB_LIB.T6G(SCH_1):PAGE430_I83@PURE_QUANTA.PT5161LRS(CHIPS)':
 'SMBDAT': CDS_PINID='SMBDAT';
NET_NAME
'SMB_RT_CPU0_P3_ROM_MUX_1D_R_SCL'
 '@T6G_MB_LIB.T6G(SCH_1):SMB_RT_CPU0_P3_ROM_MUX_1D_R_SCL':
 C_SIGNAL='@t6g_mb_lib.t6g(sch_1):smb_rt_cpu0_p3_rom_mux_1d_r_scl';
NODE_NAME     R684 2
 '@T6G_MB_LIB.T6G(SCH_1):PAGE430_I22@PURE_QUANTA.Q_RES(CHIPS)':
 'B': CDS_PINID='B';
NODE_NAME     U6013 FF5
 '@T6G_MB_LIB.T6G(SCH_1):PAGE430_I83@PURE_QUANTA.PT5161LRS(CHIPS)':
 'EE_CLK': CDS_PINID='EE_CLK';
NET_NAME
'SMB_RT_CPU0_P3_ROM_MUX_1D_R_SDA'
 '@T6G_MB_LIB.T6G(SCH_1):SMB_RT_CPU0_P3_ROM_MUX_1D_R_SDA':
 C_SIGNAL='@t6g_mb_lib.t6g(sch_1):smb_rt_cpu0_p3_rom_mux_1d_r_sda';
NODE_NAME     R686 2
 '@T6G_MB_LIB.T6G(SCH_1):PAGE430_I21@PURE_QUANTA.Q_RES(CHIPS)':
 'B': CDS_PINID='B';
NODE_NAME     U6013 FJ3
 '@T6G_MB_LIB.T6G(SCH_1):PAGE430_I83@PURE_QUANTA.PT5161LRS(CHIPS)':
 'EE_DAT': CDS_PINID='EE_DAT';
NET_NAME
'SMB_RT_CPU0_P3_ROM_MUX_1D_SCL'
 '@T6G_MB_LIB.T6G(SCH_1):SMB_RT_CPU0_P3_ROM_MUX_1D_SCL':
 C_SIGNAL='@t6g_mb_lib.t6g(sch_1):smb_rt_cpu0_p3_rom_mux_1d_scl';
NODE_NAME     R684 1
 '@T6G_MB_LIB.T6G(SCH_1):PAGE430_I22@PURE_QUANTA.Q_RES(CHIPS)':
 'A': CDS_PINID='A';
NODE_NAME     U46 1
 '@T6G_MB_LIB.T6G(SCH_1):PAGE376_I108@PURE_QUANTA.PI3CSW12ZUAEX(CHIPS)':
 '1D+': CDS_PINID='\1d+\';
NODE_NAME     R1428 2
 '@T6G_MB_LIB.T6G(SCH_1):PAGE377_I169@PURE_QUANTA.Q_RES(CHIPS)':
 'B': CDS_PINID='B';
NET_NAME
'SMB_RT_CPU0_P3_ROM_MUX_1D_SDA'
 '@T6G_MB_LIB.T6G(SCH_1):SMB_RT_CPU0_P3_ROM_MUX_1D_SDA':
 C_SIGNAL='@t6g_mb_lib.t6g(sch_1):smb_rt_cpu0_p3_rom_mux_1d_sda';
NODE_NAME     R686 1
 '@T6G_MB_LIB.T6G(SCH_1):PAGE430_I21@PURE_QUANTA.Q_RES(CHIPS)':
 'A': CDS_PINID='A';
NODE_NAME     U46 2
 '@T6G_MB_LIB.T6G(SCH_1):PAGE376_I108@PURE_QUANTA.PI3CSW12ZUAEX(CHIPS)':
 '1D-': CDS_PINID='\1d-\';
NODE_NAME     R1420 2
 '@T6G_MB_LIB.T6G(SCH_1):PAGE377_I168@PURE_QUANTA.Q_RES(CHIPS)':
 'B': CDS_PINID='B';
NET_NAME
'SMB_RT_CPU0_P3_ROM_MUX_2D_R_SCL'
 '@T6G_MB_LIB.T6G(SCH_1):SMB_RT_CPU0_P3_ROM_MUX_2D_R_SCL':
 C_SIGNAL='@t6g_mb_lib.t6g(sch_1):smb_rt_cpu0_p3_rom_mux_2d_r_scl';
NODE_NAME     R831 1
 '@T6G_MB_LIB.T6G(SCH_1):PAGE377_I74@PURE_QUANTA.Q_RES(CHIPS)':
 'A': CDS_PINID='A';
NODE_NAME     U22 18
 '@T6G_MB_LIB.T6G(SCH_1):PAGE377_I94@PURE_QUANTA.TCA9548APWR(CHIPS)':
 'SC6': CDS_PINID='SC6';
NODE_NAME     R1379 2
 '@T6G_MB_LIB.T6G(SCH_1):PAGE377_I126@PURE_QUANTA.Q_RES(CHIPS)':
 'B': CDS_PINID='B';
NET_NAME
'SMB_RT_CPU0_P3_ROM_MUX_2D_R_SDA'
 '@T6G_MB_LIB.T6G(SCH_1):SMB_RT_CPU0_P3_ROM_MUX_2D_R_SDA':
 C_SIGNAL='@t6g_mb_lib.t6g(sch_1):smb_rt_cpu0_p3_rom_mux_2d_r_sda';
NODE_NAME     R830 1
 '@T6G_MB_LIB.T6G(SCH_1):PAGE377_I78@PURE_QUANTA.Q_RES(CHIPS)':
 'A': CDS_PINID='A';
NODE_NAME     U22 17
 '@T6G_MB_LIB.T6G(SCH_1):PAGE377_I94@PURE_QUANTA.TCA9548APWR(CHIPS)':
 'SD6': CDS_PINID='SD6';
NODE_NAME     R1375 2
 '@T6G_MB_LIB.T6G(SCH_1):PAGE377_I125@PURE_QUANTA.Q_RES(CHIPS)':
 'B': CDS_PINID='B';
NET_NAME
'SMB_RT_CPU0_P3_ROM_MUX_2D_SCL'
 '@T6G_MB_LIB.T6G(SCH_1):SMB_RT_CPU0_P3_ROM_MUX_2D_SCL':
 C_SIGNAL='@t6g_mb_lib.t6g(sch_1):smb_rt_cpu0_p3_rom_mux_2d_scl';
NODE_NAME     R831 2
 '@T6G_MB_LIB.T6G(SCH_1):PAGE377_I74@PURE_QUANTA.Q_RES(CHIPS)':
 'B': CDS_PINID='B';
NODE_NAME     U46 3
 '@T6G_MB_LIB.T6G(SCH_1):PAGE376_I108@PURE_QUANTA.PI3CSW12ZUAEX(CHIPS)':
 '2D+': CDS_PINID='\2d+\';
NET_NAME
'SMB_RT_CPU0_P3_ROM_MUX_2D_SDA'
 '@T6G_MB_LIB.T6G(SCH_1):SMB_RT_CPU0_P3_ROM_MUX_2D_SDA':
 C_SIGNAL='@t6g_mb_lib.t6g(sch_1):smb_rt_cpu0_p3_rom_mux_2d_sda';
NODE_NAME     R830 2
 '@T6G_MB_LIB.T6G(SCH_1):PAGE377_I78@PURE_QUANTA.Q_RES(CHIPS)':
 'B': CDS_PINID='B';
NODE_NAME     U46 4
 '@T6G_MB_LIB.T6G(SCH_1):PAGE376_I108@PURE_QUANTA.PI3CSW12ZUAEX(CHIPS)':
 '2D-': CDS_PINID='\2d-\';
NET_NAME
'SMB_RT_CPU0_P3_ROM_R_SCL'
 '@T6G_MB_LIB.T6G(SCH_1):SMB_RT_CPU0_P3_ROM_R_SCL':
 C_SIGNAL='@t6g_mb_lib.t6g(sch_1):smb_rt_cpu0_p3_rom_r_scl';
NODE_NAME     R687 1
 '@T6G_MB_LIB.T6G(SCH_1):PAGE432_I3@PURE_QUANTA.Q_RES(CHIPS)':
 'A': CDS_PINID='A';
NODE_NAME     R839 2
 '@T6G_MB_LIB.T6G(SCH_1):PAGE377_I20@PURE_QUANTA.Q_RES(CHIPS)':
 'B': CDS_PINID='B';
NODE_NAME     U46 8
 '@T6G_MB_LIB.T6G(SCH_1):PAGE376_I108@PURE_QUANTA.PI3CSW12ZUAEX(CHIPS)':
 'D+': CDS_PINID='\d+\';
NET_NAME
'SMB_RT_CPU0_P3_ROM_R_SDA'
 '@T6G_MB_LIB.T6G(SCH_1):SMB_RT_CPU0_P3_ROM_R_SDA':
 C_SIGNAL='@t6g_mb_lib.t6g(sch_1):smb_rt_cpu0_p3_rom_r_sda';
NODE_NAME     R688 1
 '@T6G_MB_LIB.T6G(SCH_1):PAGE432_I4@PURE_QUANTA.Q_RES(CHIPS)':
 'A': CDS_PINID='A';
NODE_NAME     R838 2
 '@T6G_MB_LIB.T6G(SCH_1):PAGE377_I19@PURE_QUANTA.Q_RES(CHIPS)':
 'B': CDS_PINID='B';
NODE_NAME     U46 7
 '@T6G_MB_LIB.T6G(SCH_1):PAGE376_I108@PURE_QUANTA.PI3CSW12ZUAEX(CHIPS)':
 'D-': CDS_PINID='\d-\';
NET_NAME
'SMB_RT_CPU0_P3_ROM_SCL'
 '@T6G_MB_LIB.T6G(SCH_1):SMB_RT_CPU0_P3_ROM_SCL':
 C_SIGNAL='@t6g_mb_lib.t6g(sch_1):smb_rt_cpu0_p3_rom_scl';
NODE_NAME     R687 2
 '@T6G_MB_LIB.T6G(SCH_1):PAGE432_I3@PURE_QUANTA.Q_RES(CHIPS)':
 'B': CDS_PINID='B';
NODE_NAME     U17 6
 '@T6G_MB_LIB.T6G(SCH_1):PAGE432_I5@PURE_QUANTA.M24M02DRMN6TP(CHIPS)':
 'SCL': CDS_PINID='SCL';
NET_NAME
'SMB_RT_CPU0_P3_ROM_SDA'
 '@T6G_MB_LIB.T6G(SCH_1):SMB_RT_CPU0_P3_ROM_SDA':
 C_SIGNAL='@t6g_mb_lib.t6g(sch_1):smb_rt_cpu0_p3_rom_sda';
NODE_NAME     R688 2
 '@T6G_MB_LIB.T6G(SCH_1):PAGE432_I4@PURE_QUANTA.Q_RES(CHIPS)':
 'B': CDS_PINID='B';
NODE_NAME     U17 5
 '@T6G_MB_LIB.T6G(SCH_1):PAGE432_I5@PURE_QUANTA.M24M02DRMN6TP(CHIPS)':
 'SDA': CDS_PINID='SDA';
NET_NAME
'SMB_RT_CPU0_P3_R_SCL'
 '@T6G_MB_LIB.T6G(SCH_1):SMB_RT_CPU0_P3_R_SCL':
 C_SIGNAL='@t6g_mb_lib.t6g(sch_1):smb_rt_cpu0_p3_r_scl';
NODE_NAME     R6759 2
 '@T6G_MB_LIB.T6G(SCH_1):PAGE378_I59@PURE_QUANTA.Q_RES(CHIPS)':
 'B': CDS_PINID='B';
NODE_NAME     R6767 2
 '@T6G_MB_LIB.T6G(SCH_1):PAGE378_I82@PURE_QUANTA.Q_RES(CHIPS)':
 'B': CDS_PINID='B';
NODE_NAME     R1109 1
 '@T6G_MB_LIB.T6G(SCH_1):PAGE430_I32@PURE_QUANTA.Q_RES(CHIPS)':
 'A': CDS_PINID='A';
NET_NAME
'SMB_RT_CPU0_P3_R_SDA'
 '@T6G_MB_LIB.T6G(SCH_1):SMB_RT_CPU0_P3_R_SDA':
 C_SIGNAL='@t6g_mb_lib.t6g(sch_1):smb_rt_cpu0_p3_r_sda';
NODE_NAME     R6758 2
 '@T6G_MB_LIB.T6G(SCH_1):PAGE378_I55@PURE_QUANTA.Q_RES(CHIPS)':
 'B': CDS_PINID='B';
NODE_NAME     R6766 2
 '@T6G_MB_LIB.T6G(SCH_1):PAGE378_I83@PURE_QUANTA.Q_RES(CHIPS)':
 'B': CDS_PINID='B';
NODE_NAME     R1110 1
 '@T6G_MB_LIB.T6G(SCH_1):PAGE430_I33@PURE_QUANTA.Q_RES(CHIPS)':
 'A': CDS_PINID='A';
NET_NAME
'SMB_RT_CPU0_P3_SCL'
 '@T6G_MB_LIB.T6G(SCH_1):SMB_RT_CPU0_P3_SCL':
 C_SIGNAL='@t6g_mb_lib.t6g(sch_1):smb_rt_cpu0_p3_scl';
NODE_NAME     U6020 18
 '@T6G_MB_LIB.T6G(SCH_1):PAGE378_I1@PURE_QUANTA.TCA9548APWR(CHIPS)':
 'SC6': CDS_PINID='SC6';
NODE_NAME     R6759 1
 '@T6G_MB_LIB.T6G(SCH_1):PAGE378_I59@PURE_QUANTA.Q_RES(CHIPS)':
 'A': CDS_PINID='A';
NET_NAME
'SMB_RT_CPU0_P3_SDA'
 '@T6G_MB_LIB.T6G(SCH_1):SMB_RT_CPU0_P3_SDA':
 C_SIGNAL='@t6g_mb_lib.t6g(sch_1):smb_rt_cpu0_p3_sda';
NODE_NAME     U6020 17
 '@T6G_MB_LIB.T6G(SCH_1):PAGE378_I1@PURE_QUANTA.TCA9548APWR(CHIPS)':
 'SD6': CDS_PINID='SD6';
NODE_NAME     R6758 1
 '@T6G_MB_LIB.T6G(SCH_1):PAGE378_I55@PURE_QUANTA.Q_RES(CHIPS)':
 'A': CDS_PINID='A';
NET_NAME
'SMB_RT_CPU1_P0_R2_SCL'
 '@T6G_MB_LIB.T6G(SCH_1):SMB_RT_CPU1_P0_R2_SCL':
 C_SIGNAL='@t6g_mb_lib.t6g(sch_1):smb_rt_cpu1_p0_r2_scl';
NODE_NAME     U6014 B31
 '@T6G_MB_LIB.T6G(SCH_1):PAGE401_I1@PURE_QUANTA.PT5161LRS(CHIPS)':
 'SMBCLK': CDS_PINID='SMBCLK';
NODE_NAME     R6812 2
 '@T6G_MB_LIB.T6G(SCH_1):PAGE401_I19@PURE_QUANTA.Q_RES(CHIPS)':
 'B': CDS_PINID='B';
NET_NAME
'SMB_RT_CPU1_P0_R2_SDA'
 '@T6G_MB_LIB.T6G(SCH_1):SMB_RT_CPU1_P0_R2_SDA':
 C_SIGNAL='@t6g_mb_lib.t6g(sch_1):smb_rt_cpu1_p0_r2_sda';
NODE_NAME     U6014 B28
 '@T6G_MB_LIB.T6G(SCH_1):PAGE401_I1@PURE_QUANTA.PT5161LRS(CHIPS)':
 'SMBDAT': CDS_PINID='SMBDAT';
NODE_NAME     R6813 2
 '@T6G_MB_LIB.T6G(SCH_1):PAGE401_I20@PURE_QUANTA.Q_RES(CHIPS)':
 'B': CDS_PINID='B';
NET_NAME
'SMB_RT_CPU1_P0_ROM_MUX_1D_R_SCL'
 '@T6G_MB_LIB.T6G(SCH_1):SMB_RT_CPU1_P0_ROM_MUX_1D_R_SCL':
 C_SIGNAL='@t6g_mb_lib.t6g(sch_1):smb_rt_cpu1_p0_rom_mux_1d_r_scl';
NODE_NAME     U6014 FF5
 '@T6G_MB_LIB.T6G(SCH_1):PAGE401_I1@PURE_QUANTA.PT5161LRS(CHIPS)':
 'EE_CLK': CDS_PINID='EE_CLK';
NODE_NAME     R674 2
 '@T6G_MB_LIB.T6G(SCH_1):PAGE401_I155@PURE_QUANTA.Q_RES(CHIPS)':
 'B': CDS_PINID='B';
NET_NAME
'SMB_RT_CPU1_P0_ROM_MUX_1D_R_SDA'
 '@T6G_MB_LIB.T6G(SCH_1):SMB_RT_CPU1_P0_ROM_MUX_1D_R_SDA':
 C_SIGNAL='@t6g_mb_lib.t6g(sch_1):smb_rt_cpu1_p0_rom_mux_1d_r_sda';
NODE_NAME     U6014 FJ3
 '@T6G_MB_LIB.T6G(SCH_1):PAGE401_I1@PURE_QUANTA.PT5161LRS(CHIPS)':
 'EE_DAT': CDS_PINID='EE_DAT';
NODE_NAME     R675 2
 '@T6G_MB_LIB.T6G(SCH_1):PAGE401_I13@PURE_QUANTA.Q_RES(CHIPS)':
 'B': CDS_PINID='B';
NET_NAME
'SMB_RT_CPU1_P0_ROM_MUX_1D_SCL'
 '@T6G_MB_LIB.T6G(SCH_1):SMB_RT_CPU1_P0_ROM_MUX_1D_SCL':
 C_SIGNAL='@t6g_mb_lib.t6g(sch_1):smb_rt_cpu1_p0_rom_mux_1d_scl';
NODE_NAME     U45 1
 '@T6G_MB_LIB.T6G(SCH_1):PAGE376_I22@PURE_QUANTA.PI3CSW12ZUAEX(CHIPS)':
 '1D+': CDS_PINID='\1d+\';
NODE_NAME     R1437 2
 '@T6G_MB_LIB.T6G(SCH_1):PAGE377_I172@PURE_QUANTA.Q_RES(CHIPS)':
 'B': CDS_PINID='B';
NODE_NAME     R674 1
 '@T6G_MB_LIB.T6G(SCH_1):PAGE401_I155@PURE_QUANTA.Q_RES(CHIPS)':
 'A': CDS_PINID='A';
NET_NAME
'SMB_RT_CPU1_P0_ROM_MUX_1D_SDA'
 '@T6G_MB_LIB.T6G(SCH_1):SMB_RT_CPU1_P0_ROM_MUX_1D_SDA':
 C_SIGNAL='@t6g_mb_lib.t6g(sch_1):smb_rt_cpu1_p0_rom_mux_1d_sda';
NODE_NAME     R675 1
 '@T6G_MB_LIB.T6G(SCH_1):PAGE401_I13@PURE_QUANTA.Q_RES(CHIPS)':
 'A': CDS_PINID='A';
NODE_NAME     U45 2
 '@T6G_MB_LIB.T6G(SCH_1):PAGE376_I22@PURE_QUANTA.PI3CSW12ZUAEX(CHIPS)':
 '1D-': CDS_PINID='\1d-\';
NODE_NAME     R1436 2
 '@T6G_MB_LIB.T6G(SCH_1):PAGE377_I173@PURE_QUANTA.Q_RES(CHIPS)':
 'B': CDS_PINID='B';
NET_NAME
'SMB_RT_CPU1_P0_ROM_MUX_2D_R_SCL'
 '@T6G_MB_LIB.T6G(SCH_1):SMB_RT_CPU1_P0_ROM_MUX_2D_R_SCL':
 C_SIGNAL='@t6g_mb_lib.t6g(sch_1):smb_rt_cpu1_p0_rom_mux_2d_r_scl';
NODE_NAME     R802 2
 '@T6G_MB_LIB.T6G(SCH_1):PAGE377_I50@PURE_QUANTA.Q_RES(CHIPS)':
 'B': CDS_PINID='B';
NODE_NAME     U22 5
 '@T6G_MB_LIB.T6G(SCH_1):PAGE377_I94@PURE_QUANTA.TCA9548APWR(CHIPS)':
 'SC0': CDS_PINID='SC0';
NODE_NAME     R1390 2
 '@T6G_MB_LIB.T6G(SCH_1):PAGE377_I105@PURE_QUANTA.Q_RES(CHIPS)':
 'B': CDS_PINID='B';
NET_NAME
'SMB_RT_CPU1_P0_ROM_MUX_2D_R_SDA'
 '@T6G_MB_LIB.T6G(SCH_1):SMB_RT_CPU1_P0_ROM_MUX_2D_R_SDA':
 C_SIGNAL='@t6g_mb_lib.t6g(sch_1):smb_rt_cpu1_p0_rom_mux_2d_r_sda';
NODE_NAME     R801 2
 '@T6G_MB_LIB.T6G(SCH_1):PAGE377_I49@PURE_QUANTA.Q_RES(CHIPS)':
 'B': CDS_PINID='B';
NODE_NAME     U22 4
 '@T6G_MB_LIB.T6G(SCH_1):PAGE377_I94@PURE_QUANTA.TCA9548APWR(CHIPS)':
 'SD0': CDS_PINID='SD0';
NODE_NAME     R1361 2
 '@T6G_MB_LIB.T6G(SCH_1):PAGE377_I104@PURE_QUANTA.Q_RES(CHIPS)':
 'B': CDS_PINID='B';
NET_NAME
'SMB_RT_CPU1_P0_ROM_MUX_2D_SCL'
 '@T6G_MB_LIB.T6G(SCH_1):SMB_RT_CPU1_P0_ROM_MUX_2D_SCL':
 C_SIGNAL='@t6g_mb_lib.t6g(sch_1):smb_rt_cpu1_p0_rom_mux_2d_scl';
NODE_NAME     R802 1
 '@T6G_MB_LIB.T6G(SCH_1):PAGE377_I50@PURE_QUANTA.Q_RES(CHIPS)':
 'A': CDS_PINID='A';
NODE_NAME     U45 3
 '@T6G_MB_LIB.T6G(SCH_1):PAGE376_I22@PURE_QUANTA.PI3CSW12ZUAEX(CHIPS)':
 '2D+': CDS_PINID='\2d+\';
NET_NAME
'SMB_RT_CPU1_P0_ROM_MUX_2D_SDA'
 '@T6G_MB_LIB.T6G(SCH_1):SMB_RT_CPU1_P0_ROM_MUX_2D_SDA':
 C_SIGNAL='@t6g_mb_lib.t6g(sch_1):smb_rt_cpu1_p0_rom_mux_2d_sda';
NODE_NAME     R801 1
 '@T6G_MB_LIB.T6G(SCH_1):PAGE377_I49@PURE_QUANTA.Q_RES(CHIPS)':
 'A': CDS_PINID='A';
NODE_NAME     U45 4
 '@T6G_MB_LIB.T6G(SCH_1):PAGE376_I22@PURE_QUANTA.PI3CSW12ZUAEX(CHIPS)':
 '2D-': CDS_PINID='\2d-\';
NET_NAME
'SMB_RT_CPU1_P0_ROM_R_SCL'
 '@T6G_MB_LIB.T6G(SCH_1):SMB_RT_CPU1_P0_ROM_R_SCL':
 C_SIGNAL='@t6g_mb_lib.t6g(sch_1):smb_rt_cpu1_p0_rom_r_scl';
NODE_NAME     R672 1
 '@T6G_MB_LIB.T6G(SCH_1):PAGE399_I3@PURE_QUANTA.Q_RES(CHIPS)':
 'A': CDS_PINID='A';
NODE_NAME     R6706 2
 '@T6G_MB_LIB.T6G(SCH_1):PAGE377_I65@PURE_QUANTA.Q_RES(CHIPS)':
 'B': CDS_PINID='B';
NODE_NAME     U45 8
 '@T6G_MB_LIB.T6G(SCH_1):PAGE376_I22@PURE_QUANTA.PI3CSW12ZUAEX(CHIPS)':
 'D+': CDS_PINID='\d+\';
NET_NAME
'SMB_RT_CPU1_P0_ROM_R_SDA'
 '@T6G_MB_LIB.T6G(SCH_1):SMB_RT_CPU1_P0_ROM_R_SDA':
 C_SIGNAL='@t6g_mb_lib.t6g(sch_1):smb_rt_cpu1_p0_rom_r_sda';
NODE_NAME     R673 1
 '@T6G_MB_LIB.T6G(SCH_1):PAGE399_I4@PURE_QUANTA.Q_RES(CHIPS)':
 'A': CDS_PINID='A';
NODE_NAME     R6707 2
 '@T6G_MB_LIB.T6G(SCH_1):PAGE377_I64@PURE_QUANTA.Q_RES(CHIPS)':
 'B': CDS_PINID='B';
NODE_NAME     U45 7
 '@T6G_MB_LIB.T6G(SCH_1):PAGE376_I22@PURE_QUANTA.PI3CSW12ZUAEX(CHIPS)':
 'D-': CDS_PINID='\d-\';
NET_NAME
'SMB_RT_CPU1_P0_ROM_SCL'
 '@T6G_MB_LIB.T6G(SCH_1):SMB_RT_CPU1_P0_ROM_SCL':
 C_SIGNAL='@t6g_mb_lib.t6g(sch_1):smb_rt_cpu1_p0_rom_scl';
NODE_NAME     R672 2
 '@T6G_MB_LIB.T6G(SCH_1):PAGE399_I3@PURE_QUANTA.Q_RES(CHIPS)':
 'B': CDS_PINID='B';
NODE_NAME     U12 6
 '@T6G_MB_LIB.T6G(SCH_1):PAGE399_I5@PURE_QUANTA.M24M02DRMN6TP(CHIPS)':
 'SCL': CDS_PINID='SCL';
NET_NAME
'SMB_RT_CPU1_P0_ROM_SDA'
 '@T6G_MB_LIB.T6G(SCH_1):SMB_RT_CPU1_P0_ROM_SDA':
 C_SIGNAL='@t6g_mb_lib.t6g(sch_1):smb_rt_cpu1_p0_rom_sda';
NODE_NAME     R673 2
 '@T6G_MB_LIB.T6G(SCH_1):PAGE399_I4@PURE_QUANTA.Q_RES(CHIPS)':
 'B': CDS_PINID='B';
NODE_NAME     U12 5
 '@T6G_MB_LIB.T6G(SCH_1):PAGE399_I5@PURE_QUANTA.M24M02DRMN6TP(CHIPS)':
 'SDA': CDS_PINID='SDA';
NET_NAME
'SMB_RT_CPU1_P0_R_SCL'
 '@T6G_MB_LIB.T6G(SCH_1):SMB_RT_CPU1_P0_R_SCL':
 C_SIGNAL='@t6g_mb_lib.t6g(sch_1):smb_rt_cpu1_p0_r_scl';
NODE_NAME     R6812 1
 '@T6G_MB_LIB.T6G(SCH_1):PAGE401_I19@PURE_QUANTA.Q_RES(CHIPS)':
 'A': CDS_PINID='A';
NODE_NAME     R6811 1
 '@T6G_MB_LIB.T6G(SCH_1):PAGE378_I7@PURE_QUANTA.Q_RES(CHIPS)':
 'A': CDS_PINID='A';
NODE_NAME     R6719 2
 '@T6G_MB_LIB.T6G(SCH_1):PAGE378_I11@PURE_QUANTA.Q_RES(CHIPS)':
 'B': CDS_PINID='B';
NET_NAME
'SMB_RT_CPU1_P0_R_SDA'
 '@T6G_MB_LIB.T6G(SCH_1):SMB_RT_CPU1_P0_R_SDA':
 C_SIGNAL='@t6g_mb_lib.t6g(sch_1):smb_rt_cpu1_p0_r_sda';
NODE_NAME     R6813 1
 '@T6G_MB_LIB.T6G(SCH_1):PAGE401_I20@PURE_QUANTA.Q_RES(CHIPS)':
 'A': CDS_PINID='A';
NODE_NAME     R6810 1
 '@T6G_MB_LIB.T6G(SCH_1):PAGE378_I6@PURE_QUANTA.Q_RES(CHIPS)':
 'A': CDS_PINID='A';
NODE_NAME     R6718 2
 '@T6G_MB_LIB.T6G(SCH_1):PAGE378_I9@PURE_QUANTA.Q_RES(CHIPS)':
 'B': CDS_PINID='B';
NET_NAME
'SMB_RT_CPU1_P0_SCL'
 '@T6G_MB_LIB.T6G(SCH_1):SMB_RT_CPU1_P0_SCL':
 C_SIGNAL='@t6g_mb_lib.t6g(sch_1):smb_rt_cpu1_p0_scl';
NODE_NAME     U6020 5
 '@T6G_MB_LIB.T6G(SCH_1):PAGE378_I1@PURE_QUANTA.TCA9548APWR(CHIPS)':
 'SC0': CDS_PINID='SC0';
NODE_NAME     R6811 2
 '@T6G_MB_LIB.T6G(SCH_1):PAGE378_I7@PURE_QUANTA.Q_RES(CHIPS)':
 'B': CDS_PINID='B';
NET_NAME
'SMB_RT_CPU1_P0_SDA'
 '@T6G_MB_LIB.T6G(SCH_1):SMB_RT_CPU1_P0_SDA':
 C_SIGNAL='@t6g_mb_lib.t6g(sch_1):smb_rt_cpu1_p0_sda';
NODE_NAME     U6020 4
 '@T6G_MB_LIB.T6G(SCH_1):PAGE378_I1@PURE_QUANTA.TCA9548APWR(CHIPS)':
 'SD0': CDS_PINID='SD0';
NODE_NAME     R6810 2
 '@T6G_MB_LIB.T6G(SCH_1):PAGE378_I6@PURE_QUANTA.Q_RES(CHIPS)':
 'B': CDS_PINID='B';
NET_NAME
'SMB_RT_CPU1_P1_R2_SCL'
 '@T6G_MB_LIB.T6G(SCH_1):SMB_RT_CPU1_P1_R2_SCL':
 C_SIGNAL='@t6g_mb_lib.t6g(sch_1):smb_rt_cpu1_p1_r2_scl';
NODE_NAME     R779 2
 '@T6G_MB_LIB.T6G(SCH_1):PAGE392_I44@PURE_QUANTA.Q_RES(CHIPS)':
 'B': CDS_PINID='B';
NODE_NAME     U6015 B31
 '@T6G_MB_LIB.T6G(SCH_1):PAGE392_I47@PURE_QUANTA.PT5161LRS(CHIPS)':
 'SMBCLK': CDS_PINID='SMBCLK';
NET_NAME
'SMB_RT_CPU1_P1_R2_SDA'
 '@T6G_MB_LIB.T6G(SCH_1):SMB_RT_CPU1_P1_R2_SDA':
 C_SIGNAL='@t6g_mb_lib.t6g(sch_1):smb_rt_cpu1_p1_r2_sda';
NODE_NAME     R780 2
 '@T6G_MB_LIB.T6G(SCH_1):PAGE392_I43@PURE_QUANTA.Q_RES(CHIPS)':
 'B': CDS_PINID='B';
NODE_NAME     U6015 B28
 '@T6G_MB_LIB.T6G(SCH_1):PAGE392_I47@PURE_QUANTA.PT5161LRS(CHIPS)':
 'SMBDAT': CDS_PINID='SMBDAT';
NET_NAME
'SMB_RT_CPU1_P1_ROM_MUX_1D_R_SCL'
 '@T6G_MB_LIB.T6G(SCH_1):SMB_RT_CPU1_P1_ROM_MUX_1D_R_SCL':
 C_SIGNAL='@t6g_mb_lib.t6g(sch_1):smb_rt_cpu1_p1_rom_mux_1d_r_scl';
NODE_NAME     R670 2
 '@T6G_MB_LIB.T6G(SCH_1):PAGE392_I36@PURE_QUANTA.Q_RES(CHIPS)':
 'B': CDS_PINID='B';
NODE_NAME     U6015 FF5
 '@T6G_MB_LIB.T6G(SCH_1):PAGE392_I47@PURE_QUANTA.PT5161LRS(CHIPS)':
 'EE_CLK': CDS_PINID='EE_CLK';
NET_NAME
'SMB_RT_CPU1_P1_ROM_MUX_1D_R_SDA'
 '@T6G_MB_LIB.T6G(SCH_1):SMB_RT_CPU1_P1_ROM_MUX_1D_R_SDA':
 C_SIGNAL='@t6g_mb_lib.t6g(sch_1):smb_rt_cpu1_p1_rom_mux_1d_r_sda';
NODE_NAME     R671 2
 '@T6G_MB_LIB.T6G(SCH_1):PAGE392_I35@PURE_QUANTA.Q_RES(CHIPS)':
 'B': CDS_PINID='B';
NODE_NAME     U6015 FJ3
 '@T6G_MB_LIB.T6G(SCH_1):PAGE392_I47@PURE_QUANTA.PT5161LRS(CHIPS)':
 'EE_DAT': CDS_PINID='EE_DAT';
NET_NAME
'SMB_RT_CPU1_P1_ROM_MUX_1D_SCL'
 '@T6G_MB_LIB.T6G(SCH_1):SMB_RT_CPU1_P1_ROM_MUX_1D_SCL':
 C_SIGNAL='@t6g_mb_lib.t6g(sch_1):smb_rt_cpu1_p1_rom_mux_1d_scl';
NODE_NAME     R670 1
 '@T6G_MB_LIB.T6G(SCH_1):PAGE392_I36@PURE_QUANTA.Q_RES(CHIPS)':
 'A': CDS_PINID='A';
NODE_NAME     U42 1
 '@T6G_MB_LIB.T6G(SCH_1):PAGE376_I31@PURE_QUANTA.PI3CSW12ZUAEX(CHIPS)':
 '1D+': CDS_PINID='\1d+\';
NODE_NAME     R1451 2
 '@T6G_MB_LIB.T6G(SCH_1):PAGE377_I175@PURE_QUANTA.Q_RES(CHIPS)':
 'B': CDS_PINID='B';
NET_NAME
'SMB_RT_CPU1_P1_ROM_MUX_1D_SDA'
 '@T6G_MB_LIB.T6G(SCH_1):SMB_RT_CPU1_P1_ROM_MUX_1D_SDA':
 C_SIGNAL='@t6g_mb_lib.t6g(sch_1):smb_rt_cpu1_p1_rom_mux_1d_sda';
NODE_NAME     R671 1
 '@T6G_MB_LIB.T6G(SCH_1):PAGE392_I35@PURE_QUANTA.Q_RES(CHIPS)':
 'A': CDS_PINID='A';
NODE_NAME     U42 2
 '@T6G_MB_LIB.T6G(SCH_1):PAGE376_I31@PURE_QUANTA.PI3CSW12ZUAEX(CHIPS)':
 '1D-': CDS_PINID='\1d-\';
NODE_NAME     R1448 2
 '@T6G_MB_LIB.T6G(SCH_1):PAGE377_I174@PURE_QUANTA.Q_RES(CHIPS)':
 'B': CDS_PINID='B';
NET_NAME
'SMB_RT_CPU1_P1_ROM_MUX_2D_R_SCL'
 '@T6G_MB_LIB.T6G(SCH_1):SMB_RT_CPU1_P1_ROM_MUX_2D_R_SCL':
 C_SIGNAL='@t6g_mb_lib.t6g(sch_1):smb_rt_cpu1_p1_rom_mux_2d_r_scl';
NODE_NAME     R805 2
 '@T6G_MB_LIB.T6G(SCH_1):PAGE377_I46@PURE_QUANTA.Q_RES(CHIPS)':
 'B': CDS_PINID='B';
NODE_NAME     U22 7
 '@T6G_MB_LIB.T6G(SCH_1):PAGE377_I94@PURE_QUANTA.TCA9548APWR(CHIPS)':
 'SC1': CDS_PINID='SC1';
NODE_NAME     R1394 2
 '@T6G_MB_LIB.T6G(SCH_1):PAGE377_I107@PURE_QUANTA.Q_RES(CHIPS)':
 'B': CDS_PINID='B';
NET_NAME
'SMB_RT_CPU1_P1_ROM_MUX_2D_R_SDA'
 '@T6G_MB_LIB.T6G(SCH_1):SMB_RT_CPU1_P1_ROM_MUX_2D_R_SDA':
 C_SIGNAL='@t6g_mb_lib.t6g(sch_1):smb_rt_cpu1_p1_rom_mux_2d_r_sda';
NODE_NAME     R803 2
 '@T6G_MB_LIB.T6G(SCH_1):PAGE377_I48@PURE_QUANTA.Q_RES(CHIPS)':
 'B': CDS_PINID='B';
NODE_NAME     U22 6
 '@T6G_MB_LIB.T6G(SCH_1):PAGE377_I94@PURE_QUANTA.TCA9548APWR(CHIPS)':
 'SD1': CDS_PINID='SD1';
NODE_NAME     R1393 2
 '@T6G_MB_LIB.T6G(SCH_1):PAGE377_I106@PURE_QUANTA.Q_RES(CHIPS)':
 'B': CDS_PINID='B';
NET_NAME
'SMB_RT_CPU1_P1_ROM_MUX_2D_SCL'
 '@T6G_MB_LIB.T6G(SCH_1):SMB_RT_CPU1_P1_ROM_MUX_2D_SCL':
 C_SIGNAL='@t6g_mb_lib.t6g(sch_1):smb_rt_cpu1_p1_rom_mux_2d_scl';
NODE_NAME     R805 1
 '@T6G_MB_LIB.T6G(SCH_1):PAGE377_I46@PURE_QUANTA.Q_RES(CHIPS)':
 'A': CDS_PINID='A';
NODE_NAME     U42 3
 '@T6G_MB_LIB.T6G(SCH_1):PAGE376_I31@PURE_QUANTA.PI3CSW12ZUAEX(CHIPS)':
 '2D+': CDS_PINID='\2d+\';
NET_NAME
'SMB_RT_CPU1_P1_ROM_MUX_2D_SDA'
 '@T6G_MB_LIB.T6G(SCH_1):SMB_RT_CPU1_P1_ROM_MUX_2D_SDA':
 C_SIGNAL='@t6g_mb_lib.t6g(sch_1):smb_rt_cpu1_p1_rom_mux_2d_sda';
NODE_NAME     R803 1
 '@T6G_MB_LIB.T6G(SCH_1):PAGE377_I48@PURE_QUANTA.Q_RES(CHIPS)':
 'A': CDS_PINID='A';
NODE_NAME     U42 4
 '@T6G_MB_LIB.T6G(SCH_1):PAGE376_I31@PURE_QUANTA.PI3CSW12ZUAEX(CHIPS)':
 '2D-': CDS_PINID='\2d-\';
NET_NAME
'SMB_RT_CPU1_P1_ROM_R_SCL'
 '@T6G_MB_LIB.T6G(SCH_1):SMB_RT_CPU1_P1_ROM_R_SCL':
 C_SIGNAL='@t6g_mb_lib.t6g(sch_1):smb_rt_cpu1_p1_rom_r_scl';
NODE_NAME     R689 1
 '@T6G_MB_LIB.T6G(SCH_1):PAGE442_I4@PURE_QUANTA.Q_RES(CHIPS)':
 'A': CDS_PINID='A';
NODE_NAME     R6734 2
 '@T6G_MB_LIB.T6G(SCH_1):PAGE377_I62@PURE_QUANTA.Q_RES(CHIPS)':
 'B': CDS_PINID='B';
NODE_NAME     U42 8
 '@T6G_MB_LIB.T6G(SCH_1):PAGE376_I31@PURE_QUANTA.PI3CSW12ZUAEX(CHIPS)':
 'D+': CDS_PINID='\d+\';
NET_NAME
'SMB_RT_CPU1_P1_ROM_R_SDA'
 '@T6G_MB_LIB.T6G(SCH_1):SMB_RT_CPU1_P1_ROM_R_SDA':
 C_SIGNAL='@t6g_mb_lib.t6g(sch_1):smb_rt_cpu1_p1_rom_r_sda';
NODE_NAME     R690 1
 '@T6G_MB_LIB.T6G(SCH_1):PAGE442_I3@PURE_QUANTA.Q_RES(CHIPS)':
 'A': CDS_PINID='A';
NODE_NAME     R6735 2
 '@T6G_MB_LIB.T6G(SCH_1):PAGE377_I63@PURE_QUANTA.Q_RES(CHIPS)':
 'B': CDS_PINID='B';
NODE_NAME     U42 7
 '@T6G_MB_LIB.T6G(SCH_1):PAGE376_I31@PURE_QUANTA.PI3CSW12ZUAEX(CHIPS)':
 'D-': CDS_PINID='\d-\';
NET_NAME
'SMB_RT_CPU1_P1_ROM_SCL'
 '@T6G_MB_LIB.T6G(SCH_1):SMB_RT_CPU1_P1_ROM_SCL':
 C_SIGNAL='@t6g_mb_lib.t6g(sch_1):smb_rt_cpu1_p1_rom_scl';
NODE_NAME     R689 2
 '@T6G_MB_LIB.T6G(SCH_1):PAGE442_I4@PURE_QUANTA.Q_RES(CHIPS)':
 'B': CDS_PINID='B';
NODE_NAME     U19 6
 '@T6G_MB_LIB.T6G(SCH_1):PAGE442_I5@PURE_QUANTA.M24M02DRMN6TP(CHIPS)':
 'SCL': CDS_PINID='SCL';
NET_NAME
'SMB_RT_CPU1_P1_ROM_SDA'
 '@T6G_MB_LIB.T6G(SCH_1):SMB_RT_CPU1_P1_ROM_SDA':
 C_SIGNAL='@t6g_mb_lib.t6g(sch_1):smb_rt_cpu1_p1_rom_sda';
NODE_NAME     R690 2
 '@T6G_MB_LIB.T6G(SCH_1):PAGE442_I3@PURE_QUANTA.Q_RES(CHIPS)':
 'B': CDS_PINID='B';
NODE_NAME     U19 5
 '@T6G_MB_LIB.T6G(SCH_1):PAGE442_I5@PURE_QUANTA.M24M02DRMN6TP(CHIPS)':
 'SDA': CDS_PINID='SDA';
NET_NAME
'SMB_RT_CPU1_P1_R_SCL'
 '@T6G_MB_LIB.T6G(SCH_1):SMB_RT_CPU1_P1_R_SCL':
 C_SIGNAL='@t6g_mb_lib.t6g(sch_1):smb_rt_cpu1_p1_r_scl';
NODE_NAME     R779 1
 '@T6G_MB_LIB.T6G(SCH_1):PAGE392_I44@PURE_QUANTA.Q_RES(CHIPS)':
 'A': CDS_PINID='A';
NODE_NAME     R6737 1
 '@T6G_MB_LIB.T6G(SCH_1):PAGE378_I14@PURE_QUANTA.Q_RES(CHIPS)':
 'A': CDS_PINID='A';
NODE_NAME     R6739 2
 '@T6G_MB_LIB.T6G(SCH_1):PAGE378_I18@PURE_QUANTA.Q_RES(CHIPS)':
 'B': CDS_PINID='B';
NET_NAME
'SMB_RT_CPU1_P1_R_SDA'
 '@T6G_MB_LIB.T6G(SCH_1):SMB_RT_CPU1_P1_R_SDA':
 C_SIGNAL='@t6g_mb_lib.t6g(sch_1):smb_rt_cpu1_p1_r_sda';
NODE_NAME     R780 1
 '@T6G_MB_LIB.T6G(SCH_1):PAGE392_I43@PURE_QUANTA.Q_RES(CHIPS)':
 'A': CDS_PINID='A';
NODE_NAME     R6736 1
 '@T6G_MB_LIB.T6G(SCH_1):PAGE378_I13@PURE_QUANTA.Q_RES(CHIPS)':
 'A': CDS_PINID='A';
NODE_NAME     R6738 2
 '@T6G_MB_LIB.T6G(SCH_1):PAGE378_I17@PURE_QUANTA.Q_RES(CHIPS)':
 'B': CDS_PINID='B';
NET_NAME
'SMB_RT_CPU1_P1_SCL'
 '@T6G_MB_LIB.T6G(SCH_1):SMB_RT_CPU1_P1_SCL':
 C_SIGNAL='@t6g_mb_lib.t6g(sch_1):smb_rt_cpu1_p1_scl';
NODE_NAME     U6020 7
 '@T6G_MB_LIB.T6G(SCH_1):PAGE378_I1@PURE_QUANTA.TCA9548APWR(CHIPS)':
 'SC1': CDS_PINID='SC1';
NODE_NAME     R6737 2
 '@T6G_MB_LIB.T6G(SCH_1):PAGE378_I14@PURE_QUANTA.Q_RES(CHIPS)':
 'B': CDS_PINID='B';
NET_NAME
'SMB_RT_CPU1_P1_SDA'
 '@T6G_MB_LIB.T6G(SCH_1):SMB_RT_CPU1_P1_SDA':
 C_SIGNAL='@t6g_mb_lib.t6g(sch_1):smb_rt_cpu1_p1_sda';
NODE_NAME     U6020 6
 '@T6G_MB_LIB.T6G(SCH_1):PAGE378_I1@PURE_QUANTA.TCA9548APWR(CHIPS)':
 'SD1': CDS_PINID='SD1';
NODE_NAME     R6736 2
 '@T6G_MB_LIB.T6G(SCH_1):PAGE378_I13@PURE_QUANTA.Q_RES(CHIPS)':
 'B': CDS_PINID='B';
NET_NAME
'SMB_RT_CPU1_P2_R2_SCL'
 '@T6G_MB_LIB.T6G(SCH_1):SMB_RT_CPU1_P2_R2_SCL':
 C_SIGNAL='@t6g_mb_lib.t6g(sch_1):smb_rt_cpu1_p2_r2_scl';
NODE_NAME     R872 2
 '@T6G_MB_LIB.T6G(SCH_1):PAGE451_I34@PURE_QUANTA.Q_RES(CHIPS)':
 'B': CDS_PINID='B';
NODE_NAME     U6016 B31
 '@T6G_MB_LIB.T6G(SCH_1):PAGE451_I97@PURE_QUANTA.PT5161LRS(CHIPS)':
 'SMBCLK': CDS_PINID='SMBCLK';
NET_NAME
'SMB_RT_CPU1_P2_R2_SDA'
 '@T6G_MB_LIB.T6G(SCH_1):SMB_RT_CPU1_P2_R2_SDA':
 C_SIGNAL='@t6g_mb_lib.t6g(sch_1):smb_rt_cpu1_p2_r2_sda';
NODE_NAME     R873 2
 '@T6G_MB_LIB.T6G(SCH_1):PAGE451_I35@PURE_QUANTA.Q_RES(CHIPS)':
 'B': CDS_PINID='B';
NODE_NAME     U6016 B28
 '@T6G_MB_LIB.T6G(SCH_1):PAGE451_I97@PURE_QUANTA.PT5161LRS(CHIPS)':
 'SMBDAT': CDS_PINID='SMBDAT';
NET_NAME
'SMB_RT_CPU1_P2_ROM_MUX_1D_R_SCL'
 '@T6G_MB_LIB.T6G(SCH_1):SMB_RT_CPU1_P2_ROM_MUX_1D_R_SCL':
 C_SIGNAL='@t6g_mb_lib.t6g(sch_1):smb_rt_cpu1_p2_rom_mux_1d_r_scl';
NODE_NAME     R691 2
 '@T6G_MB_LIB.T6G(SCH_1):PAGE451_I30@PURE_QUANTA.Q_RES(CHIPS)':
 'B': CDS_PINID='B';
NODE_NAME     U6016 FF5
 '@T6G_MB_LIB.T6G(SCH_1):PAGE451_I97@PURE_QUANTA.PT5161LRS(CHIPS)':
 'EE_CLK': CDS_PINID='EE_CLK';
NET_NAME
'SMB_RT_CPU1_P2_ROM_MUX_1D_R_SDA'
 '@T6G_MB_LIB.T6G(SCH_1):SMB_RT_CPU1_P2_ROM_MUX_1D_R_SDA':
 C_SIGNAL='@t6g_mb_lib.t6g(sch_1):smb_rt_cpu1_p2_rom_mux_1d_r_sda';
NODE_NAME     R692 2
 '@T6G_MB_LIB.T6G(SCH_1):PAGE451_I29@PURE_QUANTA.Q_RES(CHIPS)':
 'B': CDS_PINID='B';
NODE_NAME     U6016 FJ3
 '@T6G_MB_LIB.T6G(SCH_1):PAGE451_I97@PURE_QUANTA.PT5161LRS(CHIPS)':
 'EE_DAT': CDS_PINID='EE_DAT';
NET_NAME
'SMB_RT_CPU1_P2_ROM_MUX_1D_SCL'
 '@T6G_MB_LIB.T6G(SCH_1):SMB_RT_CPU1_P2_ROM_MUX_1D_SCL':
 C_SIGNAL='@t6g_mb_lib.t6g(sch_1):smb_rt_cpu1_p2_rom_mux_1d_scl';
NODE_NAME     R691 1
 '@T6G_MB_LIB.T6G(SCH_1):PAGE451_I30@PURE_QUANTA.Q_RES(CHIPS)':
 'A': CDS_PINID='A';
NODE_NAME     U43 1
 '@T6G_MB_LIB.T6G(SCH_1):PAGE376_I61@PURE_QUANTA.PI3CSW12ZUAEX(CHIPS)':
 '1D+': CDS_PINID='\1d+\';
NODE_NAME     R1469 2
 '@T6G_MB_LIB.T6G(SCH_1):PAGE377_I179@PURE_QUANTA.Q_RES(CHIPS)':
 'B': CDS_PINID='B';
NET_NAME
'SMB_RT_CPU1_P2_ROM_MUX_1D_SDA'
 '@T6G_MB_LIB.T6G(SCH_1):SMB_RT_CPU1_P2_ROM_MUX_1D_SDA':
 C_SIGNAL='@t6g_mb_lib.t6g(sch_1):smb_rt_cpu1_p2_rom_mux_1d_sda';
NODE_NAME     R692 1
 '@T6G_MB_LIB.T6G(SCH_1):PAGE451_I29@PURE_QUANTA.Q_RES(CHIPS)':
 'A': CDS_PINID='A';
NODE_NAME     U43 2
 '@T6G_MB_LIB.T6G(SCH_1):PAGE376_I61@PURE_QUANTA.PI3CSW12ZUAEX(CHIPS)':
 '1D-': CDS_PINID='\1d-\';
NODE_NAME     R1468 2
 '@T6G_MB_LIB.T6G(SCH_1):PAGE377_I178@PURE_QUANTA.Q_RES(CHIPS)':
 'B': CDS_PINID='B';
NET_NAME
'SMB_RT_CPU1_P2_ROM_MUX_2D_R_SCL'
 '@T6G_MB_LIB.T6G(SCH_1):SMB_RT_CPU1_P2_ROM_MUX_2D_R_SCL':
 C_SIGNAL='@t6g_mb_lib.t6g(sch_1):smb_rt_cpu1_p2_rom_mux_2d_r_scl';
NODE_NAME     R809 2
 '@T6G_MB_LIB.T6G(SCH_1):PAGE377_I44@PURE_QUANTA.Q_RES(CHIPS)':
 'B': CDS_PINID='B';
NODE_NAME     U22 11
 '@T6G_MB_LIB.T6G(SCH_1):PAGE377_I94@PURE_QUANTA.TCA9548APWR(CHIPS)':
 'SC3': CDS_PINID='SC3';
NODE_NAME     R1407 2
 '@T6G_MB_LIB.T6G(SCH_1):PAGE377_I111@PURE_QUANTA.Q_RES(CHIPS)':
 'B': CDS_PINID='B';
NET_NAME
'SMB_RT_CPU1_P2_ROM_MUX_2D_R_SDA'
 '@T6G_MB_LIB.T6G(SCH_1):SMB_RT_CPU1_P2_ROM_MUX_2D_R_SDA':
 C_SIGNAL='@t6g_mb_lib.t6g(sch_1):smb_rt_cpu1_p2_rom_mux_2d_r_sda';
NODE_NAME     R808 2
 '@T6G_MB_LIB.T6G(SCH_1):PAGE377_I45@PURE_QUANTA.Q_RES(CHIPS)':
 'B': CDS_PINID='B';
NODE_NAME     U22 10
 '@T6G_MB_LIB.T6G(SCH_1):PAGE377_I94@PURE_QUANTA.TCA9548APWR(CHIPS)':
 'SD3': CDS_PINID='SD3';
NODE_NAME     R1403 2
 '@T6G_MB_LIB.T6G(SCH_1):PAGE377_I110@PURE_QUANTA.Q_RES(CHIPS)':
 'B': CDS_PINID='B';
NET_NAME
'SMB_RT_CPU1_P2_ROM_MUX_2D_SCL'
 '@T6G_MB_LIB.T6G(SCH_1):SMB_RT_CPU1_P2_ROM_MUX_2D_SCL':
 C_SIGNAL='@t6g_mb_lib.t6g(sch_1):smb_rt_cpu1_p2_rom_mux_2d_scl';
NODE_NAME     R809 1
 '@T6G_MB_LIB.T6G(SCH_1):PAGE377_I44@PURE_QUANTA.Q_RES(CHIPS)':
 'A': CDS_PINID='A';
NODE_NAME     U43 3
 '@T6G_MB_LIB.T6G(SCH_1):PAGE376_I61@PURE_QUANTA.PI3CSW12ZUAEX(CHIPS)':
 '2D+': CDS_PINID='\2d+\';
NET_NAME
'SMB_RT_CPU1_P2_ROM_MUX_2D_SDA'
 '@T6G_MB_LIB.T6G(SCH_1):SMB_RT_CPU1_P2_ROM_MUX_2D_SDA':
 C_SIGNAL='@t6g_mb_lib.t6g(sch_1):smb_rt_cpu1_p2_rom_mux_2d_sda';
NODE_NAME     R808 1
 '@T6G_MB_LIB.T6G(SCH_1):PAGE377_I45@PURE_QUANTA.Q_RES(CHIPS)':
 'A': CDS_PINID='A';
NODE_NAME     U43 4
 '@T6G_MB_LIB.T6G(SCH_1):PAGE376_I61@PURE_QUANTA.PI3CSW12ZUAEX(CHIPS)':
 '2D-': CDS_PINID='\2d-\';
NET_NAME
'SMB_RT_CPU1_P2_ROM_R_SCL'
 '@T6G_MB_LIB.T6G(SCH_1):SMB_RT_CPU1_P2_ROM_R_SCL':
 C_SIGNAL='@t6g_mb_lib.t6g(sch_1):smb_rt_cpu1_p2_rom_r_scl';
NODE_NAME     R693 1
 '@T6G_MB_LIB.T6G(SCH_1):PAGE453_I4@PURE_QUANTA.Q_RES(CHIPS)':
 'A': CDS_PINID='A';
NODE_NAME     R827 2
 '@T6G_MB_LIB.T6G(SCH_1):PAGE377_I58@PURE_QUANTA.Q_RES(CHIPS)':
 'B': CDS_PINID='B';
NODE_NAME     U43 8
 '@T6G_MB_LIB.T6G(SCH_1):PAGE376_I61@PURE_QUANTA.PI3CSW12ZUAEX(CHIPS)':
 'D+': CDS_PINID='\d+\';
NET_NAME
'SMB_RT_CPU1_P2_ROM_R_SDA'
 '@T6G_MB_LIB.T6G(SCH_1):SMB_RT_CPU1_P2_ROM_R_SDA':
 C_SIGNAL='@t6g_mb_lib.t6g(sch_1):smb_rt_cpu1_p2_rom_r_sda';
NODE_NAME     R694 1
 '@T6G_MB_LIB.T6G(SCH_1):PAGE453_I3@PURE_QUANTA.Q_RES(CHIPS)':
 'A': CDS_PINID='A';
NODE_NAME     R826 2
 '@T6G_MB_LIB.T6G(SCH_1):PAGE377_I59@PURE_QUANTA.Q_RES(CHIPS)':
 'B': CDS_PINID='B';
NODE_NAME     U43 7
 '@T6G_MB_LIB.T6G(SCH_1):PAGE376_I61@PURE_QUANTA.PI3CSW12ZUAEX(CHIPS)':
 'D-': CDS_PINID='\d-\';
NET_NAME
'SMB_RT_CPU1_P2_ROM_SCL'
 '@T6G_MB_LIB.T6G(SCH_1):SMB_RT_CPU1_P2_ROM_SCL':
 C_SIGNAL='@t6g_mb_lib.t6g(sch_1):smb_rt_cpu1_p2_rom_scl';
NODE_NAME     R693 2
 '@T6G_MB_LIB.T6G(SCH_1):PAGE453_I4@PURE_QUANTA.Q_RES(CHIPS)':
 'B': CDS_PINID='B';
NODE_NAME     U20 6
 '@T6G_MB_LIB.T6G(SCH_1):PAGE453_I5@PURE_QUANTA.M24M02DRMN6TP(CHIPS)':
 'SCL': CDS_PINID='SCL';
NET_NAME
'SMB_RT_CPU1_P2_ROM_SDA'
 '@T6G_MB_LIB.T6G(SCH_1):SMB_RT_CPU1_P2_ROM_SDA':
 C_SIGNAL='@t6g_mb_lib.t6g(sch_1):smb_rt_cpu1_p2_rom_sda';
NODE_NAME     R694 2
 '@T6G_MB_LIB.T6G(SCH_1):PAGE453_I3@PURE_QUANTA.Q_RES(CHIPS)':
 'B': CDS_PINID='B';
NODE_NAME     U20 5
 '@T6G_MB_LIB.T6G(SCH_1):PAGE453_I5@PURE_QUANTA.M24M02DRMN6TP(CHIPS)':
 'SDA': CDS_PINID='SDA';
NET_NAME
'SMB_RT_CPU1_P2_R_SCL'
 '@T6G_MB_LIB.T6G(SCH_1):SMB_RT_CPU1_P2_R_SCL':
 C_SIGNAL='@t6g_mb_lib.t6g(sch_1):smb_rt_cpu1_p2_r_scl';
NODE_NAME     R6749 1
 '@T6G_MB_LIB.T6G(SCH_1):PAGE378_I25@PURE_QUANTA.Q_RES(CHIPS)':
 'A': CDS_PINID='A';
NODE_NAME     R6753 2
 '@T6G_MB_LIB.T6G(SCH_1):PAGE378_I36@PURE_QUANTA.Q_RES(CHIPS)':
 'B': CDS_PINID='B';
NODE_NAME     R872 1
 '@T6G_MB_LIB.T6G(SCH_1):PAGE451_I34@PURE_QUANTA.Q_RES(CHIPS)':
 'A': CDS_PINID='A';
NET_NAME
'SMB_RT_CPU1_P2_R_SDA'
 '@T6G_MB_LIB.T6G(SCH_1):SMB_RT_CPU1_P2_R_SDA':
 C_SIGNAL='@t6g_mb_lib.t6g(sch_1):smb_rt_cpu1_p2_r_sda';
NODE_NAME     R6748 1
 '@T6G_MB_LIB.T6G(SCH_1):PAGE378_I26@PURE_QUANTA.Q_RES(CHIPS)':
 'A': CDS_PINID='A';
NODE_NAME     R6752 2
 '@T6G_MB_LIB.T6G(SCH_1):PAGE378_I35@PURE_QUANTA.Q_RES(CHIPS)':
 'B': CDS_PINID='B';
NODE_NAME     R873 1
 '@T6G_MB_LIB.T6G(SCH_1):PAGE451_I35@PURE_QUANTA.Q_RES(CHIPS)':
 'A': CDS_PINID='A';
NET_NAME
'SMB_RT_CPU1_P2_SCL'
 '@T6G_MB_LIB.T6G(SCH_1):SMB_RT_CPU1_P2_SCL':
 C_SIGNAL='@t6g_mb_lib.t6g(sch_1):smb_rt_cpu1_p2_scl';
NODE_NAME     U6020 11
 '@T6G_MB_LIB.T6G(SCH_1):PAGE378_I1@PURE_QUANTA.TCA9548APWR(CHIPS)':
 'SC3': CDS_PINID='SC3';
NODE_NAME     R6749 2
 '@T6G_MB_LIB.T6G(SCH_1):PAGE378_I25@PURE_QUANTA.Q_RES(CHIPS)':
 'B': CDS_PINID='B';
NET_NAME
'SMB_RT_CPU1_P2_SDA'
 '@T6G_MB_LIB.T6G(SCH_1):SMB_RT_CPU1_P2_SDA':
 C_SIGNAL='@t6g_mb_lib.t6g(sch_1):smb_rt_cpu1_p2_sda';
NODE_NAME     U6020 10
 '@T6G_MB_LIB.T6G(SCH_1):PAGE378_I1@PURE_QUANTA.TCA9548APWR(CHIPS)':
 'SD3': CDS_PINID='SD3';
NODE_NAME     R6748 2
 '@T6G_MB_LIB.T6G(SCH_1):PAGE378_I26@PURE_QUANTA.Q_RES(CHIPS)':
 'B': CDS_PINID='B';
NET_NAME
'SMB_RT_CPU1_P3_R2_SCL'
 '@T6G_MB_LIB.T6G(SCH_1):SMB_RT_CPU1_P3_R2_SCL':
 C_SIGNAL='@t6g_mb_lib.t6g(sch_1):smb_rt_cpu1_p3_r2_scl';
NODE_NAME     R913 2
 '@T6G_MB_LIB.T6G(SCH_1):PAGE462_I42@PURE_QUANTA.Q_RES(CHIPS)':
 'B': CDS_PINID='B';
NODE_NAME     U6017 B31
 '@T6G_MB_LIB.T6G(SCH_1):PAGE462_I97@PURE_QUANTA.PT5161LRS(CHIPS)':
 'SMBCLK': CDS_PINID='SMBCLK';
NET_NAME
'SMB_RT_CPU1_P3_R2_SDA'
 '@T6G_MB_LIB.T6G(SCH_1):SMB_RT_CPU1_P3_R2_SDA':
 C_SIGNAL='@t6g_mb_lib.t6g(sch_1):smb_rt_cpu1_p3_r2_sda';
NODE_NAME     R914 2
 '@T6G_MB_LIB.T6G(SCH_1):PAGE462_I41@PURE_QUANTA.Q_RES(CHIPS)':
 'B': CDS_PINID='B';
NODE_NAME     U6017 B28
 '@T6G_MB_LIB.T6G(SCH_1):PAGE462_I97@PURE_QUANTA.PT5161LRS(CHIPS)':
 'SMBDAT': CDS_PINID='SMBDAT';
NET_NAME
'SMB_RT_CPU1_P3_ROM_MUX_1D_R_SCL'
 '@T6G_MB_LIB.T6G(SCH_1):SMB_RT_CPU1_P3_ROM_MUX_1D_R_SCL':
 C_SIGNAL='@t6g_mb_lib.t6g(sch_1):smb_rt_cpu1_p3_rom_mux_1d_r_scl';
NODE_NAME     U6017 FF5
 '@T6G_MB_LIB.T6G(SCH_1):PAGE462_I97@PURE_QUANTA.PT5161LRS(CHIPS)':
 'EE_CLK': CDS_PINID='EE_CLK';
NODE_NAME     R695 2
 '@T6G_MB_LIB.T6G(SCH_1):PAGE462_I146@PURE_QUANTA.Q_RES(CHIPS)':
 'B': CDS_PINID='B';
NET_NAME
'SMB_RT_CPU1_P3_ROM_MUX_1D_R_SDA'
 '@T6G_MB_LIB.T6G(SCH_1):SMB_RT_CPU1_P3_ROM_MUX_1D_R_SDA':
 C_SIGNAL='@t6g_mb_lib.t6g(sch_1):smb_rt_cpu1_p3_rom_mux_1d_r_sda';
NODE_NAME     R696 2
 '@T6G_MB_LIB.T6G(SCH_1):PAGE462_I33@PURE_QUANTA.Q_RES(CHIPS)':
 'B': CDS_PINID='B';
NODE_NAME     U6017 FJ3
 '@T6G_MB_LIB.T6G(SCH_1):PAGE462_I97@PURE_QUANTA.PT5161LRS(CHIPS)':
 'EE_DAT': CDS_PINID='EE_DAT';
NET_NAME
'SMB_RT_CPU1_P3_ROM_MUX_1D_SCL'
 '@T6G_MB_LIB.T6G(SCH_1):SMB_RT_CPU1_P3_ROM_MUX_1D_SCL':
 C_SIGNAL='@t6g_mb_lib.t6g(sch_1):smb_rt_cpu1_p3_rom_mux_1d_scl';
NODE_NAME     U41 1
 '@T6G_MB_LIB.T6G(SCH_1):PAGE376_I46@PURE_QUANTA.PI3CSW12ZUAEX(CHIPS)':
 '1D+': CDS_PINID='\1d+\';
NODE_NAME     R1463 2
 '@T6G_MB_LIB.T6G(SCH_1):PAGE377_I177@PURE_QUANTA.Q_RES(CHIPS)':
 'B': CDS_PINID='B';
NODE_NAME     R695 1
 '@T6G_MB_LIB.T6G(SCH_1):PAGE462_I146@PURE_QUANTA.Q_RES(CHIPS)':
 'A': CDS_PINID='A';
NET_NAME
'SMB_RT_CPU1_P3_ROM_MUX_1D_SDA'
 '@T6G_MB_LIB.T6G(SCH_1):SMB_RT_CPU1_P3_ROM_MUX_1D_SDA':
 C_SIGNAL='@t6g_mb_lib.t6g(sch_1):smb_rt_cpu1_p3_rom_mux_1d_sda';
NODE_NAME     R696 1
 '@T6G_MB_LIB.T6G(SCH_1):PAGE462_I33@PURE_QUANTA.Q_RES(CHIPS)':
 'A': CDS_PINID='A';
NODE_NAME     U41 2
 '@T6G_MB_LIB.T6G(SCH_1):PAGE376_I46@PURE_QUANTA.PI3CSW12ZUAEX(CHIPS)':
 '1D-': CDS_PINID='\1d-\';
NODE_NAME     R1462 2
 '@T6G_MB_LIB.T6G(SCH_1):PAGE377_I176@PURE_QUANTA.Q_RES(CHIPS)':
 'B': CDS_PINID='B';
NET_NAME
'SMB_RT_CPU1_P3_ROM_MUX_2D_R_SCL'
 '@T6G_MB_LIB.T6G(SCH_1):SMB_RT_CPU1_P3_ROM_MUX_2D_R_SCL':
 C_SIGNAL='@t6g_mb_lib.t6g(sch_1):smb_rt_cpu1_p3_rom_mux_2d_r_scl';
NODE_NAME     R807 2
 '@T6G_MB_LIB.T6G(SCH_1):PAGE377_I43@PURE_QUANTA.Q_RES(CHIPS)':
 'B': CDS_PINID='B';
NODE_NAME     U22 9
 '@T6G_MB_LIB.T6G(SCH_1):PAGE377_I94@PURE_QUANTA.TCA9548APWR(CHIPS)':
 'SC2': CDS_PINID='SC2';
NODE_NAME     R1402 2
 '@T6G_MB_LIB.T6G(SCH_1):PAGE377_I109@PURE_QUANTA.Q_RES(CHIPS)':
 'B': CDS_PINID='B';
NET_NAME
'SMB_RT_CPU1_P3_ROM_MUX_2D_R_SDA'
 '@T6G_MB_LIB.T6G(SCH_1):SMB_RT_CPU1_P3_ROM_MUX_2D_R_SDA':
 C_SIGNAL='@t6g_mb_lib.t6g(sch_1):smb_rt_cpu1_p3_rom_mux_2d_r_sda';
NODE_NAME     R806 2
 '@T6G_MB_LIB.T6G(SCH_1):PAGE377_I47@PURE_QUANTA.Q_RES(CHIPS)':
 'B': CDS_PINID='B';
NODE_NAME     U22 8
 '@T6G_MB_LIB.T6G(SCH_1):PAGE377_I94@PURE_QUANTA.TCA9548APWR(CHIPS)':
 'SD2': CDS_PINID='SD2';
NODE_NAME     R1399 2
 '@T6G_MB_LIB.T6G(SCH_1):PAGE377_I108@PURE_QUANTA.Q_RES(CHIPS)':
 'B': CDS_PINID='B';
NET_NAME
'SMB_RT_CPU1_P3_ROM_MUX_2D_SCL'
 '@T6G_MB_LIB.T6G(SCH_1):SMB_RT_CPU1_P3_ROM_MUX_2D_SCL':
 C_SIGNAL='@t6g_mb_lib.t6g(sch_1):smb_rt_cpu1_p3_rom_mux_2d_scl';
NODE_NAME     R807 1
 '@T6G_MB_LIB.T6G(SCH_1):PAGE377_I43@PURE_QUANTA.Q_RES(CHIPS)':
 'A': CDS_PINID='A';
NODE_NAME     U41 3
 '@T6G_MB_LIB.T6G(SCH_1):PAGE376_I46@PURE_QUANTA.PI3CSW12ZUAEX(CHIPS)':
 '2D+': CDS_PINID='\2d+\';
NET_NAME
'SMB_RT_CPU1_P3_ROM_MUX_2D_SDA'
 '@T6G_MB_LIB.T6G(SCH_1):SMB_RT_CPU1_P3_ROM_MUX_2D_SDA':
 C_SIGNAL='@t6g_mb_lib.t6g(sch_1):smb_rt_cpu1_p3_rom_mux_2d_sda';
NODE_NAME     R806 1
 '@T6G_MB_LIB.T6G(SCH_1):PAGE377_I47@PURE_QUANTA.Q_RES(CHIPS)':
 'A': CDS_PINID='A';
NODE_NAME     U41 4
 '@T6G_MB_LIB.T6G(SCH_1):PAGE376_I46@PURE_QUANTA.PI3CSW12ZUAEX(CHIPS)':
 '2D-': CDS_PINID='\2d-\';
NET_NAME
'SMB_RT_CPU1_P3_ROM_R_SCL'
 '@T6G_MB_LIB.T6G(SCH_1):SMB_RT_CPU1_P3_ROM_R_SCL':
 C_SIGNAL='@t6g_mb_lib.t6g(sch_1):smb_rt_cpu1_p3_rom_r_scl';
NODE_NAME     R812 2
 '@T6G_MB_LIB.T6G(SCH_1):PAGE377_I60@PURE_QUANTA.Q_RES(CHIPS)':
 'B': CDS_PINID='B';
NODE_NAME     U41 8
 '@T6G_MB_LIB.T6G(SCH_1):PAGE376_I46@PURE_QUANTA.PI3CSW12ZUAEX(CHIPS)':
 'D+': CDS_PINID='\d+\';
NODE_NAME     R697 1
 '@T6G_MB_LIB.T6G(SCH_1):PAGE464_I25@PURE_QUANTA.Q_RES(CHIPS)':
 'A': CDS_PINID='A';
NET_NAME
'SMB_RT_CPU1_P3_ROM_R_SDA'
 '@T6G_MB_LIB.T6G(SCH_1):SMB_RT_CPU1_P3_ROM_R_SDA':
 C_SIGNAL='@t6g_mb_lib.t6g(sch_1):smb_rt_cpu1_p3_rom_r_sda';
NODE_NAME     R698 1
 '@T6G_MB_LIB.T6G(SCH_1):PAGE464_I4@PURE_QUANTA.Q_RES(CHIPS)':
 'A': CDS_PINID='A';
NODE_NAME     R810 2
 '@T6G_MB_LIB.T6G(SCH_1):PAGE377_I61@PURE_QUANTA.Q_RES(CHIPS)':
 'B': CDS_PINID='B';
NODE_NAME     U41 7
 '@T6G_MB_LIB.T6G(SCH_1):PAGE376_I46@PURE_QUANTA.PI3CSW12ZUAEX(CHIPS)':
 'D-': CDS_PINID='\d-\';
NET_NAME
'SMB_RT_CPU1_P3_ROM_SCL'
 '@T6G_MB_LIB.T6G(SCH_1):SMB_RT_CPU1_P3_ROM_SCL':
 C_SIGNAL='@t6g_mb_lib.t6g(sch_1):smb_rt_cpu1_p3_rom_scl';
NODE_NAME     U21 6
 '@T6G_MB_LIB.T6G(SCH_1):PAGE464_I5@PURE_QUANTA.M24M02DRMN6TP(CHIPS)':
 'SCL': CDS_PINID='SCL';
NODE_NAME     R697 2
 '@T6G_MB_LIB.T6G(SCH_1):PAGE464_I25@PURE_QUANTA.Q_RES(CHIPS)':
 'B': CDS_PINID='B';
NET_NAME
'SMB_RT_CPU1_P3_ROM_SDA'
 '@T6G_MB_LIB.T6G(SCH_1):SMB_RT_CPU1_P3_ROM_SDA':
 C_SIGNAL='@t6g_mb_lib.t6g(sch_1):smb_rt_cpu1_p3_rom_sda';
NODE_NAME     R698 2
 '@T6G_MB_LIB.T6G(SCH_1):PAGE464_I4@PURE_QUANTA.Q_RES(CHIPS)':
 'B': CDS_PINID='B';
NODE_NAME     U21 5
 '@T6G_MB_LIB.T6G(SCH_1):PAGE464_I5@PURE_QUANTA.M24M02DRMN6TP(CHIPS)':
 'SDA': CDS_PINID='SDA';
NET_NAME
'SMB_RT_CPU1_P3_R_SCL'
 '@T6G_MB_LIB.T6G(SCH_1):SMB_RT_CPU1_P3_R_SCL':
 C_SIGNAL='@t6g_mb_lib.t6g(sch_1):smb_rt_cpu1_p3_r_scl';
NODE_NAME     R6747 1
 '@T6G_MB_LIB.T6G(SCH_1):PAGE378_I21@PURE_QUANTA.Q_RES(CHIPS)':
 'A': CDS_PINID='A';
NODE_NAME     R6751 2
 '@T6G_MB_LIB.T6G(SCH_1):PAGE378_I32@PURE_QUANTA.Q_RES(CHIPS)':
 'B': CDS_PINID='B';
NODE_NAME     R913 1
 '@T6G_MB_LIB.T6G(SCH_1):PAGE462_I42@PURE_QUANTA.Q_RES(CHIPS)':
 'A': CDS_PINID='A';
NET_NAME
'SMB_RT_CPU1_P3_R_SDA'
 '@T6G_MB_LIB.T6G(SCH_1):SMB_RT_CPU1_P3_R_SDA':
 C_SIGNAL='@t6g_mb_lib.t6g(sch_1):smb_rt_cpu1_p3_r_sda';
NODE_NAME     R6746 1
 '@T6G_MB_LIB.T6G(SCH_1):PAGE378_I22@PURE_QUANTA.Q_RES(CHIPS)':
 'A': CDS_PINID='A';
NODE_NAME     R6750 2
 '@T6G_MB_LIB.T6G(SCH_1):PAGE378_I31@PURE_QUANTA.Q_RES(CHIPS)':
 'B': CDS_PINID='B';
NODE_NAME     R914 1
 '@T6G_MB_LIB.T6G(SCH_1):PAGE462_I41@PURE_QUANTA.Q_RES(CHIPS)':
 'A': CDS_PINID='A';
NET_NAME
'SMB_RT_CPU1_P3_SCL'
 '@T6G_MB_LIB.T6G(SCH_1):SMB_RT_CPU1_P3_SCL':
 C_SIGNAL='@t6g_mb_lib.t6g(sch_1):smb_rt_cpu1_p3_scl';
NODE_NAME     U6020 9
 '@T6G_MB_LIB.T6G(SCH_1):PAGE378_I1@PURE_QUANTA.TCA9548APWR(CHIPS)':
 'SC2': CDS_PINID='SC2';
NODE_NAME     R6747 2
 '@T6G_MB_LIB.T6G(SCH_1):PAGE378_I21@PURE_QUANTA.Q_RES(CHIPS)':
 'B': CDS_PINID='B';
NET_NAME
'SMB_RT_CPU1_P3_SDA'
 '@T6G_MB_LIB.T6G(SCH_1):SMB_RT_CPU1_P3_SDA':
 C_SIGNAL='@t6g_mb_lib.t6g(sch_1):smb_rt_cpu1_p3_sda';
NODE_NAME     U6020 8
 '@T6G_MB_LIB.T6G(SCH_1):PAGE378_I1@PURE_QUANTA.TCA9548APWR(CHIPS)':
 'SD2': CDS_PINID='SD2';
NODE_NAME     R6746 2
 '@T6G_MB_LIB.T6G(SCH_1):PAGE378_I22@PURE_QUANTA.Q_RES(CHIPS)':
 'B': CDS_PINID='B';
NET_NAME
'SMB_SCM_2_R1_SCL'
 '@T6G_MB_LIB.T6G(SCH_1):SMB_SCM_2_R1_SCL':
 C_SIGNAL='@t6g_mb_lib.t6g(sch_1):smb_scm_2_r1_scl';
NODE_NAME     R8248 1
 '@T6G_MB_LIB.T6G(SCH_1):PAGE192_I84@PURE_QUANTA.Q_RES(CHIPS)':
 'A': CDS_PINID='A';
NODE_NAME     R1321 2
 '@T6G_MB_LIB.T6G(SCH_1):PAGE349_I10@PURE_QUANTA.Q_RES(CHIPS)':
 'B': CDS_PINID='B';
NODE_NAME     R1495 1
 '@T6G_MB_LIB.T6G(SCH_1):PAGE349_I49@PURE_QUANTA.Q_RES(CHIPS)':
 'A': CDS_PINID='A';
NET_NAME
'SMB_SCM_2_R1_SDA'
 '@T6G_MB_LIB.T6G(SCH_1):SMB_SCM_2_R1_SDA':
 C_SIGNAL='@t6g_mb_lib.t6g(sch_1):smb_scm_2_r1_sda';
NODE_NAME     R8249 1
 '@T6G_MB_LIB.T6G(SCH_1):PAGE192_I81@PURE_QUANTA.Q_RES(CHIPS)':
 'A': CDS_PINID='A';
NODE_NAME     R1494 2
 '@T6G_MB_LIB.T6G(SCH_1):PAGE349_I9@PURE_QUANTA.Q_RES(CHIPS)':
 'B': CDS_PINID='B';
NODE_NAME     R1496 1
 '@T6G_MB_LIB.T6G(SCH_1):PAGE349_I48@PURE_QUANTA.Q_RES(CHIPS)':
 'A': CDS_PINID='A';
NET_NAME
'SMB_SCM_2_R2_SCL'
 '@T6G_MB_LIB.T6G(SCH_1):SMB_SCM_2_R2_SCL':
 C_SIGNAL='@t6g_mb_lib.t6g(sch_1):smb_scm_2_r2_scl';
NODE_NAME     R8381 1
 '@T6G_MB_LIB.T6G(SCH_1):PAGE199_I40@PURE_QUANTA.Q_RES(CHIPS)':
 'A': CDS_PINID='A';
NODE_NAME     R1495 2
 '@T6G_MB_LIB.T6G(SCH_1):PAGE349_I49@PURE_QUANTA.Q_RES(CHIPS)':
 'B': CDS_PINID='B';
NODE_NAME     R349 1
 '@T6G_MB_LIB.T6G(SCH_1):PAGE349_I185@PURE_QUANTA.Q_RES(CHIPS)':
 'A': CDS_PINID='A';
NET_NAME
'SMB_SCM_2_R2_SDA'
 '@T6G_MB_LIB.T6G(SCH_1):SMB_SCM_2_R2_SDA':
 C_SIGNAL='@t6g_mb_lib.t6g(sch_1):smb_scm_2_r2_sda';
NODE_NAME     R8382 1
 '@T6G_MB_LIB.T6G(SCH_1):PAGE199_I39@PURE_QUANTA.Q_RES(CHIPS)':
 'A': CDS_PINID='A';
NODE_NAME     R1496 2
 '@T6G_MB_LIB.T6G(SCH_1):PAGE349_I48@PURE_QUANTA.Q_RES(CHIPS)':
 'B': CDS_PINID='B';
NODE_NAME     R350 1
 '@T6G_MB_LIB.T6G(SCH_1):PAGE349_I184@PURE_QUANTA.Q_RES(CHIPS)':
 'A': CDS_PINID='A';
NET_NAME
'SMB_SCM_2_R3_SCL'
 '@T6G_MB_LIB.T6G(SCH_1):SMB_SCM_2_R3_SCL':
 C_SIGNAL='@t6g_mb_lib.t6g(sch_1):smb_scm_2_r3_scl';
NODE_NAME     R8308 1
 '@T6G_MB_LIB.T6G(SCH_1):PAGE168_I85@PURE_QUANTA.Q_RES(CHIPS)':
 'A': CDS_PINID='A';
NODE_NAME     R1497 2
 '@T6G_MB_LIB.T6G(SCH_1):PAGE349_I176@PURE_QUANTA.Q_RES(CHIPS)':
 'B': CDS_PINID='B';
NODE_NAME     R6076 1
 '@T6G_MB_LIB.T6G(SCH_1):PAGE349_I181@PURE_QUANTA.Q_RES(CHIPS)':
 'A': CDS_PINID='A';
NODE_NAME     PJ1 3
 '@T6G_MB_LIB.T6G(SCH_1):PAGE168_I143@PURE_QUANTA.CONN3_210HP1030BR1(CHIPS)':
 '3': CDS_PINID='\3\';
NET_NAME
'SMB_SCM_2_R3_SDA'
 '@T6G_MB_LIB.T6G(SCH_1):SMB_SCM_2_R3_SDA':
 C_SIGNAL='@t6g_mb_lib.t6g(sch_1):smb_scm_2_r3_sda';
NODE_NAME     R8309 1
 '@T6G_MB_LIB.T6G(SCH_1):PAGE168_I84@PURE_QUANTA.Q_RES(CHIPS)':
 'A': CDS_PINID='A';
NODE_NAME     R6077 1
 '@T6G_MB_LIB.T6G(SCH_1):PAGE349_I182@PURE_QUANTA.Q_RES(CHIPS)':
 'A': CDS_PINID='A';
NODE_NAME     R1498 2
 '@T6G_MB_LIB.T6G(SCH_1):PAGE349_I183@PURE_QUANTA.Q_RES(CHIPS)':
 'B': CDS_PINID='B';
NODE_NAME     PJ1 2
 '@T6G_MB_LIB.T6G(SCH_1):PAGE168_I143@PURE_QUANTA.CONN3_210HP1030BR1(CHIPS)':
 '2': CDS_PINID='\2\';
NET_NAME
'SMB_SCM_2_R4_SCL'
 '@T6G_MB_LIB.T6G(SCH_1):SMB_SCM_2_R4_SCL':
 C_SIGNAL='@t6g_mb_lib.t6g(sch_1):smb_scm_2_r4_scl';
NODE_NAME     R1793 1
 '@T6G_MB_LIB.T6G(SCH_1):PAGE369_I147@PURE_QUANTA.Q_RES(CHIPS)':
 'A': CDS_PINID='A';
NODE_NAME     R3672 1
 '@T6G_MB_LIB.T6G(SCH_1):PAGE369_I150@PURE_QUANTA.Q_RES(CHIPS)':
 'A': CDS_PINID='A';
NODE_NAME     R6076 2
 '@T6G_MB_LIB.T6G(SCH_1):PAGE349_I181@PURE_QUANTA.Q_RES(CHIPS)':
 'B': CDS_PINID='B';
NET_NAME
'SMB_SCM_2_R4_SDA'
 '@T6G_MB_LIB.T6G(SCH_1):SMB_SCM_2_R4_SDA':
 C_SIGNAL='@t6g_mb_lib.t6g(sch_1):smb_scm_2_r4_sda';
NODE_NAME     R1792 1
 '@T6G_MB_LIB.T6G(SCH_1):PAGE369_I146@PURE_QUANTA.Q_RES(CHIPS)':
 'A': CDS_PINID='A';
NODE_NAME     R3671 1
 '@T6G_MB_LIB.T6G(SCH_1):PAGE369_I149@PURE_QUANTA.Q_RES(CHIPS)':
 'A': CDS_PINID='A';
NODE_NAME     R6077 2
 '@T6G_MB_LIB.T6G(SCH_1):PAGE349_I182@PURE_QUANTA.Q_RES(CHIPS)':
 'B': CDS_PINID='B';
NET_NAME
'SMB_SCM_2_R5_SCL'
 '@T6G_MB_LIB.T6G(SCH_1):SMB_SCM_2_R5_SCL':
 C_SIGNAL='@t6g_mb_lib.t6g(sch_1):smb_scm_2_r5_scl';
NODE_NAME     R8071 1
 '@T6G_MB_LIB.T6G(SCH_1):PAGE175_I85@PURE_QUANTA.Q_RES(CHIPS)':
 'A': CDS_PINID='A';
NODE_NAME     R349 2
 '@T6G_MB_LIB.T6G(SCH_1):PAGE349_I185@PURE_QUANTA.Q_RES(CHIPS)':
 'B': CDS_PINID='B';
NODE_NAME     R351 1
 '@T6G_MB_LIB.T6G(SCH_1):PAGE349_I187@PURE_QUANTA.Q_RES(CHIPS)':
 'A': CDS_PINID='A';
NET_NAME
'SMB_SCM_2_R5_SDA'
 '@T6G_MB_LIB.T6G(SCH_1):SMB_SCM_2_R5_SDA':
 C_SIGNAL='@t6g_mb_lib.t6g(sch_1):smb_scm_2_r5_sda';
NODE_NAME     R8072 1
 '@T6G_MB_LIB.T6G(SCH_1):PAGE175_I82@PURE_QUANTA.Q_RES(CHIPS)':
 'A': CDS_PINID='A';
NODE_NAME     R350 2
 '@T6G_MB_LIB.T6G(SCH_1):PAGE349_I184@PURE_QUANTA.Q_RES(CHIPS)':
 'B': CDS_PINID='B';
NODE_NAME     R352 1
 '@T6G_MB_LIB.T6G(SCH_1):PAGE349_I186@PURE_QUANTA.Q_RES(CHIPS)':
 'A': CDS_PINID='A';
NET_NAME
'SMB_SCM_2_R6_SCL'
 '@T6G_MB_LIB.T6G(SCH_1):SMB_SCM_2_R6_SCL':
 C_SIGNAL='@t6g_mb_lib.t6g(sch_1):smb_scm_2_r6_scl';
NODE_NAME     R118 1
 '@T6G_MB_LIB.T6G(SCH_1):PAGE182_I41@PURE_QUANTA.Q_RES(CHIPS)':
 'A': CDS_PINID='A';
NODE_NAME     R351 2
 '@T6G_MB_LIB.T6G(SCH_1):PAGE349_I187@PURE_QUANTA.Q_RES(CHIPS)':
 'B': CDS_PINID='B';
NODE_NAME     R6856 1
 '@T6G_MB_LIB.T6G(SCH_1):PAGE349_I226@PURE_QUANTA.Q_RES(CHIPS)':
 'A': CDS_PINID='A';
NET_NAME
'SMB_SCM_2_R6_SDA'
 '@T6G_MB_LIB.T6G(SCH_1):SMB_SCM_2_R6_SDA':
 C_SIGNAL='@t6g_mb_lib.t6g(sch_1):smb_scm_2_r6_sda';
NODE_NAME     R119 1
 '@T6G_MB_LIB.T6G(SCH_1):PAGE182_I40@PURE_QUANTA.Q_RES(CHIPS)':
 'A': CDS_PINID='A';
NODE_NAME     R352 2
 '@T6G_MB_LIB.T6G(SCH_1):PAGE349_I186@PURE_QUANTA.Q_RES(CHIPS)':
 'B': CDS_PINID='B';
NODE_NAME     R6857 1
 '@T6G_MB_LIB.T6G(SCH_1):PAGE349_I227@PURE_QUANTA.Q_RES(CHIPS)':
 'A': CDS_PINID='A';
NET_NAME
'SMB_SENSOR_E1S_3V3AUX_SCL'
 '@T6G_MB_LIB.T6G(SCH_1):SMB_SENSOR_E1S_3V3AUX_SCL':
 C_SIGNAL='@t6g_mb_lib.t6g(sch_1):smb_sensor_e1s_3v3aux_scl';
NODE_NAME     U279 7
 '@T6G_MB_LIB.T6G(SCH_1):PAGE346_I93@PURE_QUANTA.PCA9617ADP(CHIPS)':
 'SCLB': CDS_PINID='SCLB';
NODE_NAME     R3526 2
 '@T6G_MB_LIB.T6G(SCH_1):PAGE252_I23@PURE_QUANTA.Q_RES(CHIPS)':
 'B': CDS_PINID='B';
NODE_NAME     R3535 2
 '@T6G_MB_LIB.T6G(SCH_1):PAGE252_I44@PURE_QUANTA.Q_RES(CHIPS)':
 'B': CDS_PINID='B';
NET_NAME
'SMB_SENSOR_E1S_3V3AUX_SDA'
 '@T6G_MB_LIB.T6G(SCH_1):SMB_SENSOR_E1S_3V3AUX_SDA':
 C_SIGNAL='@t6g_mb_lib.t6g(sch_1):smb_sensor_e1s_3v3aux_sda';
NODE_NAME     U279 6
 '@T6G_MB_LIB.T6G(SCH_1):PAGE346_I93@PURE_QUANTA.PCA9617ADP(CHIPS)':
 'SDAB': CDS_PINID='SDAB';
NODE_NAME     R3527 2
 '@T6G_MB_LIB.T6G(SCH_1):PAGE252_I24@PURE_QUANTA.Q_RES(CHIPS)':
 'B': CDS_PINID='B';
NODE_NAME     R3536 2
 '@T6G_MB_LIB.T6G(SCH_1):PAGE252_I43@PURE_QUANTA.Q_RES(CHIPS)':
 'B': CDS_PINID='B';
NET_NAME
'SMB_SENSOR_M2_P1_3V3AUX_SCL'
 '@T6G_MB_LIB.T6G(SCH_1):SMB_SENSOR_M2_P1_3V3AUX_SCL':
 C_SIGNAL='@t6g_mb_lib.t6g(sch_1):smb_sensor_m2_p1_3v3aux_scl';
NODE_NAME     U98 6
 '@T6G_MB_LIB.T6G(SCH_1):PAGE346_I27@PURE_QUANTA.PCA9306DP1(CHIPS)':
 'SCL2': CDS_PINID='SCL2';
NODE_NAME     R2967 2
 '@T6G_MB_LIB.T6G(SCH_1):PAGE252_I25@PURE_QUANTA.Q_RES(CHIPS)':
 'B': CDS_PINID='B';
NODE_NAME     R1089 2
 '@T6G_MB_LIB.T6G(SCH_1):PAGE252_I37@PURE_QUANTA.Q_RES(CHIPS)':
 'B': CDS_PINID='B';
NET_NAME
'SMB_SENSOR_M2_P1_3V3AUX_SDA'
 '@T6G_MB_LIB.T6G(SCH_1):SMB_SENSOR_M2_P1_3V3AUX_SDA':
 C_SIGNAL='@t6g_mb_lib.t6g(sch_1):smb_sensor_m2_p1_3v3aux_sda';
NODE_NAME     U98 5
 '@T6G_MB_LIB.T6G(SCH_1):PAGE346_I27@PURE_QUANTA.PCA9306DP1(CHIPS)':
 'SDA2': CDS_PINID='SDA2';
NODE_NAME     R2968 2
 '@T6G_MB_LIB.T6G(SCH_1):PAGE252_I26@PURE_QUANTA.Q_RES(CHIPS)':
 'B': CDS_PINID='B';
NODE_NAME     R1090 2
 '@T6G_MB_LIB.T6G(SCH_1):PAGE252_I38@PURE_QUANTA.Q_RES(CHIPS)':
 'B': CDS_PINID='B';
NET_NAME
'SMB_SEN_MAM_2_3V3AUX_SCL'
 '@T6G_MB_LIB.T6G(SCH_1):SMB_SEN_MAM_2_3V3AUX_SCL':
 C_SIGNAL='@t6g_mb_lib.t6g(sch_1):smb_sen_mam_2_3v3aux_scl';
NODE_NAME     R1228 2
 '@T6G_MB_LIB.T6G(SCH_1):PAGE263_I139@PURE_QUANTA.Q_RES(CHIPS)':
 'B': CDS_PINID='B';
NODE_NAME     U50 13
 '@T6G_MB_LIB.T6G(SCH_1):PAGE263_I156@PURE_QUANTA.MAX11617EEET(CHIPS)':
 'SCL': CDS_PINID='SCL';
NET_NAME
'SMB_SEN_MAM_2_3V3AUX_SDA'
 '@T6G_MB_LIB.T6G(SCH_1):SMB_SEN_MAM_2_3V3AUX_SDA':
 C_SIGNAL='@t6g_mb_lib.t6g(sch_1):smb_sen_mam_2_3v3aux_sda';
NODE_NAME     R1227 2
 '@T6G_MB_LIB.T6G(SCH_1):PAGE263_I138@PURE_QUANTA.Q_RES(CHIPS)':
 'B': CDS_PINID='B';
NODE_NAME     U50 14
 '@T6G_MB_LIB.T6G(SCH_1):PAGE263_I156@PURE_QUANTA.MAX11617EEET(CHIPS)':
 'SDA': CDS_PINID='SDA';
NET_NAME
'SMB_SEN_MAM_3V3AUX_SCL'
 '@T6G_MB_LIB.T6G(SCH_1):SMB_SEN_MAM_3V3AUX_SCL':
 C_SIGNAL='@t6g_mb_lib.t6g(sch_1):smb_sen_mam_3v3aux_scl';
NODE_NAME     R1793 2
 '@T6G_MB_LIB.T6G(SCH_1):PAGE369_I147@PURE_QUANTA.Q_RES(CHIPS)':
 'B': CDS_PINID='B';
NODE_NAME     U193 13
 '@T6G_MB_LIB.T6G(SCH_1):PAGE369_I169@PURE_QUANTA.MAX11617EEET(CHIPS)':
 'SCL': CDS_PINID='SCL';
NET_NAME
'SMB_SEN_MAM_3V3AUX_SDA'
 '@T6G_MB_LIB.T6G(SCH_1):SMB_SEN_MAM_3V3AUX_SDA':
 C_SIGNAL='@t6g_mb_lib.t6g(sch_1):smb_sen_mam_3v3aux_sda';
NODE_NAME     R1792 2
 '@T6G_MB_LIB.T6G(SCH_1):PAGE369_I146@PURE_QUANTA.Q_RES(CHIPS)':
 'B': CDS_PINID='B';
NODE_NAME     U193 14
 '@T6G_MB_LIB.T6G(SCH_1):PAGE369_I169@PURE_QUANTA.MAX11617EEET(CHIPS)':
 'SDA': CDS_PINID='SDA';
NET_NAME
'SMB_SEN_TIC_2_3V3AUX_SCL'
 '@T6G_MB_LIB.T6G(SCH_1):SMB_SEN_TIC_2_3V3AUX_SCL':
 C_SIGNAL='@t6g_mb_lib.t6g(sch_1):smb_sen_tic_2_3v3aux_scl';
NODE_NAME     R1244 2
 '@T6G_MB_LIB.T6G(SCH_1):PAGE263_I140@PURE_QUANTA.Q_RES(CHIPS)':
 'B': CDS_PINID='B';
NODE_NAME     U51 3
 '@T6G_MB_LIB.T6G(SCH_1):PAGE263_I142@PURE_QUANTA.ADC128D818CIMTXNOPB(CHIPS)':
 'SCL': CDS_PINID='SCL';
NET_NAME
'SMB_SEN_TIC_2_3V3AUX_SDA'
 '@T6G_MB_LIB.T6G(SCH_1):SMB_SEN_TIC_2_3V3AUX_SDA':
 C_SIGNAL='@t6g_mb_lib.t6g(sch_1):smb_sen_tic_2_3v3aux_sda';
NODE_NAME     R1243 2
 '@T6G_MB_LIB.T6G(SCH_1):PAGE263_I141@PURE_QUANTA.Q_RES(CHIPS)':
 'B': CDS_PINID='B';
NODE_NAME     U51 2
 '@T6G_MB_LIB.T6G(SCH_1):PAGE263_I142@PURE_QUANTA.ADC128D818CIMTXNOPB(CHIPS)':
 'SDA': CDS_PINID='SDA';
NET_NAME
'SMB_SEN_TIC_3V3AUX_SCL'
 '@T6G_MB_LIB.T6G(SCH_1):SMB_SEN_TIC_3V3AUX_SCL':
 C_SIGNAL='@t6g_mb_lib.t6g(sch_1):smb_sen_tic_3v3aux_scl';
NODE_NAME     U269 3
 '@T6G_MB_LIB.T6G(SCH_1):PAGE369_I142@PURE_QUANTA.ADC128D818CIMTXNOPB(CHIPS)':
 'SCL': CDS_PINID='SCL';
NODE_NAME     R3672 2
 '@T6G_MB_LIB.T6G(SCH_1):PAGE369_I150@PURE_QUANTA.Q_RES(CHIPS)':
 'B': CDS_PINID='B';
NET_NAME
'SMB_SEN_TIC_3V3AUX_SDA'
 '@T6G_MB_LIB.T6G(SCH_1):SMB_SEN_TIC_3V3AUX_SDA':
 C_SIGNAL='@t6g_mb_lib.t6g(sch_1):smb_sen_tic_3v3aux_sda';
NODE_NAME     U269 2
 '@T6G_MB_LIB.T6G(SCH_1):PAGE369_I142@PURE_QUANTA.ADC128D818CIMTXNOPB(CHIPS)':
 'SDA': CDS_PINID='SDA';
NODE_NAME     R3671 2
 '@T6G_MB_LIB.T6G(SCH_1):PAGE369_I149@PURE_QUANTA.Q_RES(CHIPS)':
 'B': CDS_PINID='B';
NET_NAME
'SMB_SML1_PMBUS_HSC_L_SCL'
 '@T6G_MB_LIB.T6G(SCH_1):SMB_SML1_PMBUS_HSC_L_SCL':
 C_SIGNAL='@t6g_mb_lib.t6g(sch_1):smb_sml1_pmbus_hsc_l_scl';
NODE_NAME     R3909 2
 '@T6G_MB_LIB.T6G(SCH_1):PAGE267_I37@PURE_QUANTA.Q_RES(CHIPS)':
 'B': CDS_PINID='B';
NODE_NAME     PU289 11
 '@T6G_MB_LIB.T6G(SCH_1):PAGE267_I58@PURE_QUANTA.MP5990GMA1111Z(CHIPS)':
 'SCL': CDS_PINID='SCL';
NET_NAME
'SMB_SML1_PMBUS_HSC_R1_SCL'
 '@T6G_MB_LIB.T6G(SCH_1):SMB_SML1_PMBUS_HSC_R1_SCL':
 C_SIGNAL='@t6g_mb_lib.t6g(sch_1):smb_sml1_pmbus_hsc_r1_scl';
NODE_NAME     PJ38 18
 '@T6G_MB_LIB.T6G(SCH_1):PAGE371_I42@PURE_QUANTA.SCONN21_9193031121LF(CHIPS)':
 '18': CDS_PINID='\18\';
NODE_NAME     R347 2
 '@T6G_MB_LIB.T6G(SCH_1):PAGE349_I173@PURE_QUANTA.Q_RES(CHIPS)':
 'B': CDS_PINID='B';
NODE_NAME     JP10 1
 '@T6G_MB_LIB.T6G(SCH_1):PAGE372_I103@PURE_QUANTA.CONN3_210HP1030BR1(CHIPS)':
 '1': CDS_PINID='\1\';
NET_NAME
'SMB_SML1_PMBUS_HSC_R1_SDA'
 '@T6G_MB_LIB.T6G(SCH_1):SMB_SML1_PMBUS_HSC_R1_SDA':
 C_SIGNAL='@t6g_mb_lib.t6g(sch_1):smb_sml1_pmbus_hsc_r1_sda';
NODE_NAME     PJ38 19
 '@T6G_MB_LIB.T6G(SCH_1):PAGE371_I42@PURE_QUANTA.SCONN21_9193031121LF(CHIPS)':
 '19': CDS_PINID='\19\';
NODE_NAME     R348 2
 '@T6G_MB_LIB.T6G(SCH_1):PAGE349_I172@PURE_QUANTA.Q_RES(CHIPS)':
 'B': CDS_PINID='B';
NODE_NAME     JP10 2
 '@T6G_MB_LIB.T6G(SCH_1):PAGE372_I103@PURE_QUANTA.CONN3_210HP1030BR1(CHIPS)':
 '2': CDS_PINID='\2\';
NET_NAME
'SMB_SML1_PMBUS_HSC_R_SDA'
 '@T6G_MB_LIB.T6G(SCH_1):SMB_SML1_PMBUS_HSC_R_SDA':
 C_SIGNAL='@t6g_mb_lib.t6g(sch_1):smb_sml1_pmbus_hsc_r_sda';
NODE_NAME     R1714 2
 '@T6G_MB_LIB.T6G(SCH_1):PAGE267_I36@PURE_QUANTA.Q_RES(CHIPS)':
 'B': CDS_PINID='B';
NODE_NAME     PU289 12
 '@T6G_MB_LIB.T6G(SCH_1):PAGE267_I58@PURE_QUANTA.MP5990GMA1111Z(CHIPS)':
 'SDA': CDS_PINID='SDA';
NET_NAME
'SMB_SML1_PMBUS_HSC_SCL'
 '@T6G_MB_LIB.T6G(SCH_1):SMB_SML1_PMBUS_HSC_SCL':
 C_SIGNAL='@t6g_mb_lib.t6g(sch_1):smb_sml1_pmbus_hsc_scl';
NODE_NAME     R2995 2
 '@T6G_MB_LIB.T6G(SCH_1):PAGE349_I91@PURE_QUANTA.Q_RES(CHIPS)':
 'B': CDS_PINID='B';
NODE_NAME     R3909 1
 '@T6G_MB_LIB.T6G(SCH_1):PAGE267_I37@PURE_QUANTA.Q_RES(CHIPS)':
 'A': CDS_PINID='A';
NODE_NAME     R347 1
 '@T6G_MB_LIB.T6G(SCH_1):PAGE349_I173@PURE_QUANTA.Q_RES(CHIPS)':
 'A': CDS_PINID='A';
NODE_NAME     R6784 2
 '@T6G_MB_LIB.T6G(SCH_1):PAGE349_I198@PURE_QUANTA.Q_RES(CHIPS)':
 'B': CDS_PINID='B';
NET_NAME
'SMB_SML1_PMBUS_HSC_SDA'
 '@T6G_MB_LIB.T6G(SCH_1):SMB_SML1_PMBUS_HSC_SDA':
 C_SIGNAL='@t6g_mb_lib.t6g(sch_1):smb_sml1_pmbus_hsc_sda';
NODE_NAME     R2996 2
 '@T6G_MB_LIB.T6G(SCH_1):PAGE349_I92@PURE_QUANTA.Q_RES(CHIPS)':
 'B': CDS_PINID='B';
NODE_NAME     R1714 1
 '@T6G_MB_LIB.T6G(SCH_1):PAGE267_I36@PURE_QUANTA.Q_RES(CHIPS)':
 'A': CDS_PINID='A';
NODE_NAME     R348 1
 '@T6G_MB_LIB.T6G(SCH_1):PAGE349_I172@PURE_QUANTA.Q_RES(CHIPS)':
 'A': CDS_PINID='A';
NODE_NAME     R6785 2
 '@T6G_MB_LIB.T6G(SCH_1):PAGE349_I199@PURE_QUANTA.Q_RES(CHIPS)':
 'B': CDS_PINID='B';
NET_NAME
'SMB_USB_CPU0_HUB1_SCL'
 '@T6G_MB_LIB.T6G(SCH_1):SMB_USB_CPU0_HUB1_SCL':
 C_SIGNAL='@t6g_mb_lib.t6g(sch_1):smb_usb_cpu0_hub1_scl';
NODE_NAME     U6001 32
 '@T6G_MB_LIB.T6G(SCH_1):PAGE153_I1@PURE_QUANTA.CYUSB330468LTXI(CHIPS)':
 'I2C_CLK': CDS_PINID='I2C_CLK';
NODE_NAME     R6201 2
 '@T6G_MB_LIB.T6G(SCH_1):PAGE252_I84@PURE_QUANTA.Q_RES(CHIPS)':
 'B': CDS_PINID='B';
NODE_NAME     R6224 1
 '@T6G_MB_LIB.T6G(SCH_1):PAGE153_I84@PURE_QUANTA.Q_RES(CHIPS)':
 'A': CDS_PINID='A';
NODE_NAME     R6211 2
 '@T6G_MB_LIB.T6G(SCH_1):PAGE252_I89@PURE_QUANTA.Q_RES(CHIPS)':
 'B': CDS_PINID='B';
NODE_NAME     R6314 1
 '@T6G_MB_LIB.T6G(SCH_1):PAGE155_I137@PURE_QUANTA.Q_RES(CHIPS)':
 'A': CDS_PINID='A';
NODE_NAME     R6280 1
 '@T6G_MB_LIB.T6G(SCH_1):PAGE157_I146@PURE_QUANTA.Q_RES(CHIPS)':
 'A': CDS_PINID='A';
NET_NAME
'SMB_USB_CPU0_HUB1_SCL_R'
 '@T6G_MB_LIB.T6G(SCH_1):SMB_USB_CPU0_HUB1_SCL_R':
 C_SIGNAL='@t6g_mb_lib.t6g(sch_1):smb_usb_cpu0_hub1_scl_r';
NODE_NAME     U36 5
 '@T6G_MB_LIB.T6G(SCH_1):PAGE252_I33@PURE_QUANTA.TCA9548APWR(CHIPS)':
 'SC0': CDS_PINID='SC0';
NODE_NAME     R6201 1
 '@T6G_MB_LIB.T6G(SCH_1):PAGE252_I84@PURE_QUANTA.Q_RES(CHIPS)':
 'A': CDS_PINID='A';
NET_NAME
'SMB_USB_CPU0_HUB1_SCL_R2'
 '@T6G_MB_LIB.T6G(SCH_1):SMB_USB_CPU0_HUB1_SCL_R2':
 C_SIGNAL='@t6g_mb_lib.t6g(sch_1):smb_usb_cpu0_hub1_scl_r2';
NODE_NAME     U6003 6
 '@T6G_MB_LIB.T6G(SCH_1):PAGE153_I64@PURE_QUANTA.M24128BWMN6TP(CHIPS)':
 'SCL': CDS_PINID='SCL';
NODE_NAME     R6224 2
 '@T6G_MB_LIB.T6G(SCH_1):PAGE153_I84@PURE_QUANTA.Q_RES(CHIPS)':
 'B': CDS_PINID='B';
NODE_NAME     R6226 2
 '@T6G_MB_LIB.T6G(SCH_1):PAGE153_I85@PURE_QUANTA.Q_RES(CHIPS)':
 'B': CDS_PINID='B';
NET_NAME
'SMB_USB_CPU0_HUB1_SDA'
 '@T6G_MB_LIB.T6G(SCH_1):SMB_USB_CPU0_HUB1_SDA':
 C_SIGNAL='@t6g_mb_lib.t6g(sch_1):smb_usb_cpu0_hub1_sda';
NODE_NAME     U6001 33
 '@T6G_MB_LIB.T6G(SCH_1):PAGE153_I1@PURE_QUANTA.CYUSB330468LTXI(CHIPS)':
 'I2C_DATA': CDS_PINID='I2C_DATA';
NODE_NAME     R6200 2
 '@T6G_MB_LIB.T6G(SCH_1):PAGE252_I83@PURE_QUANTA.Q_RES(CHIPS)':
 'B': CDS_PINID='B';
NODE_NAME     R6225 1
 '@T6G_MB_LIB.T6G(SCH_1):PAGE153_I83@PURE_QUANTA.Q_RES(CHIPS)':
 'A': CDS_PINID='A';
NODE_NAME     R6212 2
 '@T6G_MB_LIB.T6G(SCH_1):PAGE252_I90@PURE_QUANTA.Q_RES(CHIPS)':
 'B': CDS_PINID='B';
NODE_NAME     R6279 1
 '@T6G_MB_LIB.T6G(SCH_1):PAGE157_I148@PURE_QUANTA.Q_RES(CHIPS)':
 'A': CDS_PINID='A';
NODE_NAME     R6311 1
 '@T6G_MB_LIB.T6G(SCH_1):PAGE155_I200@PURE_QUANTA.Q_RES(CHIPS)':
 'A': CDS_PINID='A';
NET_NAME
'SMB_USB_CPU0_HUB1_SDA_R'
 '@T6G_MB_LIB.T6G(SCH_1):SMB_USB_CPU0_HUB1_SDA_R':
 C_SIGNAL='@t6g_mb_lib.t6g(sch_1):smb_usb_cpu0_hub1_sda_r';
NODE_NAME     U36 4
 '@T6G_MB_LIB.T6G(SCH_1):PAGE252_I33@PURE_QUANTA.TCA9548APWR(CHIPS)':
 'SD0': CDS_PINID='SD0';
NODE_NAME     R6200 1
 '@T6G_MB_LIB.T6G(SCH_1):PAGE252_I83@PURE_QUANTA.Q_RES(CHIPS)':
 'A': CDS_PINID='A';
NET_NAME
'SMB_USB_CPU0_HUB1_SDA_R2'
 '@T6G_MB_LIB.T6G(SCH_1):SMB_USB_CPU0_HUB1_SDA_R2':
 C_SIGNAL='@t6g_mb_lib.t6g(sch_1):smb_usb_cpu0_hub1_sda_r2';
NODE_NAME     U6003 5
 '@T6G_MB_LIB.T6G(SCH_1):PAGE153_I64@PURE_QUANTA.M24128BWMN6TP(CHIPS)':
 'SDA': CDS_PINID='SDA';
NODE_NAME     R6225 2
 '@T6G_MB_LIB.T6G(SCH_1):PAGE153_I83@PURE_QUANTA.Q_RES(CHIPS)':
 'B': CDS_PINID='B';
NODE_NAME     R6227 2
 '@T6G_MB_LIB.T6G(SCH_1):PAGE153_I86@PURE_QUANTA.Q_RES(CHIPS)':
 'B': CDS_PINID='B';
NET_NAME
'SMB_USB_HUB2_TI_SCL_MRP_PRT_CTL1'
 '@T6G_MB_LIB.T6G(SCH_1):SMB_USB_HUB2_TI_SCL_MRP_PRT_CTL1':
 C_SIGNAL='@t6g_mb_lib.t6g(sch_1):smb_usb_hub2_ti_scl_mrp_prt_ctl1';
NODE_NAME     U6002 38
 '@T6G_MB_LIB.T6G(SCH_1):PAGE157_I119@PURE_QUANTA.TUSB8042AIRGCR(CHIPS)':
 'SCL||SMBCLK': CDS_PINID='\scl||smbclk\';
NODE_NAME     R6280 2
 '@T6G_MB_LIB.T6G(SCH_1):PAGE157_I146@PURE_QUANTA.Q_RES(CHIPS)':
 'B': CDS_PINID='B';
NET_NAME
'SMB_USB_HUB2_TI_SDA_MRP_PRT_CTL2'
 '@T6G_MB_LIB.T6G(SCH_1):SMB_USB_HUB2_TI_SDA_MRP_PRT_CTL2':
 C_SIGNAL='@t6g_mb_lib.t6g(sch_1):smb_usb_hub2_ti_sda_mrp_prt_ctl2';
NODE_NAME     U6002 37
 '@T6G_MB_LIB.T6G(SCH_1):PAGE157_I119@PURE_QUANTA.TUSB8042AIRGCR(CHIPS)':
 'SDA||SMBDAT': CDS_PINID='\sda||smbdat\';
NODE_NAME     R6279 2
 '@T6G_MB_LIB.T6G(SCH_1):PAGE157_I148@PURE_QUANTA.Q_RES(CHIPS)':
 'B': CDS_PINID='B';
NET_NAME
'SMB_VR_3V3AUX_SCL'
 '@T6G_MB_LIB.T6G(SCH_1):SMB_VR_3V3AUX_SCL':
 C_SIGNAL='@t6g_mb_lib.t6g(sch_1):smb_vr_3v3aux_scl';
NODE_NAME     R3713 2
 '@T6G_MB_LIB.T6G(SCH_1):PAGE251_I33@PURE_QUANTA.Q_RES(CHIPS)':
 'B': CDS_PINID='B';
NODE_NAME     R3723 2
 '@T6G_MB_LIB.T6G(SCH_1):PAGE251_I53@PURE_QUANTA.Q_RES(CHIPS)':
 'B': CDS_PINID='B';
NODE_NAME     R1497 1
 '@T6G_MB_LIB.T6G(SCH_1):PAGE349_I176@PURE_QUANTA.Q_RES(CHIPS)':
 'A': CDS_PINID='A';
NODE_NAME     R308 1
 '@T6G_MB_LIB.T6G(SCH_1):PAGE349_I224@PURE_QUANTA.Q_RES(CHIPS)':
 'A': CDS_PINID='A';
NET_NAME
'SMB_VR_3V3AUX_SCL_R0'
 '@T6G_MB_LIB.T6G(SCH_1):SMB_VR_3V3AUX_SCL_R0':
 C_SIGNAL='@t6g_mb_lib.t6g(sch_1):smb_vr_3v3aux_scl_r0';
NODE_NAME     R2421 2
 '@T6G_MB_LIB.T6G(SCH_1):PAGE348_I98@PURE_QUANTA.Q_RES(CHIPS)':
 'B': CDS_PINID='B';
NODE_NAME     J41 A5
 '@T6G_MB_LIB.T6G(SCH_1):PAGE348_I176@PURE_QUANTA.SCONN168_ME1016810202011(CHIPS)':
 'GND_A5': CDS_PINID='GND_A5';
NET_NAME
'SMB_VR_3V3AUX_SCL_R6'
 '@T6G_MB_LIB.T6G(SCH_1):SMB_VR_3V3AUX_SCL_R6':
 C_SIGNAL='@t6g_mb_lib.t6g(sch_1):smb_vr_3v3aux_scl_r6';
NODE_NAME     R3713 1
 '@T6G_MB_LIB.T6G(SCH_1):PAGE251_I33@PURE_QUANTA.Q_RES(CHIPS)':
 'A': CDS_PINID='A';
NODE_NAME     U39 5
 '@T6G_MB_LIB.T6G(SCH_1):PAGE251_I74@PURE_QUANTA.TCA9548APWR(CHIPS)':
 'SC0': CDS_PINID='SC0';
NET_NAME
'SMB_VR_3V3AUX_SDA'
 '@T6G_MB_LIB.T6G(SCH_1):SMB_VR_3V3AUX_SDA':
 C_SIGNAL='@t6g_mb_lib.t6g(sch_1):smb_vr_3v3aux_sda';
NODE_NAME     R3714 2
 '@T6G_MB_LIB.T6G(SCH_1):PAGE251_I32@PURE_QUANTA.Q_RES(CHIPS)':
 'B': CDS_PINID='B';
NODE_NAME     R3724 2
 '@T6G_MB_LIB.T6G(SCH_1):PAGE251_I52@PURE_QUANTA.Q_RES(CHIPS)':
 'B': CDS_PINID='B';
NODE_NAME     R1498 1
 '@T6G_MB_LIB.T6G(SCH_1):PAGE349_I183@PURE_QUANTA.Q_RES(CHIPS)':
 'A': CDS_PINID='A';
NODE_NAME     R309 1
 '@T6G_MB_LIB.T6G(SCH_1):PAGE349_I225@PURE_QUANTA.Q_RES(CHIPS)':
 'A': CDS_PINID='A';
NET_NAME
'SMB_VR_3V3AUX_SDA_R0'
 '@T6G_MB_LIB.T6G(SCH_1):SMB_VR_3V3AUX_SDA_R0':
 C_SIGNAL='@t6g_mb_lib.t6g(sch_1):smb_vr_3v3aux_sda_r0';
NODE_NAME     J41 A6
 '@T6G_MB_LIB.T6G(SCH_1):PAGE348_I176@PURE_QUANTA.SCONN168_ME1016810202011(CHIPS)':
 'GND_A6': CDS_PINID='GND_A6';
NODE_NAME     R2422 2
 '@T6G_MB_LIB.T6G(SCH_1):PAGE348_I101@PURE_QUANTA.Q_RES(CHIPS)':
 'B': CDS_PINID='B';
NET_NAME
'SMB_VR_3V3AUX_SDA_R6'
 '@T6G_MB_LIB.T6G(SCH_1):SMB_VR_3V3AUX_SDA_R6':
 C_SIGNAL='@t6g_mb_lib.t6g(sch_1):smb_vr_3v3aux_sda_r6';
NODE_NAME     R3714 1
 '@T6G_MB_LIB.T6G(SCH_1):PAGE251_I32@PURE_QUANTA.Q_RES(CHIPS)':
 'A': CDS_PINID='A';
NODE_NAME     U39 4
 '@T6G_MB_LIB.T6G(SCH_1):PAGE251_I74@PURE_QUANTA.TCA9548APWR(CHIPS)':
 'SD0': CDS_PINID='SD0';
NET_NAME
'SMB_VR_3V3STBY_SCL'
 '@T6G_MB_LIB.T6G(SCH_1):SMB_VR_3V3STBY_SCL':
 C_SIGNAL='@t6g_mb_lib.t6g(sch_1):smb_vr_3v3stby_scl';
NODE_NAME     R175 1
 '@T6G_MB_LIB.T6G(SCH_1):PAGE185_I81@PURE_QUANTA.Q_RES(CHIPS)':
 'A': CDS_PINID='A';
NODE_NAME     R1321 1
 '@T6G_MB_LIB.T6G(SCH_1):PAGE349_I10@PURE_QUANTA.Q_RES(CHIPS)':
 'A': CDS_PINID='A';
NODE_NAME     R6858 1
 '@T6G_MB_LIB.T6G(SCH_1):PAGE349_I207@PURE_QUANTA.Q_RES(CHIPS)':
 'A': CDS_PINID='A';
NODE_NAME     R308 2
 '@T6G_MB_LIB.T6G(SCH_1):PAGE349_I224@PURE_QUANTA.Q_RES(CHIPS)':
 'B': CDS_PINID='B';
NET_NAME
'SMB_VR_3V3STBY_SDA'
 '@T6G_MB_LIB.T6G(SCH_1):SMB_VR_3V3STBY_SDA':
 C_SIGNAL='@t6g_mb_lib.t6g(sch_1):smb_vr_3v3stby_sda';
NODE_NAME     R8176 1
 '@T6G_MB_LIB.T6G(SCH_1):PAGE185_I80@PURE_QUANTA.Q_RES(CHIPS)':
 'A': CDS_PINID='A';
NODE_NAME     R1494 1
 '@T6G_MB_LIB.T6G(SCH_1):PAGE349_I9@PURE_QUANTA.Q_RES(CHIPS)':
 'A': CDS_PINID='A';
NODE_NAME     R6859 1
 '@T6G_MB_LIB.T6G(SCH_1):PAGE349_I206@PURE_QUANTA.Q_RES(CHIPS)':
 'A': CDS_PINID='A';
NODE_NAME     R309 2
 '@T6G_MB_LIB.T6G(SCH_1):PAGE349_I225@PURE_QUANTA.Q_RES(CHIPS)':
 'B': CDS_PINID='B';
NET_NAME
'SMB_VR_SENSOR_3V3AUX_SCL'
 '@T6G_MB_LIB.T6G(SCH_1):SMB_VR_SENSOR_3V3AUX_SCL':
 C_SIGNAL='@t6g_mb_lib.t6g(sch_1):smb_vr_sensor_3v3aux_scl';
NODE_NAME     R2421 1
 '@T6G_MB_LIB.T6G(SCH_1):PAGE348_I98@PURE_QUANTA.Q_RES(CHIPS)':
 'A': CDS_PINID='A';
NODE_NAME     R4269 2
 '@T6G_MB_LIB.T6G(SCH_1):PAGE251_I41@PURE_QUANTA.Q_RES(CHIPS)':
 'B': CDS_PINID='B';
NODE_NAME     R3711 1
 '@T6G_MB_LIB.T6G(SCH_1):PAGE251_I69@PURE_QUANTA.Q_RES(CHIPS)':
 'A': CDS_PINID='A';
NET_NAME
'SMB_VR_SENSOR_3V3AUX_SCL_R'
 '@T6G_MB_LIB.T6G(SCH_1):SMB_VR_SENSOR_3V3AUX_SCL_R':
 C_SIGNAL='@t6g_mb_lib.t6g(sch_1):smb_vr_sensor_3v3aux_scl_r';
NODE_NAME     R3711 2
 '@T6G_MB_LIB.T6G(SCH_1):PAGE251_I69@PURE_QUANTA.Q_RES(CHIPS)':
 'B': CDS_PINID='B';
NODE_NAME     U39 22
 '@T6G_MB_LIB.T6G(SCH_1):PAGE251_I74@PURE_QUANTA.TCA9548APWR(CHIPS)':
 'SCL': CDS_PINID='SCL';
NET_NAME
'SMB_VR_SENSOR_3V3AUX_SDA'
 '@T6G_MB_LIB.T6G(SCH_1):SMB_VR_SENSOR_3V3AUX_SDA':
 C_SIGNAL='@t6g_mb_lib.t6g(sch_1):smb_vr_sensor_3v3aux_sda';
NODE_NAME     R4270 2
 '@T6G_MB_LIB.T6G(SCH_1):PAGE251_I40@PURE_QUANTA.Q_RES(CHIPS)':
 'B': CDS_PINID='B';
NODE_NAME     R3712 1
 '@T6G_MB_LIB.T6G(SCH_1):PAGE251_I68@PURE_QUANTA.Q_RES(CHIPS)':
 'A': CDS_PINID='A';
NODE_NAME     R2422 1
 '@T6G_MB_LIB.T6G(SCH_1):PAGE348_I101@PURE_QUANTA.Q_RES(CHIPS)':
 'A': CDS_PINID='A';
NET_NAME
'SMB_VR_SENSOR_3V3AUX_SDA_R'
 '@T6G_MB_LIB.T6G(SCH_1):SMB_VR_SENSOR_3V3AUX_SDA_R':
 C_SIGNAL='@t6g_mb_lib.t6g(sch_1):smb_vr_sensor_3v3aux_sda_r';
NODE_NAME     R3712 2
 '@T6G_MB_LIB.T6G(SCH_1):PAGE251_I68@PURE_QUANTA.Q_RES(CHIPS)':
 'B': CDS_PINID='B';
NODE_NAME     U39 23
 '@T6G_MB_LIB.T6G(SCH_1):PAGE251_I74@PURE_QUANTA.TCA9548APWR(CHIPS)':
 'SDA': CDS_PINID='SDA';
NET_NAME
'SMERR_LED'
 '@T6G_MB_LIB.T6G(SCH_1):SMERR_LED':
 C_SIGNAL='@t6g_mb_lib.t6g(sch_1):smerr_led';
NODE_NAME     R947 2
 '@T6G_MB_LIB.T6G(SCH_1):PAGE143_I11@PURE_QUANTA.Q_RES(CHIPS)':
 'B': CDS_PINID='B';
NODE_NAME     Q11 6
 '@T6G_MB_LIB.T6G(SCH_1):PAGE143_I19@PURE_QUANTA.MOSFET_DUAL_6P(CHIPS)':
 'D1': CDS_PINID='D1';
NODE_NAME     Q11 5
 '@T6G_MB_LIB.T6G(SCH_1):PAGE143_I19@PURE_QUANTA.MOSFET_DUAL_6P(CHIPS)':
 'G2': CDS_PINID='G2';
NET_NAME
'SMERR_LED_N'
 '@T6G_MB_LIB.T6G(SCH_1):SMERR_LED_N':
 C_SIGNAL='@t6g_mb_lib.t6g(sch_1):smerr_led_n';
NODE_NAME     D6 C
 '@T6G_MB_LIB.T6G(SCH_1):PAGE143_I9@PURE_QUANTA.Q_LED(CHIPS)':
 'C': CDS_PINID='C';
NODE_NAME     Q11 3
 '@T6G_MB_LIB.T6G(SCH_1):PAGE143_I19@PURE_QUANTA.MOSFET_DUAL_6P(CHIPS)':
 'D2': CDS_PINID='D2';
NET_NAME
'SPI_CPU0_CLK'
 '@T6G_MB_LIB.T6G(SCH_1):SPI_CPU0_CLK':
 C_SIGNAL='@t6g_mb_lib.t6g(sch_1):spi_cpu0_clk';
NODE_NAME     U53 4
 '@T6G_MB_LIB.T6G(SCH_1):PAGE76_I63@PURE_QUANTA.SN74AVC4T774PWR(CHIPS)':
 'A2': CDS_PINID='A2';
NODE_NAME     R461 1
 '@T6G_MB_LIB.T6G(SCH_1):PAGE29_I409@PURE_QUANTA.Q_RES(CHIPS)':
 'A': CDS_PINID='A';
NODE_NAME     R743 2
 '@T6G_MB_LIB.T6G(SCH_1):PAGE75_I97@PURE_QUANTA.Q_RES(CHIPS)':
 'B': CDS_PINID='B';
NODE_NAME     R6098 2
 '@T6G_MB_LIB.T6G(SCH_1):PAGE75_I99@PURE_QUANTA.Q_RES(CHIPS)':
 'B': CDS_PINID='B';
NET_NAME
'SPI_CPU0_CS0_N'
 '@T6G_MB_LIB.T6G(SCH_1):SPI_CPU0_CS0_N':
 C_SIGNAL='@t6g_mb_lib.t6g(sch_1):spi_cpu0_cs0_n';
NODE_NAME     U53 3
 '@T6G_MB_LIB.T6G(SCH_1):PAGE76_I63@PURE_QUANTA.SN74AVC4T774PWR(CHIPS)':
 'A1': CDS_PINID='A1';
NODE_NAME     R811 2
 '@T6G_MB_LIB.T6G(SCH_1):PAGE76_I106@PURE_QUANTA.Q_RES(CHIPS)':
 'B': CDS_PINID='B';
NODE_NAME     R459 1
 '@T6G_MB_LIB.T6G(SCH_1):PAGE29_I407@PURE_QUANTA.Q_RES(CHIPS)':
 'A': CDS_PINID='A';
NET_NAME
'SPI_CPU0_CS1_N'
 '@T6G_MB_LIB.T6G(SCH_1):SPI_CPU0_CS1_N':
 C_SIGNAL='@t6g_mb_lib.t6g(sch_1):spi_cpu0_cs1_n';
NODE_NAME     U53 5
 '@T6G_MB_LIB.T6G(SCH_1):PAGE76_I63@PURE_QUANTA.SN74AVC4T774PWR(CHIPS)':
 'A3': CDS_PINID='A3';
NODE_NAME     R601 2
 '@T6G_MB_LIB.T6G(SCH_1):PAGE76_I108@PURE_QUANTA.Q_RES(CHIPS)':
 'B': CDS_PINID='B';
NODE_NAME     R460 1
 '@T6G_MB_LIB.T6G(SCH_1):PAGE29_I408@PURE_QUANTA.Q_RES(CHIPS)':
 'A': CDS_PINID='A';
NET_NAME
'SPI_CPU0_D0'
 '@T6G_MB_LIB.T6G(SCH_1):SPI_CPU0_D0':
 C_SIGNAL='@t6g_mb_lib.t6g(sch_1):spi_cpu0_d0';
NODE_NAME     R464 1
 '@T6G_MB_LIB.T6G(SCH_1):PAGE29_I410@PURE_QUANTA.Q_RES(CHIPS)':
 'A': CDS_PINID='A';
NODE_NAME     R1532 2
 '@T6G_MB_LIB.T6G(SCH_1):PAGE76_I131@PURE_QUANTA.Q_RES(CHIPS)':
 'B': CDS_PINID='B';
NODE_NAME     R8007 1
 '@T6G_MB_LIB.T6G(SCH_1):PAGE76_I240@PURE_QUANTA.Q_RES(CHIPS)':
 'A': CDS_PINID='A';
NET_NAME
'SPI_CPU0_D1'
 '@T6G_MB_LIB.T6G(SCH_1):SPI_CPU0_D1':
 C_SIGNAL='@t6g_mb_lib.t6g(sch_1):spi_cpu0_d1';
NODE_NAME     R465 1
 '@T6G_MB_LIB.T6G(SCH_1):PAGE29_I411@PURE_QUANTA.Q_RES(CHIPS)':
 'A': CDS_PINID='A';
NODE_NAME     R1531 2
 '@T6G_MB_LIB.T6G(SCH_1):PAGE76_I132@PURE_QUANTA.Q_RES(CHIPS)':
 'B': CDS_PINID='B';
NODE_NAME     R8008 1
 '@T6G_MB_LIB.T6G(SCH_1):PAGE76_I241@PURE_QUANTA.Q_RES(CHIPS)':
 'A': CDS_PINID='A';
NET_NAME
'SPI_CPU0_D2'
 '@T6G_MB_LIB.T6G(SCH_1):SPI_CPU0_D2':
 C_SIGNAL='@t6g_mb_lib.t6g(sch_1):spi_cpu0_d2';
NODE_NAME     R466 1
 '@T6G_MB_LIB.T6G(SCH_1):PAGE29_I412@PURE_QUANTA.Q_RES(CHIPS)':
 'A': CDS_PINID='A';
NODE_NAME     R1530 2
 '@T6G_MB_LIB.T6G(SCH_1):PAGE76_I133@PURE_QUANTA.Q_RES(CHIPS)':
 'B': CDS_PINID='B';
NODE_NAME     R8006 1
 '@T6G_MB_LIB.T6G(SCH_1):PAGE76_I239@PURE_QUANTA.Q_RES(CHIPS)':
 'A': CDS_PINID='A';
NET_NAME
'SPI_CPU0_D3'
 '@T6G_MB_LIB.T6G(SCH_1):SPI_CPU0_D3':
 C_SIGNAL='@t6g_mb_lib.t6g(sch_1):spi_cpu0_d3';
NODE_NAME     R467 1
 '@T6G_MB_LIB.T6G(SCH_1):PAGE29_I413@PURE_QUANTA.Q_RES(CHIPS)':
 'A': CDS_PINID='A';
NODE_NAME     R1529 2
 '@T6G_MB_LIB.T6G(SCH_1):PAGE76_I134@PURE_QUANTA.Q_RES(CHIPS)':
 'B': CDS_PINID='B';
NODE_NAME     R8005 1
 '@T6G_MB_LIB.T6G(SCH_1):PAGE76_I234@PURE_QUANTA.Q_RES(CHIPS)':
 'A': CDS_PINID='A';
NET_NAME
'SPI_CPU0_LVC3_CLK'
 '@T6G_MB_LIB.T6G(SCH_1):SPI_CPU0_LVC3_CLK':
 C_SIGNAL='@t6g_mb_lib.t6g(sch_1):spi_cpu0_lvc3_clk';
NODE_NAME     U53 13
 '@T6G_MB_LIB.T6G(SCH_1):PAGE76_I63@PURE_QUANTA.SN74AVC4T774PWR(CHIPS)':
 'B2': CDS_PINID='B2';
NODE_NAME     R602 1
 '@T6G_MB_LIB.T6G(SCH_1):PAGE76_I230@PURE_QUANTA.Q_RES(CHIPS)':
 'A': CDS_PINID='A';
NET_NAME
'SPI_CPU0_LVC3_CS0_N'
 '@T6G_MB_LIB.T6G(SCH_1):SPI_CPU0_LVC3_CS0_N':
 C_SIGNAL='@t6g_mb_lib.t6g(sch_1):spi_cpu0_lvc3_cs0_n';
NODE_NAME     U53 14
 '@T6G_MB_LIB.T6G(SCH_1):PAGE76_I63@PURE_QUANTA.SN74AVC4T774PWR(CHIPS)':
 'B1': CDS_PINID='B1';
NODE_NAME     R603 1
 '@T6G_MB_LIB.T6G(SCH_1):PAGE76_I228@PURE_QUANTA.Q_RES(CHIPS)':
 'A': CDS_PINID='A';
NET_NAME
'SPI_CPU0_LVC3_CS1_N'
 '@T6G_MB_LIB.T6G(SCH_1):SPI_CPU0_LVC3_CS1_N':
 C_SIGNAL='@t6g_mb_lib.t6g(sch_1):spi_cpu0_lvc3_cs1_n';
NODE_NAME     U53 12
 '@T6G_MB_LIB.T6G(SCH_1):PAGE76_I63@PURE_QUANTA.SN74AVC4T774PWR(CHIPS)':
 'B3': CDS_PINID='B3';
NODE_NAME     R600 1
 '@T6G_MB_LIB.T6G(SCH_1):PAGE76_I180@PURE_QUANTA.Q_RES(CHIPS)':
 'A': CDS_PINID='A';
NET_NAME
'SPI_CPU0_LVC3_D0'
 '@T6G_MB_LIB.T6G(SCH_1):SPI_CPU0_LVC3_D0':
 C_SIGNAL='@t6g_mb_lib.t6g(sch_1):spi_cpu0_lvc3_d0';
NODE_NAME     U54 8
 '@T6G_MB_LIB.T6G(SCH_1):PAGE76_I67@PURE_QUANTA.PI4ULS3V304AZMAEX(CHIPS)':
 'B3': CDS_PINID='B3';
NODE_NAME     R604 1
 '@T6G_MB_LIB.T6G(SCH_1):PAGE76_I221@PURE_QUANTA.Q_RES(CHIPS)':
 'A': CDS_PINID='A';
NET_NAME
'SPI_CPU0_LVC3_D1'
 '@T6G_MB_LIB.T6G(SCH_1):SPI_CPU0_LVC3_D1':
 C_SIGNAL='@t6g_mb_lib.t6g(sch_1):spi_cpu0_lvc3_d1';
NODE_NAME     U54 7
 '@T6G_MB_LIB.T6G(SCH_1):PAGE76_I67@PURE_QUANTA.PI4ULS3V304AZMAEX(CHIPS)':
 'B4': CDS_PINID='B4';
NODE_NAME     R605 1
 '@T6G_MB_LIB.T6G(SCH_1):PAGE76_I219@PURE_QUANTA.Q_RES(CHIPS)':
 'A': CDS_PINID='A';
NET_NAME
'SPI_CPU0_LVC3_D2'
 '@T6G_MB_LIB.T6G(SCH_1):SPI_CPU0_LVC3_D2':
 C_SIGNAL='@t6g_mb_lib.t6g(sch_1):spi_cpu0_lvc3_d2';
NODE_NAME     U54 9
 '@T6G_MB_LIB.T6G(SCH_1):PAGE76_I67@PURE_QUANTA.PI4ULS3V304AZMAEX(CHIPS)':
 'B2': CDS_PINID='B2';
NODE_NAME     R606 1
 '@T6G_MB_LIB.T6G(SCH_1):PAGE76_I205@PURE_QUANTA.Q_RES(CHIPS)':
 'A': CDS_PINID='A';
NET_NAME
'SPI_CPU0_LVC3_D3'
 '@T6G_MB_LIB.T6G(SCH_1):SPI_CPU0_LVC3_D3':
 C_SIGNAL='@t6g_mb_lib.t6g(sch_1):spi_cpu0_lvc3_d3';
NODE_NAME     U54 10
 '@T6G_MB_LIB.T6G(SCH_1):PAGE76_I67@PURE_QUANTA.PI4ULS3V304AZMAEX(CHIPS)':
 'B1': CDS_PINID='B1';
NODE_NAME     R607 1
 '@T6G_MB_LIB.T6G(SCH_1):PAGE76_I207@PURE_QUANTA.Q_RES(CHIPS)':
 'A': CDS_PINID='A';
NET_NAME
'SPI_CPU0_LVC3_R_TPM_CS_N'
 '@T6G_MB_LIB.T6G(SCH_1):SPI_CPU0_LVC3_R_TPM_CS_N':
 C_SIGNAL='@t6g_mb_lib.t6g(sch_1):spi_cpu0_lvc3_r_tpm_cs_n';
NODE_NAME     U53 11
 '@T6G_MB_LIB.T6G(SCH_1):PAGE76_I63@PURE_QUANTA.SN74AVC4T774PWR(CHIPS)':
 'B4': CDS_PINID='B4';
NODE_NAME     R608 1
 '@T6G_MB_LIB.T6G(SCH_1):PAGE76_I242@PURE_QUANTA.Q_RES(CHIPS)':
 'A': CDS_PINID='A';
NET_NAME
'SPI_CPU0_LVC3_SCM_CLK'
 '@T6G_MB_LIB.T6G(SCH_1):SPI_CPU0_LVC3_SCM_CLK':
 C_SIGNAL='@t6g_mb_lib.t6g(sch_1):spi_cpu0_lvc3_scm_clk';
NODE_NAME     R20 2
 '@T6G_MB_LIB.T6G(SCH_1):PAGE76_I115@PURE_QUANTA.Q_RES(CHIPS)':
 'B': CDS_PINID='B';
NODE_NAME     R602 2
 '@T6G_MB_LIB.T6G(SCH_1):PAGE76_I230@PURE_QUANTA.Q_RES(CHIPS)':
 'B': CDS_PINID='B';
NODE_NAME     J41 B11
 '@T6G_MB_LIB.T6G(SCH_1):PAGE348_I176@PURE_QUANTA.SCONN168_ME1016810202011(CHIPS)':
 '+3.3V_EDGE': CDS_PINID='\+3.3v_edge\';
NET_NAME
'SPI_CPU0_LVC3_SCM_CS0_N'
 '@T6G_MB_LIB.T6G(SCH_1):SPI_CPU0_LVC3_SCM_CS0_N':
 C_SIGNAL='@t6g_mb_lib.t6g(sch_1):spi_cpu0_lvc3_scm_cs0_n';
NODE_NAME     R610 2
 '@T6G_MB_LIB.T6G(SCH_1):PAGE76_I97@PURE_QUANTA.Q_RES(CHIPS)':
 'B': CDS_PINID='B';
NODE_NAME     R603 2
 '@T6G_MB_LIB.T6G(SCH_1):PAGE76_I228@PURE_QUANTA.Q_RES(CHIPS)':
 'B': CDS_PINID='B';
NODE_NAME     J41 B12
 '@T6G_MB_LIB.T6G(SCH_1):PAGE348_I176@PURE_QUANTA.SCONN168_ME1016810202011(CHIPS)':
 'AUX_PWR_EN': CDS_PINID='AUX_PWR_EN';
NET_NAME
'SPI_CPU0_LVC3_SCM_CS1_N'
 '@T6G_MB_LIB.T6G(SCH_1):SPI_CPU0_LVC3_SCM_CS1_N':
 C_SIGNAL='@t6g_mb_lib.t6g(sch_1):spi_cpu0_lvc3_scm_cs1_n';
NODE_NAME     R600 2
 '@T6G_MB_LIB.T6G(SCH_1):PAGE76_I180@PURE_QUANTA.Q_RES(CHIPS)':
 'B': CDS_PINID='B';
NODE_NAME     R1655 2
 '@T6G_MB_LIB.T6G(SCH_1):PAGE76_I191@PURE_QUANTA.Q_RES(CHIPS)':
 'B': CDS_PINID='B';
NET_NAME
'SPI_CPU0_LVC3_SCM_D0'
 '@T6G_MB_LIB.T6G(SCH_1):SPI_CPU0_LVC3_SCM_D0':
 C_SIGNAL='@t6g_mb_lib.t6g(sch_1):spi_cpu0_lvc3_scm_d0';
NODE_NAME     R21 2
 '@T6G_MB_LIB.T6G(SCH_1):PAGE76_I116@PURE_QUANTA.Q_RES(CHIPS)':
 'B': CDS_PINID='B';
NODE_NAME     R604 2
 '@T6G_MB_LIB.T6G(SCH_1):PAGE76_I221@PURE_QUANTA.Q_RES(CHIPS)':
 'B': CDS_PINID='B';
NODE_NAME     J41 B13
 '@T6G_MB_LIB.T6G(SCH_1):PAGE348_I176@PURE_QUANTA.SCONN168_ME1016810202011(CHIPS)':
 'GND_B13': CDS_PINID='GND_B13';
NET_NAME
'SPI_CPU0_LVC3_SCM_D1'
 '@T6G_MB_LIB.T6G(SCH_1):SPI_CPU0_LVC3_SCM_D1':
 C_SIGNAL='@t6g_mb_lib.t6g(sch_1):spi_cpu0_lvc3_scm_d1';
NODE_NAME     R127 2
 '@T6G_MB_LIB.T6G(SCH_1):PAGE76_I117@PURE_QUANTA.Q_RES(CHIPS)':
 'B': CDS_PINID='B';
NODE_NAME     R605 2
 '@T6G_MB_LIB.T6G(SCH_1):PAGE76_I219@PURE_QUANTA.Q_RES(CHIPS)':
 'B': CDS_PINID='B';
NODE_NAME     J41 B14
 '@T6G_MB_LIB.T6G(SCH_1):PAGE348_I176@PURE_QUANTA.SCONN168_ME1016810202011(CHIPS)':
 'REFCLKN0': CDS_PINID='REFCLKN0';
NET_NAME
'SPI_CPU0_LVC3_SCM_D2'
 '@T6G_MB_LIB.T6G(SCH_1):SPI_CPU0_LVC3_SCM_D2':
 C_SIGNAL='@t6g_mb_lib.t6g(sch_1):spi_cpu0_lvc3_scm_d2';
NODE_NAME     R128 2
 '@T6G_MB_LIB.T6G(SCH_1):PAGE76_I118@PURE_QUANTA.Q_RES(CHIPS)':
 'B': CDS_PINID='B';
NODE_NAME     R606 2
 '@T6G_MB_LIB.T6G(SCH_1):PAGE76_I205@PURE_QUANTA.Q_RES(CHIPS)':
 'B': CDS_PINID='B';
NODE_NAME     J41 B15
 '@T6G_MB_LIB.T6G(SCH_1):PAGE348_I176@PURE_QUANTA.SCONN168_ME1016810202011(CHIPS)':
 'REFCLKP0': CDS_PINID='REFCLKP0';
NET_NAME
'SPI_CPU0_LVC3_SCM_D3'
 '@T6G_MB_LIB.T6G(SCH_1):SPI_CPU0_LVC3_SCM_D3':
 C_SIGNAL='@t6g_mb_lib.t6g(sch_1):spi_cpu0_lvc3_scm_d3';
NODE_NAME     R129 2
 '@T6G_MB_LIB.T6G(SCH_1):PAGE76_I119@PURE_QUANTA.Q_RES(CHIPS)':
 'B': CDS_PINID='B';
NODE_NAME     R607 2
 '@T6G_MB_LIB.T6G(SCH_1):PAGE76_I207@PURE_QUANTA.Q_RES(CHIPS)':
 'B': CDS_PINID='B';
NODE_NAME     J41 B16
 '@T6G_MB_LIB.T6G(SCH_1):PAGE348_I176@PURE_QUANTA.SCONN168_ME1016810202011(CHIPS)':
 'GND_B16': CDS_PINID='GND_B16';
NET_NAME
'SPI_CPU0_LVC3_TPM_CS_N'
 '@T6G_MB_LIB.T6G(SCH_1):SPI_CPU0_LVC3_TPM_CS_N':
 C_SIGNAL='@t6g_mb_lib.t6g(sch_1):spi_cpu0_lvc3_tpm_cs_n';
NODE_NAME     R1547 2
 '@T6G_MB_LIB.T6G(SCH_1):PAGE76_I148@PURE_QUANTA.Q_RES(CHIPS)':
 'B': CDS_PINID='B';
NODE_NAME     J41 OB12
 '@T6G_MB_LIB.T6G(SCH_1):PAGE348_I176@PURE_QUANTA.SCONN168_ME1016810202011(CHIPS)':
 'REFCLKP2': CDS_PINID='REFCLKP2';
NODE_NAME     R608 2
 '@T6G_MB_LIB.T6G(SCH_1):PAGE76_I242@PURE_QUANTA.Q_RES(CHIPS)':
 'B': CDS_PINID='B';
NET_NAME
'SPI_CPU0_R1_D0'
 '@T6G_MB_LIB.T6G(SCH_1):SPI_CPU0_R1_D0':
 C_SIGNAL='@t6g_mb_lib.t6g(sch_1):spi_cpu0_r1_d0';
NODE_NAME     U54 4
 '@T6G_MB_LIB.T6G(SCH_1):PAGE76_I67@PURE_QUANTA.PI4ULS3V304AZMAEX(CHIPS)':
 'A3': CDS_PINID='A3';
NODE_NAME     R8007 2
 '@T6G_MB_LIB.T6G(SCH_1):PAGE76_I240@PURE_QUANTA.Q_RES(CHIPS)':
 'B': CDS_PINID='B';
NET_NAME
'SPI_CPU0_R1_D1'
 '@T6G_MB_LIB.T6G(SCH_1):SPI_CPU0_R1_D1':
 C_SIGNAL='@t6g_mb_lib.t6g(sch_1):spi_cpu0_r1_d1';
NODE_NAME     U54 5
 '@T6G_MB_LIB.T6G(SCH_1):PAGE76_I67@PURE_QUANTA.PI4ULS3V304AZMAEX(CHIPS)':
 'A4': CDS_PINID='A4';
NODE_NAME     R8008 2
 '@T6G_MB_LIB.T6G(SCH_1):PAGE76_I241@PURE_QUANTA.Q_RES(CHIPS)':
 'B': CDS_PINID='B';
NET_NAME
'SPI_CPU0_R1_D2'
 '@T6G_MB_LIB.T6G(SCH_1):SPI_CPU0_R1_D2':
 C_SIGNAL='@t6g_mb_lib.t6g(sch_1):spi_cpu0_r1_d2';
NODE_NAME     U54 3
 '@T6G_MB_LIB.T6G(SCH_1):PAGE76_I67@PURE_QUANTA.PI4ULS3V304AZMAEX(CHIPS)':
 'A2': CDS_PINID='A2';
NODE_NAME     R8006 2
 '@T6G_MB_LIB.T6G(SCH_1):PAGE76_I239@PURE_QUANTA.Q_RES(CHIPS)':
 'B': CDS_PINID='B';
NET_NAME
'SPI_CPU0_R1_D3'
 '@T6G_MB_LIB.T6G(SCH_1):SPI_CPU0_R1_D3':
 C_SIGNAL='@t6g_mb_lib.t6g(sch_1):spi_cpu0_r1_d3';
NODE_NAME     U54 2
 '@T6G_MB_LIB.T6G(SCH_1):PAGE76_I67@PURE_QUANTA.PI4ULS3V304AZMAEX(CHIPS)':
 'A1': CDS_PINID='A1';
NODE_NAME     R8005 2
 '@T6G_MB_LIB.T6G(SCH_1):PAGE76_I234@PURE_QUANTA.Q_RES(CHIPS)':
 'B': CDS_PINID='B';
NET_NAME
'SPI_CPU0_R_CLK'
 '@T6G_MB_LIB.T6G(SCH_1):SPI_CPU0_R_CLK':
 C_SIGNAL='@t6g_mb_lib.t6g(sch_1):spi_cpu0_r_clk';
NODE_NAME     U25 DJ27
 '@T6G_MB_LIB.T6G(SCH_1):PAGE29_I287@PURE_QUANTA.GENOA_SP5(CHIPS)':
 'ESPI_CLK0||SPI_CLK0||AGPIO117': CDS_PINID='\espi_clk0||spi_clk0||agpio117\';
NODE_NAME     R461 2
 '@T6G_MB_LIB.T6G(SCH_1):PAGE29_I409@PURE_QUANTA.Q_RES(CHIPS)':
 'B': CDS_PINID='B';
NET_NAME
'SPI_CPU0_R_CS0_N'
 '@T6G_MB_LIB.T6G(SCH_1):SPI_CPU0_R_CS0_N':
 C_SIGNAL='@t6g_mb_lib.t6g(sch_1):spi_cpu0_r_cs0_n';
NODE_NAME     U25 DF30
 '@T6G_MB_LIB.T6G(SCH_1):PAGE29_I287@PURE_QUANTA.GENOA_SP5(CHIPS)':
 'SPI_CS0_L||AGPIO118': CDS_PINID='\spi_cs0_l||agpio118\';
NODE_NAME     R459 2
 '@T6G_MB_LIB.T6G(SCH_1):PAGE29_I407@PURE_QUANTA.Q_RES(CHIPS)':
 'B': CDS_PINID='B';
NET_NAME
'SPI_CPU0_R_CS1_N'
 '@T6G_MB_LIB.T6G(SCH_1):SPI_CPU0_R_CS1_N':
 C_SIGNAL='@t6g_mb_lib.t6g(sch_1):spi_cpu0_r_cs1_n';
NODE_NAME     U25 DG26
 '@T6G_MB_LIB.T6G(SCH_1):PAGE29_I287@PURE_QUANTA.GENOA_SP5(CHIPS)':
 'SPI_CS1_L||AGPIO119': CDS_PINID='\spi_cs1_l||agpio119\';
NODE_NAME     R460 2
 '@T6G_MB_LIB.T6G(SCH_1):PAGE29_I408@PURE_QUANTA.Q_RES(CHIPS)':
 'B': CDS_PINID='B';
NET_NAME
'SPI_CPU0_R_D0'
 '@T6G_MB_LIB.T6G(SCH_1):SPI_CPU0_R_D0':
 C_SIGNAL='@t6g_mb_lib.t6g(sch_1):spi_cpu0_r_d0';
NODE_NAME     U25 DF28
 '@T6G_MB_LIB.T6G(SCH_1):PAGE29_I287@PURE_QUANTA.GENOA_SP5(CHIPS)':
 'ESPI0_DAT0||SPI0_DAT0||AGPIO120': CDS_PINID='\espi0_dat0||spi0_dat0||agpio120\';
NODE_NAME     R464 2
 '@T6G_MB_LIB.T6G(SCH_1):PAGE29_I410@PURE_QUANTA.Q_RES(CHIPS)':
 'B': CDS_PINID='B';
NET_NAME
'SPI_CPU0_R_D1'
 '@T6G_MB_LIB.T6G(SCH_1):SPI_CPU0_R_D1':
 C_SIGNAL='@t6g_mb_lib.t6g(sch_1):spi_cpu0_r_d1';
NODE_NAME     U25 DG22
 '@T6G_MB_LIB.T6G(SCH_1):PAGE29_I287@PURE_QUANTA.GENOA_SP5(CHIPS)':
 'ESPI0_DAT1||SPI0_DAT1||AGPIO121': CDS_PINID='\espi0_dat1||spi0_dat1||agpio121\';
NODE_NAME     R465 2
 '@T6G_MB_LIB.T6G(SCH_1):PAGE29_I411@PURE_QUANTA.Q_RES(CHIPS)':
 'B': CDS_PINID='B';
NET_NAME
'SPI_CPU0_R_D2'
 '@T6G_MB_LIB.T6G(SCH_1):SPI_CPU0_R_D2':
 C_SIGNAL='@t6g_mb_lib.t6g(sch_1):spi_cpu0_r_d2';
NODE_NAME     U25 DJ28
 '@T6G_MB_LIB.T6G(SCH_1):PAGE29_I287@PURE_QUANTA.GENOA_SP5(CHIPS)':
 'ESPI0_DAT2||SPI0_DAT2||AGPIO122': CDS_PINID='\espi0_dat2||spi0_dat2||agpio122\';
NODE_NAME     R466 2
 '@T6G_MB_LIB.T6G(SCH_1):PAGE29_I412@PURE_QUANTA.Q_RES(CHIPS)':
 'B': CDS_PINID='B';
NET_NAME
'SPI_CPU0_R_D3'
 '@T6G_MB_LIB.T6G(SCH_1):SPI_CPU0_R_D3':
 C_SIGNAL='@t6g_mb_lib.t6g(sch_1):spi_cpu0_r_d3';
NODE_NAME     U25 DG29
 '@T6G_MB_LIB.T6G(SCH_1):PAGE29_I287@PURE_QUANTA.GENOA_SP5(CHIPS)':
 'ESPI0_DAT3||SPI0_DAT3||AGPIO123': CDS_PINID='\espi0_dat3||spi0_dat3||agpio123\';
NODE_NAME     R467 2
 '@T6G_MB_LIB.T6G(SCH_1):PAGE29_I413@PURE_QUANTA.Q_RES(CHIPS)':
 'B': CDS_PINID='B';
NET_NAME
'SPI_CPU0_R_TPM_CS_N'
 '@T6G_MB_LIB.T6G(SCH_1):SPI_CPU0_R_TPM_CS_N':
 C_SIGNAL='@t6g_mb_lib.t6g(sch_1):spi_cpu0_r_tpm_cs_n';
NODE_NAME     U25 DJ25
 '@T6G_MB_LIB.T6G(SCH_1):PAGE29_I287@PURE_QUANTA.GENOA_SP5(CHIPS)':
 'AGPIO76||SPI_TPM_CS_L': CDS_PINID='\agpio76||spi_tpm_cs_l\';
NODE_NAME     R475 2
 '@T6G_MB_LIB.T6G(SCH_1):PAGE29_I414@PURE_QUANTA.Q_RES(CHIPS)':
 'B': CDS_PINID='B';
NET_NAME
'SPI_CPU0_TPM_CS_N'
 '@T6G_MB_LIB.T6G(SCH_1):SPI_CPU0_TPM_CS_N':
 C_SIGNAL='@t6g_mb_lib.t6g(sch_1):spi_cpu0_tpm_cs_n';
NODE_NAME     U53 6
 '@T6G_MB_LIB.T6G(SCH_1):PAGE76_I63@PURE_QUANTA.SN74AVC4T774PWR(CHIPS)':
 'A4': CDS_PINID='A4';
NODE_NAME     R659 2
 '@T6G_MB_LIB.T6G(SCH_1):PAGE76_I107@PURE_QUANTA.Q_RES(CHIPS)':
 'B': CDS_PINID='B';
NODE_NAME     R475 1
 '@T6G_MB_LIB.T6G(SCH_1):PAGE29_I414@PURE_QUANTA.Q_RES(CHIPS)':
 'A': CDS_PINID='A';
NET_NAME
'SPI_CPU1_CLK'
 '@T6G_MB_LIB.T6G(SCH_1):SPI_CPU1_CLK':
 C_SIGNAL='@t6g_mb_lib.t6g(sch_1):spi_cpu1_clk';
NODE_NAME     R738 1
 '@T6G_MB_LIB.T6G(SCH_1):PAGE56_I11@PURE_QUANTA.Q_RES(CHIPS)':
 'A': CDS_PINID='A';
NODE_NAME     R730 2
 '@T6G_MB_LIB.T6G(SCH_1):PAGE75_I87@PURE_QUANTA.Q_RES(CHIPS)':
 'B': CDS_PINID='B';
NODE_NAME     R754 2
 '@T6G_MB_LIB.T6G(SCH_1):PAGE75_I91@PURE_QUANTA.Q_RES(CHIPS)':
 'B': CDS_PINID='B';
NET_NAME
'SPI_CPU1_R_CLK'
 '@T6G_MB_LIB.T6G(SCH_1):SPI_CPU1_R_CLK':
 C_SIGNAL='@t6g_mb_lib.t6g(sch_1):spi_cpu1_r_clk';
NODE_NAME     U26 DJ27
 '@T6G_MB_LIB.T6G(SCH_1):PAGE56_I8@PURE_QUANTA.GENOA_SP5(CHIPS)':
 'ESPI_CLK0||SPI_CLK0||AGPIO117': CDS_PINID='\espi_clk0||spi_clk0||agpio117\';
NODE_NAME     R738 2
 '@T6G_MB_LIB.T6G(SCH_1):PAGE56_I11@PURE_QUANTA.Q_RES(CHIPS)':
 'B': CDS_PINID='B';
NET_NAME
'SVID_PVDDCR_CPU0_P0_SVC'
 '@T6G_MB_LIB.T6G(SCH_1):SVID_PVDDCR_CPU0_P0_SVC':
 C_SIGNAL='@t6g_mb_lib.t6g(sch_1):svid_pvddcr_cpu0_p0_svc';
NODE_NAME     U25 A23
 '@T6G_MB_LIB.T6G(SCH_1):PAGE27_I227@PURE_QUANTA.GENOA_SP5(CHIPS)':
 'SVC0': CDS_PINID='SVC0';
NODE_NAME     PR302 2
 '@T6G_MB_LIB.T6G(SCH_1):PAGE27_I323@PURE_QUANTA.Q_RES(CHIPS)':
 'B': CDS_PINID='B';
NET_NAME
'SVID_PVDDCR_CPU0_P0_SVC_R'
 '@T6G_MB_LIB.T6G(SCH_1):SVID_PVDDCR_CPU0_P0_SVC_R':
 C_SIGNAL='@t6g_mb_lib.t6g(sch_1):svid_pvddcr_cpu0_p0_svc_r';
NODE_NAME     PR302 1
 '@T6G_MB_LIB.T6G(SCH_1):PAGE27_I323@PURE_QUANTA.Q_RES(CHIPS)':
 'A': CDS_PINID='A';
NODE_NAME     C302 1
 '@T6G_MB_LIB.T6G(SCH_1):PAGE168_I68@PURE_QUANTA.Q_CAP(CHIPS)':
 'A': CDS_PINID='A';
NODE_NAME     R8293 2
 '@T6G_MB_LIB.T6G(SCH_1):PAGE168_I71@PURE_QUANTA.Q_RES(CHIPS)':
 'B': CDS_PINID='B';
NODE_NAME     PR8005 1
 '@T6G_MB_LIB.T6G(SCH_1):PAGE168_I147@PURE_QUANTA.Q_RES(CHIPS)':
 'A': CDS_PINID='A';
NET_NAME
'SVID_PVDDCR_CPU0_P0_SVC_R1'
 '@T6G_MB_LIB.T6G(SCH_1):SVID_PVDDCR_CPU0_P0_SVC_R1':
 C_SIGNAL='@t6g_mb_lib.t6g(sch_1):svid_pvddcr_cpu0_p0_svc_r1';
NODE_NAME     PU42 22
 '@T6G_MB_LIB.T6G(SCH_1):PAGE168_I135@PURE_QUANTA.RAA229620GNPHA0(CHIPS)':
 'SVC': CDS_PINID='SVC';
NODE_NAME     PR8005 2
 '@T6G_MB_LIB.T6G(SCH_1):PAGE168_I147@PURE_QUANTA.Q_RES(CHIPS)':
 'B': CDS_PINID='B';
NET_NAME
'SVID_PVDDCR_CPU0_P0_SVD'
 '@T6G_MB_LIB.T6G(SCH_1):SVID_PVDDCR_CPU0_P0_SVD':
 C_SIGNAL='@t6g_mb_lib.t6g(sch_1):svid_pvddcr_cpu0_p0_svd';
NODE_NAME     U25 A22
 '@T6G_MB_LIB.T6G(SCH_1):PAGE27_I227@PURE_QUANTA.GENOA_SP5(CHIPS)':
 'SVD0': CDS_PINID='SVD0';
NODE_NAME     PR303 2
 '@T6G_MB_LIB.T6G(SCH_1):PAGE27_I322@PURE_QUANTA.Q_RES(CHIPS)':
 'B': CDS_PINID='B';
NET_NAME
'SVID_PVDDCR_CPU0_P0_SVD_R'
 '@T6G_MB_LIB.T6G(SCH_1):SVID_PVDDCR_CPU0_P0_SVD_R':
 C_SIGNAL='@t6g_mb_lib.t6g(sch_1):svid_pvddcr_cpu0_p0_svd_r';
NODE_NAME     PR303 1
 '@T6G_MB_LIB.T6G(SCH_1):PAGE27_I322@PURE_QUANTA.Q_RES(CHIPS)':
 'A': CDS_PINID='A';
NODE_NAME     C299 1
 '@T6G_MB_LIB.T6G(SCH_1):PAGE168_I66@PURE_QUANTA.Q_CAP(CHIPS)':
 'A': CDS_PINID='A';
NODE_NAME     R8289 2
 '@T6G_MB_LIB.T6G(SCH_1):PAGE168_I70@PURE_QUANTA.Q_RES(CHIPS)':
 'B': CDS_PINID='B';
NODE_NAME     PR8006 1
 '@T6G_MB_LIB.T6G(SCH_1):PAGE168_I148@PURE_QUANTA.Q_RES(CHIPS)':
 'A': CDS_PINID='A';
NET_NAME
'SVID_PVDDCR_CPU0_P0_SVD_R1'
 '@T6G_MB_LIB.T6G(SCH_1):SVID_PVDDCR_CPU0_P0_SVD_R1':
 C_SIGNAL='@t6g_mb_lib.t6g(sch_1):svid_pvddcr_cpu0_p0_svd_r1';
NODE_NAME     PU42 21
 '@T6G_MB_LIB.T6G(SCH_1):PAGE168_I135@PURE_QUANTA.RAA229620GNPHA0(CHIPS)':
 'SVD': CDS_PINID='SVD';
NODE_NAME     PR8006 2
 '@T6G_MB_LIB.T6G(SCH_1):PAGE168_I148@PURE_QUANTA.Q_RES(CHIPS)':
 'B': CDS_PINID='B';
NET_NAME
'SVID_PVDDCR_CPU0_P0_SVTI'
 '@T6G_MB_LIB.T6G(SCH_1):SVID_PVDDCR_CPU0_P0_SVTI':
 C_SIGNAL='@t6g_mb_lib.t6g(sch_1):svid_pvddcr_cpu0_p0_svti';
NODE_NAME     PR283 1
 '@T6G_MB_LIB.T6G(SCH_1):PAGE168_I4@PURE_QUANTA.Q_RES(CHIPS)':
 'A': CDS_PINID='A';
NODE_NAME     PR305 1
 '@T6G_MB_LIB.T6G(SCH_1):PAGE168_I86@PURE_QUANTA.Q_RES(CHIPS)':
 'A': CDS_PINID='A';
NODE_NAME     PR284 2
 '@T6G_MB_LIB.T6G(SCH_1):PAGE168_I10@PURE_QUANTA.Q_RES(CHIPS)':
 'B': CDS_PINID='B';
NET_NAME
'SVID_PVDDCR_CPU0_P0_SVTI_R'
 '@T6G_MB_LIB.T6G(SCH_1):SVID_PVDDCR_CPU0_P0_SVTI_R':
 C_SIGNAL='@t6g_mb_lib.t6g(sch_1):svid_pvddcr_cpu0_p0_svti_r';
NODE_NAME     PR305 2
 '@T6G_MB_LIB.T6G(SCH_1):PAGE168_I86@PURE_QUANTA.Q_RES(CHIPS)':
 'B': CDS_PINID='B';
NODE_NAME     PU42 24
 '@T6G_MB_LIB.T6G(SCH_1):PAGE168_I135@PURE_QUANTA.RAA229620GNPHA0(CHIPS)':
 'SVTI': CDS_PINID='SVTI';
NET_NAME
'SVID_PVDDCR_CPU0_P0_SVTO'
 '@T6G_MB_LIB.T6G(SCH_1):SVID_PVDDCR_CPU0_P0_SVTO':
 C_SIGNAL='@t6g_mb_lib.t6g(sch_1):svid_pvddcr_cpu0_p0_svto';
NODE_NAME     U25 B21
 '@T6G_MB_LIB.T6G(SCH_1):PAGE27_I227@PURE_QUANTA.GENOA_SP5(CHIPS)':
 'SVT0': CDS_PINID='SVT0';
NODE_NAME     R8304 1
 '@T6G_MB_LIB.T6G(SCH_1):PAGE168_I87@PURE_QUANTA.Q_RES(CHIPS)':
 'A': CDS_PINID='A';
NODE_NAME     R8286 1
 '@T6G_MB_LIB.T6G(SCH_1):PAGE168_I6@PURE_QUANTA.Q_RES(CHIPS)':
 'A': CDS_PINID='A';
NODE_NAME     C298 1
 '@T6G_MB_LIB.T6G(SCH_1):PAGE168_I64@PURE_QUANTA.Q_CAP(CHIPS)':
 'A': CDS_PINID='A';
NODE_NAME     R8287 2
 '@T6G_MB_LIB.T6G(SCH_1):PAGE168_I69@PURE_QUANTA.Q_RES(CHIPS)':
 'B': CDS_PINID='B';
NET_NAME
'SVID_PVDDCR_CPU0_P0_SVTO_R'
 '@T6G_MB_LIB.T6G(SCH_1):SVID_PVDDCR_CPU0_P0_SVTO_R':
 C_SIGNAL='@t6g_mb_lib.t6g(sch_1):svid_pvddcr_cpu0_p0_svto_r';
NODE_NAME     R8304 2
 '@T6G_MB_LIB.T6G(SCH_1):PAGE168_I87@PURE_QUANTA.Q_RES(CHIPS)':
 'B': CDS_PINID='B';
NODE_NAME     PU42 23
 '@T6G_MB_LIB.T6G(SCH_1):PAGE168_I135@PURE_QUANTA.RAA229620GNPHA0(CHIPS)':
 'SVTO': CDS_PINID='SVTO';
NET_NAME
'SVID_PVDDCR_CPU0_P1_SVC'
 '@T6G_MB_LIB.T6G(SCH_1):SVID_PVDDCR_CPU0_P1_SVC':
 C_SIGNAL='@t6g_mb_lib.t6g(sch_1):svid_pvddcr_cpu0_p1_svc';
NODE_NAME     U26 A23
 '@T6G_MB_LIB.T6G(SCH_1):PAGE54_I190@PURE_QUANTA.GENOA_SP5(CHIPS)':
 'SVC0': CDS_PINID='SVC0';
NODE_NAME     PR169 2
 '@T6G_MB_LIB.T6G(SCH_1):PAGE54_I334@PURE_QUANTA.Q_RES(CHIPS)':
 'B': CDS_PINID='B';
NET_NAME
'SVID_PVDDCR_CPU0_P1_SVC_R'
 '@T6G_MB_LIB.T6G(SCH_1):SVID_PVDDCR_CPU0_P1_SVC_R':
 C_SIGNAL='@t6g_mb_lib.t6g(sch_1):svid_pvddcr_cpu0_p1_svc_r';
NODE_NAME     PR169 1
 '@T6G_MB_LIB.T6G(SCH_1):PAGE54_I334@PURE_QUANTA.Q_RES(CHIPS)':
 'A': CDS_PINID='A';
NODE_NAME     C297 1
 '@T6G_MB_LIB.T6G(SCH_1):PAGE185_I66@PURE_QUANTA.Q_CAP(CHIPS)':
 'A': CDS_PINID='A';
NODE_NAME     R8160 2
 '@T6G_MB_LIB.T6G(SCH_1):PAGE185_I69@PURE_QUANTA.Q_RES(CHIPS)':
 'B': CDS_PINID='B';
NODE_NAME     PR8009 1
 '@T6G_MB_LIB.T6G(SCH_1):PAGE185_I143@PURE_QUANTA.Q_RES(CHIPS)':
 'A': CDS_PINID='A';
NET_NAME
'SVID_PVDDCR_CPU0_P1_SVC_R1'
 '@T6G_MB_LIB.T6G(SCH_1):SVID_PVDDCR_CPU0_P1_SVC_R1':
 C_SIGNAL='@t6g_mb_lib.t6g(sch_1):svid_pvddcr_cpu0_p1_svc_r1';
NODE_NAME     PU25 22
 '@T6G_MB_LIB.T6G(SCH_1):PAGE185_I133@PURE_QUANTA.RAA229620GNPHA0(CHIPS)':
 'SVC': CDS_PINID='SVC';
NODE_NAME     PR8009 2
 '@T6G_MB_LIB.T6G(SCH_1):PAGE185_I143@PURE_QUANTA.Q_RES(CHIPS)':
 'B': CDS_PINID='B';
NET_NAME
'SVID_PVDDCR_CPU0_P1_SVD'
 '@T6G_MB_LIB.T6G(SCH_1):SVID_PVDDCR_CPU0_P1_SVD':
 C_SIGNAL='@t6g_mb_lib.t6g(sch_1):svid_pvddcr_cpu0_p1_svd';
NODE_NAME     U26 A22
 '@T6G_MB_LIB.T6G(SCH_1):PAGE54_I190@PURE_QUANTA.GENOA_SP5(CHIPS)':
 'SVD0': CDS_PINID='SVD0';
NODE_NAME     PR170 2
 '@T6G_MB_LIB.T6G(SCH_1):PAGE54_I333@PURE_QUANTA.Q_RES(CHIPS)':
 'B': CDS_PINID='B';
NET_NAME
'SVID_PVDDCR_CPU0_P1_SVD_R'
 '@T6G_MB_LIB.T6G(SCH_1):SVID_PVDDCR_CPU0_P1_SVD_R':
 C_SIGNAL='@t6g_mb_lib.t6g(sch_1):svid_pvddcr_cpu0_p1_svd_r';
NODE_NAME     PR170 1
 '@T6G_MB_LIB.T6G(SCH_1):PAGE54_I333@PURE_QUANTA.Q_RES(CHIPS)':
 'A': CDS_PINID='A';
NODE_NAME     R8156 2
 '@T6G_MB_LIB.T6G(SCH_1):PAGE185_I68@PURE_QUANTA.Q_RES(CHIPS)':
 'B': CDS_PINID='B';
NODE_NAME     C296 1
 '@T6G_MB_LIB.T6G(SCH_1):PAGE185_I64@PURE_QUANTA.Q_CAP(CHIPS)':
 'A': CDS_PINID='A';
NODE_NAME     PR8010 1
 '@T6G_MB_LIB.T6G(SCH_1):PAGE185_I144@PURE_QUANTA.Q_RES(CHIPS)':
 'A': CDS_PINID='A';
NET_NAME
'SVID_PVDDCR_CPU0_P1_SVD_R1'
 '@T6G_MB_LIB.T6G(SCH_1):SVID_PVDDCR_CPU0_P1_SVD_R1':
 C_SIGNAL='@t6g_mb_lib.t6g(sch_1):svid_pvddcr_cpu0_p1_svd_r1';
NODE_NAME     PU25 21
 '@T6G_MB_LIB.T6G(SCH_1):PAGE185_I133@PURE_QUANTA.RAA229620GNPHA0(CHIPS)':
 'SVD': CDS_PINID='SVD';
NODE_NAME     PR8010 2
 '@T6G_MB_LIB.T6G(SCH_1):PAGE185_I144@PURE_QUANTA.Q_RES(CHIPS)':
 'B': CDS_PINID='B';
NET_NAME
'SVID_PVDDCR_CPU0_P1_SVTI'
 '@T6G_MB_LIB.T6G(SCH_1):SVID_PVDDCR_CPU0_P1_SVTI':
 C_SIGNAL='@t6g_mb_lib.t6g(sch_1):svid_pvddcr_cpu0_p1_svti';
NODE_NAME     PR150 1
 '@T6G_MB_LIB.T6G(SCH_1):PAGE185_I4@PURE_QUANTA.Q_RES(CHIPS)':
 'A': CDS_PINID='A';
NODE_NAME     PR172 1
 '@T6G_MB_LIB.T6G(SCH_1):PAGE185_I82@PURE_QUANTA.Q_RES(CHIPS)':
 'A': CDS_PINID='A';
NODE_NAME     PR151 2
 '@T6G_MB_LIB.T6G(SCH_1):PAGE185_I10@PURE_QUANTA.Q_RES(CHIPS)':
 'B': CDS_PINID='B';
NET_NAME
'SVID_PVDDCR_CPU0_P1_SVTI_R'
 '@T6G_MB_LIB.T6G(SCH_1):SVID_PVDDCR_CPU0_P1_SVTI_R':
 C_SIGNAL='@t6g_mb_lib.t6g(sch_1):svid_pvddcr_cpu0_p1_svti_r';
NODE_NAME     PR172 2
 '@T6G_MB_LIB.T6G(SCH_1):PAGE185_I82@PURE_QUANTA.Q_RES(CHIPS)':
 'B': CDS_PINID='B';
NODE_NAME     PU25 24
 '@T6G_MB_LIB.T6G(SCH_1):PAGE185_I133@PURE_QUANTA.RAA229620GNPHA0(CHIPS)':
 'SVTI': CDS_PINID='SVTI';
NET_NAME
'SVID_PVDDCR_CPU0_P1_SVTO'
 '@T6G_MB_LIB.T6G(SCH_1):SVID_PVDDCR_CPU0_P1_SVTO':
 C_SIGNAL='@t6g_mb_lib.t6g(sch_1):svid_pvddcr_cpu0_p1_svto';
NODE_NAME     U26 B21
 '@T6G_MB_LIB.T6G(SCH_1):PAGE54_I190@PURE_QUANTA.GENOA_SP5(CHIPS)':
 'SVT0': CDS_PINID='SVT0';
NODE_NAME     C295 1
 '@T6G_MB_LIB.T6G(SCH_1):PAGE185_I62@PURE_QUANTA.Q_CAP(CHIPS)':
 'A': CDS_PINID='A';
NODE_NAME     R154 2
 '@T6G_MB_LIB.T6G(SCH_1):PAGE185_I67@PURE_QUANTA.Q_RES(CHIPS)':
 'B': CDS_PINID='B';
NODE_NAME     R8153 1
 '@T6G_MB_LIB.T6G(SCH_1):PAGE185_I6@PURE_QUANTA.Q_RES(CHIPS)':
 'A': CDS_PINID='A';
NODE_NAME     R8171 1
 '@T6G_MB_LIB.T6G(SCH_1):PAGE185_I83@PURE_QUANTA.Q_RES(CHIPS)':
 'A': CDS_PINID='A';
NET_NAME
'SVID_PVDDCR_CPU0_P1_SVTO_R'
 '@T6G_MB_LIB.T6G(SCH_1):SVID_PVDDCR_CPU0_P1_SVTO_R':
 C_SIGNAL='@t6g_mb_lib.t6g(sch_1):svid_pvddcr_cpu0_p1_svto_r';
NODE_NAME     R8171 2
 '@T6G_MB_LIB.T6G(SCH_1):PAGE185_I83@PURE_QUANTA.Q_RES(CHIPS)':
 'B': CDS_PINID='B';
NODE_NAME     PU25 23
 '@T6G_MB_LIB.T6G(SCH_1):PAGE185_I133@PURE_QUANTA.RAA229620GNPHA0(CHIPS)':
 'SVTO': CDS_PINID='SVTO';
NET_NAME
'SVID_PVDDCR_CPU1_P0_SVC'
 '@T6G_MB_LIB.T6G(SCH_1):SVID_PVDDCR_CPU1_P0_SVC':
 C_SIGNAL='@t6g_mb_lib.t6g(sch_1):svid_pvddcr_cpu1_p0_svc';
NODE_NAME     U25 DJ72
 '@T6G_MB_LIB.T6G(SCH_1):PAGE27_I227@PURE_QUANTA.GENOA_SP5(CHIPS)':
 'SVC1': CDS_PINID='SVC1';
NODE_NAME     PR59 2
 '@T6G_MB_LIB.T6G(SCH_1):PAGE27_I318@PURE_QUANTA.Q_RES(CHIPS)':
 'B': CDS_PINID='B';
NET_NAME
'SVID_PVDDCR_CPU1_P0_SVC_R'
 '@T6G_MB_LIB.T6G(SCH_1):SVID_PVDDCR_CPU1_P0_SVC_R':
 C_SIGNAL='@t6g_mb_lib.t6g(sch_1):svid_pvddcr_cpu1_p0_svc_r';
NODE_NAME     PR59 1
 '@T6G_MB_LIB.T6G(SCH_1):PAGE27_I318@PURE_QUANTA.Q_RES(CHIPS)':
 'A': CDS_PINID='A';
NODE_NAME     C305 1
 '@T6G_MB_LIB.T6G(SCH_1):PAGE175_I35@PURE_QUANTA.Q_CAP(CHIPS)':
 'A': CDS_PINID='A';
NODE_NAME     R8048 2
 '@T6G_MB_LIB.T6G(SCH_1):PAGE175_I44@PURE_QUANTA.Q_RES(CHIPS)':
 'B': CDS_PINID='B';
NODE_NAME     PR8007 1
 '@T6G_MB_LIB.T6G(SCH_1):PAGE175_I137@PURE_QUANTA.Q_RES(CHIPS)':
 'A': CDS_PINID='A';
NET_NAME
'SVID_PVDDCR_CPU1_P0_SVC_R1'
 '@T6G_MB_LIB.T6G(SCH_1):SVID_PVDDCR_CPU1_P0_SVC_R1':
 C_SIGNAL='@t6g_mb_lib.t6g(sch_1):svid_pvddcr_cpu1_p0_svc_r1';
NODE_NAME     PU12 22
 '@T6G_MB_LIB.T6G(SCH_1):PAGE175_I128@PURE_QUANTA.RAA229620GNPHA0(CHIPS)':
 'SVC': CDS_PINID='SVC';
NODE_NAME     PR8007 2
 '@T6G_MB_LIB.T6G(SCH_1):PAGE175_I137@PURE_QUANTA.Q_RES(CHIPS)':
 'B': CDS_PINID='B';
NET_NAME
'SVID_PVDDCR_CPU1_P0_SVD'
 '@T6G_MB_LIB.T6G(SCH_1):SVID_PVDDCR_CPU1_P0_SVD':
 C_SIGNAL='@t6g_mb_lib.t6g(sch_1):svid_pvddcr_cpu1_p0_svd';
NODE_NAME     U25 DH72
 '@T6G_MB_LIB.T6G(SCH_1):PAGE27_I227@PURE_QUANTA.GENOA_SP5(CHIPS)':
 'SVD1': CDS_PINID='SVD1';
NODE_NAME     PR60 2
 '@T6G_MB_LIB.T6G(SCH_1):PAGE27_I319@PURE_QUANTA.Q_RES(CHIPS)':
 'B': CDS_PINID='B';
NET_NAME
'SVID_PVDDCR_CPU1_P0_SVD_R'
 '@T6G_MB_LIB.T6G(SCH_1):SVID_PVDDCR_CPU1_P0_SVD_R':
 C_SIGNAL='@t6g_mb_lib.t6g(sch_1):svid_pvddcr_cpu1_p0_svd_r';
NODE_NAME     PR60 1
 '@T6G_MB_LIB.T6G(SCH_1):PAGE27_I319@PURE_QUANTA.Q_RES(CHIPS)':
 'A': CDS_PINID='A';
NODE_NAME     C304 1
 '@T6G_MB_LIB.T6G(SCH_1):PAGE175_I34@PURE_QUANTA.Q_CAP(CHIPS)':
 'A': CDS_PINID='A';
NODE_NAME     R8045 2
 '@T6G_MB_LIB.T6G(SCH_1):PAGE175_I43@PURE_QUANTA.Q_RES(CHIPS)':
 'B': CDS_PINID='B';
NODE_NAME     PR8008 1
 '@T6G_MB_LIB.T6G(SCH_1):PAGE175_I136@PURE_QUANTA.Q_RES(CHIPS)':
 'A': CDS_PINID='A';
NET_NAME
'SVID_PVDDCR_CPU1_P0_SVD_R1'
 '@T6G_MB_LIB.T6G(SCH_1):SVID_PVDDCR_CPU1_P0_SVD_R1':
 C_SIGNAL='@t6g_mb_lib.t6g(sch_1):svid_pvddcr_cpu1_p0_svd_r1';
NODE_NAME     PU12 21
 '@T6G_MB_LIB.T6G(SCH_1):PAGE175_I128@PURE_QUANTA.RAA229620GNPHA0(CHIPS)':
 'SVD': CDS_PINID='SVD';
NODE_NAME     PR8008 2
 '@T6G_MB_LIB.T6G(SCH_1):PAGE175_I136@PURE_QUANTA.Q_RES(CHIPS)':
 'B': CDS_PINID='B';
NET_NAME
'SVID_PVDDCR_CPU1_P0_SVTI'
 '@T6G_MB_LIB.T6G(SCH_1):SVID_PVDDCR_CPU1_P0_SVTI':
 C_SIGNAL='@t6g_mb_lib.t6g(sch_1):svid_pvddcr_cpu1_p0_svti';
NODE_NAME     PR40 1
 '@T6G_MB_LIB.T6G(SCH_1):PAGE175_I28@PURE_QUANTA.Q_RES(CHIPS)':
 'A': CDS_PINID='A';
NODE_NAME     PR41 2
 '@T6G_MB_LIB.T6G(SCH_1):PAGE175_I40@PURE_QUANTA.Q_RES(CHIPS)':
 'B': CDS_PINID='B';
NODE_NAME     PR62 1
 '@T6G_MB_LIB.T6G(SCH_1):PAGE175_I84@PURE_QUANTA.Q_RES(CHIPS)':
 'A': CDS_PINID='A';
NET_NAME
'SVID_PVDDCR_CPU1_P0_SVTI_R'
 '@T6G_MB_LIB.T6G(SCH_1):SVID_PVDDCR_CPU1_P0_SVTI_R':
 C_SIGNAL='@t6g_mb_lib.t6g(sch_1):svid_pvddcr_cpu1_p0_svti_r';
NODE_NAME     PR62 2
 '@T6G_MB_LIB.T6G(SCH_1):PAGE175_I84@PURE_QUANTA.Q_RES(CHIPS)':
 'B': CDS_PINID='B';
NODE_NAME     PU12 24
 '@T6G_MB_LIB.T6G(SCH_1):PAGE175_I128@PURE_QUANTA.RAA229620GNPHA0(CHIPS)':
 'SVTI': CDS_PINID='SVTI';
NET_NAME
'SVID_PVDDCR_CPU1_P0_SVTO'
 '@T6G_MB_LIB.T6G(SCH_1):SVID_PVDDCR_CPU1_P0_SVTO':
 C_SIGNAL='@t6g_mb_lib.t6g(sch_1):svid_pvddcr_cpu1_p0_svto';
NODE_NAME     U25 DG73
 '@T6G_MB_LIB.T6G(SCH_1):PAGE27_I227@PURE_QUANTA.GENOA_SP5(CHIPS)':
 'SVT1': CDS_PINID='SVT1';
NODE_NAME     R8042 1
 '@T6G_MB_LIB.T6G(SCH_1):PAGE175_I32@PURE_QUANTA.Q_RES(CHIPS)':
 'A': CDS_PINID='A';
NODE_NAME     C303 1
 '@T6G_MB_LIB.T6G(SCH_1):PAGE175_I33@PURE_QUANTA.Q_CAP(CHIPS)':
 'A': CDS_PINID='A';
NODE_NAME     R8043 2
 '@T6G_MB_LIB.T6G(SCH_1):PAGE175_I42@PURE_QUANTA.Q_RES(CHIPS)':
 'B': CDS_PINID='B';
NODE_NAME     R61 1
 '@T6G_MB_LIB.T6G(SCH_1):PAGE175_I83@PURE_QUANTA.Q_RES(CHIPS)':
 'A': CDS_PINID='A';
NET_NAME
'SVID_PVDDCR_CPU1_P0_SVTO_R'
 '@T6G_MB_LIB.T6G(SCH_1):SVID_PVDDCR_CPU1_P0_SVTO_R':
 C_SIGNAL='@t6g_mb_lib.t6g(sch_1):svid_pvddcr_cpu1_p0_svto_r';
NODE_NAME     R61 2
 '@T6G_MB_LIB.T6G(SCH_1):PAGE175_I83@PURE_QUANTA.Q_RES(CHIPS)':
 'B': CDS_PINID='B';
NODE_NAME     PU12 23
 '@T6G_MB_LIB.T6G(SCH_1):PAGE175_I128@PURE_QUANTA.RAA229620GNPHA0(CHIPS)':
 'SVTO': CDS_PINID='SVTO';
NET_NAME
'SVID_PVDDCR_CPU1_P1_SVC'
 '@T6G_MB_LIB.T6G(SCH_1):SVID_PVDDCR_CPU1_P1_SVC':
 C_SIGNAL='@t6g_mb_lib.t6g(sch_1):svid_pvddcr_cpu1_p1_svc';
NODE_NAME     U26 DJ72
 '@T6G_MB_LIB.T6G(SCH_1):PAGE54_I190@PURE_QUANTA.GENOA_SP5(CHIPS)':
 'SVC1': CDS_PINID='SVC1';
NODE_NAME     PR236 2
 '@T6G_MB_LIB.T6G(SCH_1):PAGE54_I338@PURE_QUANTA.Q_RES(CHIPS)':
 'B': CDS_PINID='B';
NET_NAME
'SVID_PVDDCR_CPU1_P1_SVC_R'
 '@T6G_MB_LIB.T6G(SCH_1):SVID_PVDDCR_CPU1_P1_SVC_R':
 C_SIGNAL='@t6g_mb_lib.t6g(sch_1):svid_pvddcr_cpu1_p1_svc_r';
NODE_NAME     PR236 1
 '@T6G_MB_LIB.T6G(SCH_1):PAGE54_I338@PURE_QUANTA.Q_RES(CHIPS)':
 'A': CDS_PINID='A';
NODE_NAME     C310 1
 '@T6G_MB_LIB.T6G(SCH_1):PAGE192_I33@PURE_QUANTA.Q_CAP(CHIPS)':
 'A': CDS_PINID='A';
NODE_NAME     R8225 2
 '@T6G_MB_LIB.T6G(SCH_1):PAGE192_I42@PURE_QUANTA.Q_RES(CHIPS)':
 'B': CDS_PINID='B';
NODE_NAME     PR8011 1
 '@T6G_MB_LIB.T6G(SCH_1):PAGE192_I137@PURE_QUANTA.Q_RES(CHIPS)':
 'A': CDS_PINID='A';
NET_NAME
'SVID_PVDDCR_CPU1_P1_SVC_R1'
 '@T6G_MB_LIB.T6G(SCH_1):SVID_PVDDCR_CPU1_P1_SVC_R1':
 C_SIGNAL='@t6g_mb_lib.t6g(sch_1):svid_pvddcr_cpu1_p1_svc_r1';
NODE_NAME     PU34 22
 '@T6G_MB_LIB.T6G(SCH_1):PAGE192_I128@PURE_QUANTA.RAA229620GNPHA0(CHIPS)':
 'SVC': CDS_PINID='SVC';
NODE_NAME     PR8011 2
 '@T6G_MB_LIB.T6G(SCH_1):PAGE192_I137@PURE_QUANTA.Q_RES(CHIPS)':
 'B': CDS_PINID='B';
NET_NAME
'SVID_PVDDCR_CPU1_P1_SVD'
 '@T6G_MB_LIB.T6G(SCH_1):SVID_PVDDCR_CPU1_P1_SVD':
 C_SIGNAL='@t6g_mb_lib.t6g(sch_1):svid_pvddcr_cpu1_p1_svd';
NODE_NAME     U26 DH72
 '@T6G_MB_LIB.T6G(SCH_1):PAGE54_I190@PURE_QUANTA.GENOA_SP5(CHIPS)':
 'SVD1': CDS_PINID='SVD1';
NODE_NAME     PR237 2
 '@T6G_MB_LIB.T6G(SCH_1):PAGE54_I337@PURE_QUANTA.Q_RES(CHIPS)':
 'B': CDS_PINID='B';
NET_NAME
'SVID_PVDDCR_CPU1_P1_SVD_R'
 '@T6G_MB_LIB.T6G(SCH_1):SVID_PVDDCR_CPU1_P1_SVD_R':
 C_SIGNAL='@t6g_mb_lib.t6g(sch_1):svid_pvddcr_cpu1_p1_svd_r';
NODE_NAME     PR237 1
 '@T6G_MB_LIB.T6G(SCH_1):PAGE54_I337@PURE_QUANTA.Q_RES(CHIPS)':
 'A': CDS_PINID='A';
NODE_NAME     C309 1
 '@T6G_MB_LIB.T6G(SCH_1):PAGE192_I32@PURE_QUANTA.Q_CAP(CHIPS)':
 'A': CDS_PINID='A';
NODE_NAME     R8222 2
 '@T6G_MB_LIB.T6G(SCH_1):PAGE192_I41@PURE_QUANTA.Q_RES(CHIPS)':
 'B': CDS_PINID='B';
NODE_NAME     PR8012 1
 '@T6G_MB_LIB.T6G(SCH_1):PAGE192_I138@PURE_QUANTA.Q_RES(CHIPS)':
 'A': CDS_PINID='A';
NET_NAME
'SVID_PVDDCR_CPU1_P1_SVD_R1'
 '@T6G_MB_LIB.T6G(SCH_1):SVID_PVDDCR_CPU1_P1_SVD_R1':
 C_SIGNAL='@t6g_mb_lib.t6g(sch_1):svid_pvddcr_cpu1_p1_svd_r1';
NODE_NAME     PU34 21
 '@T6G_MB_LIB.T6G(SCH_1):PAGE192_I128@PURE_QUANTA.RAA229620GNPHA0(CHIPS)':
 'SVD': CDS_PINID='SVD';
NODE_NAME     PR8012 2
 '@T6G_MB_LIB.T6G(SCH_1):PAGE192_I138@PURE_QUANTA.Q_RES(CHIPS)':
 'B': CDS_PINID='B';
NET_NAME
'SVID_PVDDCR_CPU1_P1_SVTI'
 '@T6G_MB_LIB.T6G(SCH_1):SVID_PVDDCR_CPU1_P1_SVTI':
 C_SIGNAL='@t6g_mb_lib.t6g(sch_1):svid_pvddcr_cpu1_p1_svti';
NODE_NAME     PR217 1
 '@T6G_MB_LIB.T6G(SCH_1):PAGE192_I29@PURE_QUANTA.Q_RES(CHIPS)':
 'A': CDS_PINID='A';
NODE_NAME     PR218 2
 '@T6G_MB_LIB.T6G(SCH_1):PAGE192_I38@PURE_QUANTA.Q_RES(CHIPS)':
 'B': CDS_PINID='B';
NODE_NAME     PR239 1
 '@T6G_MB_LIB.T6G(SCH_1):PAGE192_I83@PURE_QUANTA.Q_RES(CHIPS)':
 'A': CDS_PINID='A';
NET_NAME
'SVID_PVDDCR_CPU1_P1_SVTI_R'
 '@T6G_MB_LIB.T6G(SCH_1):SVID_PVDDCR_CPU1_P1_SVTI_R':
 C_SIGNAL='@t6g_mb_lib.t6g(sch_1):svid_pvddcr_cpu1_p1_svti_r';
NODE_NAME     PR239 2
 '@T6G_MB_LIB.T6G(SCH_1):PAGE192_I83@PURE_QUANTA.Q_RES(CHIPS)':
 'B': CDS_PINID='B';
NODE_NAME     PU34 24
 '@T6G_MB_LIB.T6G(SCH_1):PAGE192_I128@PURE_QUANTA.RAA229620GNPHA0(CHIPS)':
 'SVTI': CDS_PINID='SVTI';
NET_NAME
'SVID_PVDDCR_CPU1_P1_SVTO'
 '@T6G_MB_LIB.T6G(SCH_1):SVID_PVDDCR_CPU1_P1_SVTO':
 C_SIGNAL='@t6g_mb_lib.t6g(sch_1):svid_pvddcr_cpu1_p1_svto';
NODE_NAME     U26 DG73
 '@T6G_MB_LIB.T6G(SCH_1):PAGE54_I190@PURE_QUANTA.GENOA_SP5(CHIPS)':
 'SVT1': CDS_PINID='SVT1';
NODE_NAME     R8219 1
 '@T6G_MB_LIB.T6G(SCH_1):PAGE192_I30@PURE_QUANTA.Q_RES(CHIPS)':
 'A': CDS_PINID='A';
NODE_NAME     C308 1
 '@T6G_MB_LIB.T6G(SCH_1):PAGE192_I31@PURE_QUANTA.Q_CAP(CHIPS)':
 'A': CDS_PINID='A';
NODE_NAME     R8220 2
 '@T6G_MB_LIB.T6G(SCH_1):PAGE192_I40@PURE_QUANTA.Q_RES(CHIPS)':
 'B': CDS_PINID='B';
NODE_NAME     R8238 1
 '@T6G_MB_LIB.T6G(SCH_1):PAGE192_I82@PURE_QUANTA.Q_RES(CHIPS)':
 'A': CDS_PINID='A';
NET_NAME
'SVID_PVDDCR_CPU1_P1_SVTO_R'
 '@T6G_MB_LIB.T6G(SCH_1):SVID_PVDDCR_CPU1_P1_SVTO_R':
 C_SIGNAL='@t6g_mb_lib.t6g(sch_1):svid_pvddcr_cpu1_p1_svto_r';
NODE_NAME     R8238 2
 '@T6G_MB_LIB.T6G(SCH_1):PAGE192_I82@PURE_QUANTA.Q_RES(CHIPS)':
 'B': CDS_PINID='B';
NODE_NAME     PU34 23
 '@T6G_MB_LIB.T6G(SCH_1):PAGE192_I128@PURE_QUANTA.RAA229620GNPHA0(CHIPS)':
 'SVTO': CDS_PINID='SVTO';
NET_NAME
'SWB_HSC_EN'
 '@T6G_MB_LIB.T6G(SCH_1):SWB_HSC_EN':
 C_SIGNAL='@t6g_mb_lib.t6g(sch_1):swb_hsc_en';
NODE_NAME     U316 1
 '@T6G_MB_LIB.T6G(SCH_1):PAGE331_I86@PURE_QUANTA.74LVC2G17GW(CHIPS)':
 'A0': CDS_PINID='A0';
NODE_NAME     R4548 1
 '@T6G_MB_LIB.T6G(SCH_1):PAGE331_I87@PURE_QUANTA.Q_RES(CHIPS)':
 'A': CDS_PINID='A';
NODE_NAME     R4547 2
 '@T6G_MB_LIB.T6G(SCH_1):PAGE331_I89@PURE_QUANTA.Q_RES(CHIPS)':
 'B': CDS_PINID='B';
NODE_NAME     R4558 2
 '@T6G_MB_LIB.T6G(SCH_1):PAGE80_I228@PURE_QUANTA.Q_RES(CHIPS)':
 'B': CDS_PINID='B';
NET_NAME
'SWB_HSC_EN_BUF'
 '@T6G_MB_LIB.T6G(SCH_1):SWB_HSC_EN_BUF':
 C_SIGNAL='@t6g_mb_lib.t6g(sch_1):swb_hsc_en_buf';
NODE_NAME     R4550 2
 '@T6G_MB_LIB.T6G(SCH_1):PAGE331_I97@PURE_QUANTA.Q_RES(CHIPS)':
 'B': CDS_PINID='B';
NODE_NAME     J107 N8
 '@T6G_MB_LIB.T6G(SCH_1):PAGE317_I70@PURE_QUANTA.CONN112_10137002101LF(CHIPS)':
 'N8': CDS_PINID='N8';
NET_NAME
'SWB_HSC_EN_BUF_R'
 '@T6G_MB_LIB.T6G(SCH_1):SWB_HSC_EN_BUF_R':
 C_SIGNAL='@t6g_mb_lib.t6g(sch_1):swb_hsc_en_buf_r';
NODE_NAME     U316 6
 '@T6G_MB_LIB.T6G(SCH_1):PAGE331_I86@PURE_QUANTA.74LVC2G17GW(CHIPS)':
 'B0': CDS_PINID='B0';
NODE_NAME     R4550 1
 '@T6G_MB_LIB.T6G(SCH_1):PAGE331_I97@PURE_QUANTA.Q_RES(CHIPS)':
 'A': CDS_PINID='A';
NODE_NAME     R4549 2
 '@T6G_MB_LIB.T6G(SCH_1):PAGE331_I98@PURE_QUANTA.Q_RES(CHIPS)':
 'B': CDS_PINID='B';
NODE_NAME     R4555 1
 '@T6G_MB_LIB.T6G(SCH_1):PAGE331_I99@PURE_QUANTA.Q_RES(CHIPS)':
 'A': CDS_PINID='A';
NET_NAME
'SWB_HSC_EN_R'
 '@T6G_MB_LIB.T6G(SCH_1):SWB_HSC_EN_R':
 C_SIGNAL='@t6g_mb_lib.t6g(sch_1):swb_hsc_en_r';
NODE_NAME     U18 Y13
 '@T6G_MB_LIB.T6G(SCH_1):PAGE80_I216@PURE_QUANTA.LCMXO3LF9400C5BG484C(CHIPS)':
 'PB30C': CDS_PINID='PB30C';
NODE_NAME     R4558 1
 '@T6G_MB_LIB.T6G(SCH_1):PAGE80_I228@PURE_QUANTA.Q_RES(CHIPS)':
 'A': CDS_PINID='A';
NET_NAME
'SWB_HSC_PWRGD'
 '@T6G_MB_LIB.T6G(SCH_1):SWB_HSC_PWRGD':
 C_SIGNAL='@t6g_mb_lib.t6g(sch_1):swb_hsc_pwrgd';
NODE_NAME     J107 A7
 '@T6G_MB_LIB.T6G(SCH_1):PAGE317_I70@PURE_QUANTA.CONN112_10137002101LF(CHIPS)':
 'A7': CDS_PINID='A7';
NODE_NAME     R4559 1
 '@T6G_MB_LIB.T6G(SCH_1):PAGE332_I54@PURE_QUANTA.Q_RES(CHIPS)':
 'A': CDS_PINID='A';
NODE_NAME     R4562 2
 '@T6G_MB_LIB.T6G(SCH_1):PAGE332_I55@PURE_QUANTA.Q_RES(CHIPS)':
 'B': CDS_PINID='B';
NODE_NAME     Q146 2
 '@T6G_MB_LIB.T6G(SCH_1):PAGE332_I57@PURE_QUANTA.MOSFET_NCH_DUAL(CHIPS)':
 'G1': CDS_PINID='G1';
NET_NAME
'SWB_HSC_PWRGD_ISO'
 '@T6G_MB_LIB.T6G(SCH_1):SWB_HSC_PWRGD_ISO':
 C_SIGNAL='@t6g_mb_lib.t6g(sch_1):swb_hsc_pwrgd_iso';
NODE_NAME     R4563 2
 '@T6G_MB_LIB.T6G(SCH_1):PAGE80_I243@PURE_QUANTA.Q_RES(CHIPS)':
 'B': CDS_PINID='B';
NODE_NAME     C18 1
 '@T6G_MB_LIB.T6G(SCH_1):PAGE332_I61@PURE_QUANTA.Q_CAP(CHIPS)':
 'A': CDS_PINID='A';
NODE_NAME     R4561 2
 '@T6G_MB_LIB.T6G(SCH_1):PAGE332_I110@PURE_QUANTA.Q_RES(CHIPS)':
 'B': CDS_PINID='B';
NODE_NAME     Q146 3
 '@T6G_MB_LIB.T6G(SCH_1):PAGE332_I134@PURE_QUANTA.MOSFET_NCH_DUAL(CHIPS)':
 'D2': CDS_PINID='D2';
NET_NAME
'SWB_HSC_PWRGD_ISO_R'
 '@T6G_MB_LIB.T6G(SCH_1):SWB_HSC_PWRGD_ISO_R':
 C_SIGNAL='@t6g_mb_lib.t6g(sch_1):swb_hsc_pwrgd_iso_r';
NODE_NAME     U18 Y14
 '@T6G_MB_LIB.T6G(SCH_1):PAGE80_I216@PURE_QUANTA.LCMXO3LF9400C5BG484C(CHIPS)':
 'PB33C': CDS_PINID='PB33C';
NODE_NAME     R4563 1
 '@T6G_MB_LIB.T6G(SCH_1):PAGE80_I243@PURE_QUANTA.Q_RES(CHIPS)':
 'A': CDS_PINID='A';
NET_NAME
'SWB_HSC_PWRGD_N'
 '@T6G_MB_LIB.T6G(SCH_1):SWB_HSC_PWRGD_N':
 C_SIGNAL='@t6g_mb_lib.t6g(sch_1):swb_hsc_pwrgd_n';
NODE_NAME     Q146 6
 '@T6G_MB_LIB.T6G(SCH_1):PAGE332_I57@PURE_QUANTA.MOSFET_NCH_DUAL(CHIPS)':
 'D1': CDS_PINID='D1';
NODE_NAME     R4560 2
 '@T6G_MB_LIB.T6G(SCH_1):PAGE332_I62@PURE_QUANTA.Q_RES(CHIPS)':
 'B': CDS_PINID='B';
NODE_NAME     Q146 5
 '@T6G_MB_LIB.T6G(SCH_1):PAGE332_I134@PURE_QUANTA.MOSFET_NCH_DUAL(CHIPS)':
 'G2': CDS_PINID='G2';
NET_NAME
'SW_P0V9_RETIMER_CPU0_BOOT1'
 '@T6G_MB_LIB.T6G(SCH_1):SW_P0V9_RETIMER_CPU0_BOOT1':
 C_SIGNAL='@t6g_mb_lib.t6g(sch_1):sw_p0v9_retimer_cpu0_boot1';
NODE_NAME     PU6503 33
 '@T6G_MB_LIB.T6G(SCH_1):PAGE476_I53@PURE_QUANTA.ISL99390FRZTR5935(CHIPS)':
 'BOOT': CDS_PINID='BOOT';
NODE_NAME     PR6554 1
 '@T6G_MB_LIB.T6G(SCH_1):PAGE476_I221@PURE_QUANTA.Q_RES(CHIPS)':
 'A': CDS_PINID='A';
NET_NAME
'SW_P0V9_RETIMER_CPU0_BOOT1_RC'
 '@T6G_MB_LIB.T6G(SCH_1):SW_P0V9_RETIMER_CPU0_BOOT1_RC':
 C_SIGNAL='@t6g_mb_lib.t6g(sch_1):sw_p0v9_retimer_cpu0_boot1_rc';
NODE_NAME     PC6563 1
 '@T6G_MB_LIB.T6G(SCH_1):PAGE476_I30@PURE_QUANTA.Q_CAP(CHIPS)':
 'A': CDS_PINID='A';
NODE_NAME     PR6554 2
 '@T6G_MB_LIB.T6G(SCH_1):PAGE476_I221@PURE_QUANTA.Q_RES(CHIPS)':
 'B': CDS_PINID='B';
NET_NAME
'SW_P0V9_RETIMER_CPU0_BOOT2'
 '@T6G_MB_LIB.T6G(SCH_1):SW_P0V9_RETIMER_CPU0_BOOT2':
 C_SIGNAL='@t6g_mb_lib.t6g(sch_1):sw_p0v9_retimer_cpu0_boot2';
NODE_NAME     PR6562 1
 '@T6G_MB_LIB.T6G(SCH_1):PAGE476_I262@PURE_QUANTA.Q_RES(CHIPS)':
 'A': CDS_PINID='A';
NODE_NAME     PU6504 33
 '@T6G_MB_LIB.T6G(SCH_1):PAGE476_I270@PURE_QUANTA.ISL99390FRZTR5935(CHIPS)':
 'BOOT': CDS_PINID='BOOT';
NET_NAME
'SW_P0V9_RETIMER_CPU0_BOOT2_RC'
 '@T6G_MB_LIB.T6G(SCH_1):SW_P0V9_RETIMER_CPU0_BOOT2_RC':
 C_SIGNAL='@t6g_mb_lib.t6g(sch_1):sw_p0v9_retimer_cpu0_boot2_rc';
NODE_NAME     PC6584 1
 '@T6G_MB_LIB.T6G(SCH_1):PAGE476_I253@PURE_QUANTA.Q_CAP(CHIPS)':
 'A': CDS_PINID='A';
NODE_NAME     PR6562 2
 '@T6G_MB_LIB.T6G(SCH_1):PAGE476_I262@PURE_QUANTA.Q_RES(CHIPS)':
 'B': CDS_PINID='B';
NET_NAME
'SW_P0V9_RETIMER_CPU0_PH1'
 '@T6G_MB_LIB.T6G(SCH_1):SW_P0V9_RETIMER_CPU0_PH1':
 C_SIGNAL='@t6g_mb_lib.t6g(sch_1):sw_p0v9_retimer_cpu0_ph1';
NODE_NAME     PC6563 2
 '@T6G_MB_LIB.T6G(SCH_1):PAGE476_I30@PURE_QUANTA.Q_CAP(CHIPS)':
 'B': CDS_PINID='B';
NODE_NAME     PU6503 32
 '@T6G_MB_LIB.T6G(SCH_1):PAGE476_I53@PURE_QUANTA.ISL99390FRZTR5935(CHIPS)':
 'PHASE': CDS_PINID='PHASE';
NET_NAME
'SW_P0V9_RETIMER_CPU0_PH2'
 '@T6G_MB_LIB.T6G(SCH_1):SW_P0V9_RETIMER_CPU0_PH2':
 C_SIGNAL='@t6g_mb_lib.t6g(sch_1):sw_p0v9_retimer_cpu0_ph2';
NODE_NAME     PC6584 2
 '@T6G_MB_LIB.T6G(SCH_1):PAGE476_I253@PURE_QUANTA.Q_CAP(CHIPS)':
 'B': CDS_PINID='B';
NODE_NAME     PU6504 32
 '@T6G_MB_LIB.T6G(SCH_1):PAGE476_I270@PURE_QUANTA.ISL99390FRZTR5935(CHIPS)':
 'PHASE': CDS_PINID='PHASE';
NET_NAME
'SW_P0V9_RETIMER_CPU0_SW1'
 '@T6G_MB_LIB.T6G(SCH_1):SW_P0V9_RETIMER_CPU0_SW1':
 C_SIGNAL='@t6g_mb_lib.t6g(sch_1):sw_p0v9_retimer_cpu0_sw1';
NODE_NAME     PL6505 1
 '@T6G_MB_LIB.T6G(SCH_1):PAGE476_I34@PURE_QUANTA.Q_INDUCTOR(CHIPS)':
 '1': CDS_PINID='\1\';
NODE_NAME     PU6503 10_19
 '@T6G_MB_LIB.T6G(SCH_1):PAGE476_I53@PURE_QUANTA.ISL99390FRZTR5935(CHIPS)':
 'SW': CDS_PINID='SW';
NODE_NAME     PC6564 1
 '@T6G_MB_LIB.T6G(SCH_1):PAGE476_I285@PURE_QUANTA.Q_CAP(CHIPS)':
 'A': CDS_PINID='A';
NET_NAME
'SW_P0V9_RETIMER_CPU0_SW1_RC'
 '@T6G_MB_LIB.T6G(SCH_1):SW_P0V9_RETIMER_CPU0_SW1_RC':
 C_SIGNAL='@t6g_mb_lib.t6g(sch_1):sw_p0v9_retimer_cpu0_sw1_rc';
NODE_NAME     PR6555 1
 '@T6G_MB_LIB.T6G(SCH_1):PAGE476_I283@PURE_QUANTA.Q_RES(CHIPS)':
 'A': CDS_PINID='A';
NODE_NAME     PC6564 2
 '@T6G_MB_LIB.T6G(SCH_1):PAGE476_I285@PURE_QUANTA.Q_CAP(CHIPS)':
 'B': CDS_PINID='B';
NET_NAME
'SW_P0V9_RETIMER_CPU0_SW2'
 '@T6G_MB_LIB.T6G(SCH_1):SW_P0V9_RETIMER_CPU0_SW2':
 C_SIGNAL='@t6g_mb_lib.t6g(sch_1):sw_p0v9_retimer_cpu0_sw2';
NODE_NAME     PL6506 1
 '@T6G_MB_LIB.T6G(SCH_1):PAGE476_I257@PURE_QUANTA.Q_INDUCTOR(CHIPS)':
 '1': CDS_PINID='\1\';
NODE_NAME     PU6504 10_19
 '@T6G_MB_LIB.T6G(SCH_1):PAGE476_I270@PURE_QUANTA.ISL99390FRZTR5935(CHIPS)':
 'SW': CDS_PINID='SW';
NODE_NAME     PC6585 1
 '@T6G_MB_LIB.T6G(SCH_1):PAGE476_I288@PURE_QUANTA.Q_CAP(CHIPS)':
 'A': CDS_PINID='A';
NET_NAME
'SW_P0V9_RETIMER_CPU0_SW2_RC'
 '@T6G_MB_LIB.T6G(SCH_1):SW_P0V9_RETIMER_CPU0_SW2_RC':
 C_SIGNAL='@t6g_mb_lib.t6g(sch_1):sw_p0v9_retimer_cpu0_sw2_rc';
NODE_NAME     PR6563 1
 '@T6G_MB_LIB.T6G(SCH_1):PAGE476_I286@PURE_QUANTA.Q_RES(CHIPS)':
 'A': CDS_PINID='A';
NODE_NAME     PC6585 2
 '@T6G_MB_LIB.T6G(SCH_1):PAGE476_I288@PURE_QUANTA.Q_CAP(CHIPS)':
 'B': CDS_PINID='B';
NET_NAME
'SW_P0V9_RETIMER_CPU1_BOOT1'
 '@T6G_MB_LIB.T6G(SCH_1):SW_P0V9_RETIMER_CPU1_BOOT1':
 C_SIGNAL='@t6g_mb_lib.t6g(sch_1):sw_p0v9_retimer_cpu1_boot1';
NODE_NAME     PU6511 33
 '@T6G_MB_LIB.T6G(SCH_1):PAGE478_I51@PURE_QUANTA.ISL99390FRZTR5935(CHIPS)':
 'BOOT': CDS_PINID='BOOT';
NODE_NAME     PR6623 1
 '@T6G_MB_LIB.T6G(SCH_1):PAGE478_I62@PURE_QUANTA.Q_RES(CHIPS)':
 'A': CDS_PINID='A';
NET_NAME
'SW_P0V9_RETIMER_CPU1_BOOT1_RC'
 '@T6G_MB_LIB.T6G(SCH_1):SW_P0V9_RETIMER_CPU1_BOOT1_RC':
 C_SIGNAL='@t6g_mb_lib.t6g(sch_1):sw_p0v9_retimer_cpu1_boot1_rc';
NODE_NAME     PR6623 2
 '@T6G_MB_LIB.T6G(SCH_1):PAGE478_I62@PURE_QUANTA.Q_RES(CHIPS)':
 'B': CDS_PINID='B';
NODE_NAME     PC6621 1
 '@T6G_MB_LIB.T6G(SCH_1):PAGE478_I76@PURE_QUANTA.Q_CAP(CHIPS)':
 'A': CDS_PINID='A';
NET_NAME
'SW_P0V9_RETIMER_CPU1_BOOT2'
 '@T6G_MB_LIB.T6G(SCH_1):SW_P0V9_RETIMER_CPU1_BOOT2':
 C_SIGNAL='@t6g_mb_lib.t6g(sch_1):sw_p0v9_retimer_cpu1_boot2';
NODE_NAME     PU6512 33
 '@T6G_MB_LIB.T6G(SCH_1):PAGE478_I12@PURE_QUANTA.ISL99390FRZTR5935(CHIPS)':
 'BOOT': CDS_PINID='BOOT';
NODE_NAME     PR6629 1
 '@T6G_MB_LIB.T6G(SCH_1):PAGE478_I19@PURE_QUANTA.Q_RES(CHIPS)':
 'A': CDS_PINID='A';
NET_NAME
'SW_P0V9_RETIMER_CPU1_BOOT2_RC'
 '@T6G_MB_LIB.T6G(SCH_1):SW_P0V9_RETIMER_CPU1_BOOT2_RC':
 C_SIGNAL='@t6g_mb_lib.t6g(sch_1):sw_p0v9_retimer_cpu1_boot2_rc';
NODE_NAME     PR6629 2
 '@T6G_MB_LIB.T6G(SCH_1):PAGE478_I19@PURE_QUANTA.Q_RES(CHIPS)':
 'B': CDS_PINID='B';
NODE_NAME     PC6640 1
 '@T6G_MB_LIB.T6G(SCH_1):PAGE478_I26@PURE_QUANTA.Q_CAP(CHIPS)':
 'A': CDS_PINID='A';
NET_NAME
'SW_P0V9_RETIMER_CPU1_PH1'
 '@T6G_MB_LIB.T6G(SCH_1):SW_P0V9_RETIMER_CPU1_PH1':
 C_SIGNAL='@t6g_mb_lib.t6g(sch_1):sw_p0v9_retimer_cpu1_ph1';
NODE_NAME     PU6511 32
 '@T6G_MB_LIB.T6G(SCH_1):PAGE478_I51@PURE_QUANTA.ISL99390FRZTR5935(CHIPS)':
 'PHASE': CDS_PINID='PHASE';
NODE_NAME     PC6621 2
 '@T6G_MB_LIB.T6G(SCH_1):PAGE478_I76@PURE_QUANTA.Q_CAP(CHIPS)':
 'B': CDS_PINID='B';
NET_NAME
'SW_P0V9_RETIMER_CPU1_PH2'
 '@T6G_MB_LIB.T6G(SCH_1):SW_P0V9_RETIMER_CPU1_PH2':
 C_SIGNAL='@t6g_mb_lib.t6g(sch_1):sw_p0v9_retimer_cpu1_ph2';
NODE_NAME     PU6512 32
 '@T6G_MB_LIB.T6G(SCH_1):PAGE478_I12@PURE_QUANTA.ISL99390FRZTR5935(CHIPS)':
 'PHASE': CDS_PINID='PHASE';
NODE_NAME     PC6640 2
 '@T6G_MB_LIB.T6G(SCH_1):PAGE478_I26@PURE_QUANTA.Q_CAP(CHIPS)':
 'B': CDS_PINID='B';
NET_NAME
'SW_P0V9_RETIMER_CPU1_SW1'
 '@T6G_MB_LIB.T6G(SCH_1):SW_P0V9_RETIMER_CPU1_SW1':
 C_SIGNAL='@t6g_mb_lib.t6g(sch_1):sw_p0v9_retimer_cpu1_sw1';
NODE_NAME     PU6511 10_19
 '@T6G_MB_LIB.T6G(SCH_1):PAGE478_I51@PURE_QUANTA.ISL99390FRZTR5935(CHIPS)':
 'SW': CDS_PINID='SW';
NODE_NAME     PL6511 1
 '@T6G_MB_LIB.T6G(SCH_1):PAGE478_I65@PURE_QUANTA.Q_INDUCTOR(CHIPS)':
 '1': CDS_PINID='\1\';
NODE_NAME     PC6622 1
 '@T6G_MB_LIB.T6G(SCH_1):PAGE478_I108@PURE_QUANTA.Q_CAP(CHIPS)':
 'A': CDS_PINID='A';
NET_NAME
'SW_P0V9_RETIMER_CPU1_SW1_RC'
 '@T6G_MB_LIB.T6G(SCH_1):SW_P0V9_RETIMER_CPU1_SW1_RC':
 C_SIGNAL='@t6g_mb_lib.t6g(sch_1):sw_p0v9_retimer_cpu1_sw1_rc';
NODE_NAME     PR6624 1
 '@T6G_MB_LIB.T6G(SCH_1):PAGE478_I106@PURE_QUANTA.Q_RES(CHIPS)':
 'A': CDS_PINID='A';
NODE_NAME     PC6622 2
 '@T6G_MB_LIB.T6G(SCH_1):PAGE478_I108@PURE_QUANTA.Q_CAP(CHIPS)':
 'B': CDS_PINID='B';
NET_NAME
'SW_P0V9_RETIMER_CPU1_SW2'
 '@T6G_MB_LIB.T6G(SCH_1):SW_P0V9_RETIMER_CPU1_SW2':
 C_SIGNAL='@t6g_mb_lib.t6g(sch_1):sw_p0v9_retimer_cpu1_sw2';
NODE_NAME     PU6512 10_19
 '@T6G_MB_LIB.T6G(SCH_1):PAGE478_I12@PURE_QUANTA.ISL99390FRZTR5935(CHIPS)':
 'SW': CDS_PINID='SW';
NODE_NAME     PL6512 1
 '@T6G_MB_LIB.T6G(SCH_1):PAGE478_I22@PURE_QUANTA.Q_INDUCTOR(CHIPS)':
 '1': CDS_PINID='\1\';
NODE_NAME     PC6641 1
 '@T6G_MB_LIB.T6G(SCH_1):PAGE478_I109@PURE_QUANTA.Q_CAP(CHIPS)':
 'A': CDS_PINID='A';
NET_NAME
'SW_P0V9_RETIMER_CPU1_SW2_RC'
 '@T6G_MB_LIB.T6G(SCH_1):SW_P0V9_RETIMER_CPU1_SW2_RC':
 C_SIGNAL='@t6g_mb_lib.t6g(sch_1):sw_p0v9_retimer_cpu1_sw2_rc';
NODE_NAME     PC6641 2
 '@T6G_MB_LIB.T6G(SCH_1):PAGE478_I109@PURE_QUANTA.Q_CAP(CHIPS)':
 'B': CDS_PINID='B';
NODE_NAME     PR6630 1
 '@T6G_MB_LIB.T6G(SCH_1):PAGE478_I110@PURE_QUANTA.Q_RES(CHIPS)':
 'A': CDS_PINID='A';
NET_NAME
'SW_P12V_AUX_P0V9_RETIMER_CPU0_FLT'
 '@T6G_MB_LIB.T6G(SCH_1):SW_P12V_AUX_P0V9_RETIMER_CPU0_FLT':
 C_SIGNAL='@t6g_mb_lib.t6g(sch_1):sw_p12v_aux_p0v9_retimer_cpu0_flt',
 CDS_GLOBAL_NET='TRUE';
NODE_NAME     PC6555_1 1
 '@T6G_MB_LIB.T6G(SCH_1):PAGE476_I6@PURE_QUANTA.Q_CAP(CHIPS)':
 'A': CDS_PINID='A';
NODE_NAME     PC6558_1 1
 '@T6G_MB_LIB.T6G(SCH_1):PAGE476_I21@PURE_QUANTA.Q_CAP(CHIPS)':
 'A': CDS_PINID='A';
NODE_NAME     PC6557_1 1
 '@T6G_MB_LIB.T6G(SCH_1):PAGE476_I24@PURE_QUANTA.Q_CAP(CHIPS)':
 'A': CDS_PINID='A';
NODE_NAME     PC6556_1 1
 '@T6G_MB_LIB.T6G(SCH_1):PAGE476_I27@PURE_QUANTA.Q_CAP(CHIPS)':
 'A': CDS_PINID='A';
NODE_NAME     PC6554_1 1
 '@T6G_MB_LIB.T6G(SCH_1):PAGE476_I29@PURE_QUANTA.Q_CAP(CHIPS)':
 'A': CDS_PINID='A';
NODE_NAME     PU6503 25_29
 '@T6G_MB_LIB.T6G(SCH_1):PAGE476_I53@PURE_QUANTA.ISL99390FRZTR5935(CHIPS)':
 'VIN1': CDS_PINID='VIN1';
NODE_NAME     PU6503 30
 '@T6G_MB_LIB.T6G(SCH_1):PAGE476_I53@PURE_QUANTA.ISL99390FRZTR5935(CHIPS)':
 'VIN2': CDS_PINID='VIN2';
NODE_NAME     PL6504 1
 '@T6G_MB_LIB.T6G(SCH_1):PAGE476_I182@PURE_QUANTA.Q_INDUCTOR(CHIPS)':
 '1': CDS_PINID='\1\';
NODE_NAME     PC6561 1
 '@T6G_MB_LIB.T6G(SCH_1):PAGE476_I209@PURE_QUANTA.Q_CAPP(CHIPS)':
 'A': CDS_PINID='A';
NODE_NAME     PC6559_1 1
 '@T6G_MB_LIB.T6G(SCH_1):PAGE476_I210@PURE_QUANTA.Q_CAP(CHIPS)':
 'A': CDS_PINID='A';
NODE_NAME     PC6816 1
 '@T6G_MB_LIB.T6G(SCH_1):PAGE476_I216@PURE_QUANTA.Q_CAP(CHIPS)':
 'A': CDS_PINID='A';
NODE_NAME     PC6560 1
 '@T6G_MB_LIB.T6G(SCH_1):PAGE476_I217@PURE_QUANTA.Q_CAP(CHIPS)':
 'A': CDS_PINID='A';
NODE_NAME     PC6810 1
 '@T6G_MB_LIB.T6G(SCH_1):PAGE476_I231@PURE_QUANTA.Q_CAPP(CHIPS)':
 'A': CDS_PINID='A';
NODE_NAME     PC6817 1
 '@T6G_MB_LIB.T6G(SCH_1):PAGE476_I232@PURE_QUANTA.Q_CAP(CHIPS)':
 'A': CDS_PINID='A';
NODE_NAME     PC6583 1
 '@T6G_MB_LIB.T6G(SCH_1):PAGE476_I241@PURE_QUANTA.Q_CAP(CHIPS)':
 'A': CDS_PINID='A';
NODE_NAME     PC6582_2 1
 '@T6G_MB_LIB.T6G(SCH_1):PAGE476_I242@PURE_QUANTA.Q_CAP(CHIPS)':
 'A': CDS_PINID='A';
NODE_NAME     PC6581_2 1
 '@T6G_MB_LIB.T6G(SCH_1):PAGE476_I243@PURE_QUANTA.Q_CAP(CHIPS)':
 'A': CDS_PINID='A';
NODE_NAME     PC6580_2 1
 '@T6G_MB_LIB.T6G(SCH_1):PAGE476_I244@PURE_QUANTA.Q_CAP(CHIPS)':
 'A': CDS_PINID='A';
NODE_NAME     PC6579_2 1
 '@T6G_MB_LIB.T6G(SCH_1):PAGE476_I245@PURE_QUANTA.Q_CAP(CHIPS)':
 'A': CDS_PINID='A';
NODE_NAME     PC6577_2 1
 '@T6G_MB_LIB.T6G(SCH_1):PAGE476_I258@PURE_QUANTA.Q_CAP(CHIPS)':
 'A': CDS_PINID='A';
NODE_NAME     PC6578_2 1
 '@T6G_MB_LIB.T6G(SCH_1):PAGE476_I259@PURE_QUANTA.Q_CAP(CHIPS)':
 'A': CDS_PINID='A';
NODE_NAME     PU6504 25_29
 '@T6G_MB_LIB.T6G(SCH_1):PAGE476_I270@PURE_QUANTA.ISL99390FRZTR5935(CHIPS)':
 'VIN1': CDS_PINID='VIN1';
NODE_NAME     PU6504 30
 '@T6G_MB_LIB.T6G(SCH_1):PAGE476_I270@PURE_QUANTA.ISL99390FRZTR5935(CHIPS)':
 'VIN2': CDS_PINID='VIN2';
NET_NAME
'SW_P12V_AUX_P0V9_RETIMER_CPU1_FLT'
 '@T6G_MB_LIB.T6G(SCH_1):SW_P12V_AUX_P0V9_RETIMER_CPU1_FLT':
 C_SIGNAL='@t6g_mb_lib.t6g(sch_1):sw_p12v_aux_p0v9_retimer_cpu1_flt',
 CDS_GLOBAL_NET='TRUE';
NODE_NAME     PU6512 25_29
 '@T6G_MB_LIB.T6G(SCH_1):PAGE478_I12@PURE_QUANTA.ISL99390FRZTR5935(CHIPS)':
 'VIN1': CDS_PINID='VIN1';
NODE_NAME     PU6512 30
 '@T6G_MB_LIB.T6G(SCH_1):PAGE478_I12@PURE_QUANTA.ISL99390FRZTR5935(CHIPS)':
 'VIN2': CDS_PINID='VIN2';
NODE_NAME     PC6634_2 1
 '@T6G_MB_LIB.T6G(SCH_1):PAGE478_I18@PURE_QUANTA.Q_CAP(CHIPS)':
 'A': CDS_PINID='A';
NODE_NAME     PC6633_2 1
 '@T6G_MB_LIB.T6G(SCH_1):PAGE478_I21@PURE_QUANTA.Q_CAP(CHIPS)':
 'A': CDS_PINID='A';
NODE_NAME     PC6635_2 1
 '@T6G_MB_LIB.T6G(SCH_1):PAGE478_I25@PURE_QUANTA.Q_CAP(CHIPS)':
 'A': CDS_PINID='A';
NODE_NAME     PC6636_2 1
 '@T6G_MB_LIB.T6G(SCH_1):PAGE478_I28@PURE_QUANTA.Q_CAP(CHIPS)':
 'A': CDS_PINID='A';
NODE_NAME     PC6637_2 1
 '@T6G_MB_LIB.T6G(SCH_1):PAGE478_I35@PURE_QUANTA.Q_CAP(CHIPS)':
 'A': CDS_PINID='A';
NODE_NAME     PC6638_2 1
 '@T6G_MB_LIB.T6G(SCH_1):PAGE478_I36@PURE_QUANTA.Q_CAP(CHIPS)':
 'A': CDS_PINID='A';
NODE_NAME     PC6639 1
 '@T6G_MB_LIB.T6G(SCH_1):PAGE478_I38@PURE_QUANTA.Q_CAP(CHIPS)':
 'A': CDS_PINID='A';
NODE_NAME     PU6511 25_29
 '@T6G_MB_LIB.T6G(SCH_1):PAGE478_I51@PURE_QUANTA.ISL99390FRZTR5935(CHIPS)':
 'VIN1': CDS_PINID='VIN1';
NODE_NAME     PU6511 30
 '@T6G_MB_LIB.T6G(SCH_1):PAGE478_I51@PURE_QUANTA.ISL99390FRZTR5935(CHIPS)':
 'VIN2': CDS_PINID='VIN2';
NODE_NAME     PC6613_1 1
 '@T6G_MB_LIB.T6G(SCH_1):PAGE478_I61@PURE_QUANTA.Q_CAP(CHIPS)':
 'A': CDS_PINID='A';
NODE_NAME     PC6612_1 1
 '@T6G_MB_LIB.T6G(SCH_1):PAGE478_I64@PURE_QUANTA.Q_CAP(CHIPS)':
 'A': CDS_PINID='A';
NODE_NAME     PC6614_1 1
 '@T6G_MB_LIB.T6G(SCH_1):PAGE478_I72@PURE_QUANTA.Q_CAP(CHIPS)':
 'A': CDS_PINID='A';
NODE_NAME     PC6615_1 1
 '@T6G_MB_LIB.T6G(SCH_1):PAGE478_I74@PURE_QUANTA.Q_CAP(CHIPS)':
 'A': CDS_PINID='A';
NODE_NAME     PC6616_1 1
 '@T6G_MB_LIB.T6G(SCH_1):PAGE478_I77@PURE_QUANTA.Q_CAP(CHIPS)':
 'A': CDS_PINID='A';
NODE_NAME     PC6617_1 1
 '@T6G_MB_LIB.T6G(SCH_1):PAGE478_I79@PURE_QUANTA.Q_CAP(CHIPS)':
 'A': CDS_PINID='A';
NODE_NAME     PC6618 1
 '@T6G_MB_LIB.T6G(SCH_1):PAGE478_I80@PURE_QUANTA.Q_CAP(CHIPS)':
 'A': CDS_PINID='A';
NODE_NAME     PC6818 1
 '@T6G_MB_LIB.T6G(SCH_1):PAGE478_I86@PURE_QUANTA.Q_CAP(CHIPS)':
 'A': CDS_PINID='A';
NODE_NAME     PC473 1
 '@T6G_MB_LIB.T6G(SCH_1):PAGE478_I88@PURE_QUANTA.Q_CAPP(CHIPS)':
 'A': CDS_PINID='A';
NODE_NAME     PC6819 1
 '@T6G_MB_LIB.T6G(SCH_1):PAGE478_I100@PURE_QUANTA.Q_CAP(CHIPS)':
 'A': CDS_PINID='A';
NODE_NAME     PC6619 1
 '@T6G_MB_LIB.T6G(SCH_1):PAGE478_I102@PURE_QUANTA.Q_CAPP(CHIPS)':
 'A': CDS_PINID='A';
NODE_NAME     PL6510 1
 '@T6G_MB_LIB.T6G(SCH_1):PAGE478_I104@PURE_QUANTA.Q_INDUCTOR(CHIPS)':
 '1': CDS_PINID='\1\';
NET_NAME
'SW_P12V_AUX_P1V2_AUX_FLT'
 '@T6G_MB_LIB.T6G(SCH_1):SW_P12V_AUX_P1V2_AUX_FLT':
 C_SIGNAL='@t6g_mb_lib.t6g(sch_1):sw_p12v_aux_p1v2_aux_flt';
NODE_NAME     PL6003 2
 '@T6G_MB_LIB.T6G(SCH_1):PAGE380_I2@PURE_QUANTA.Q_INDUCTOR(CHIPS)':
 '2': CDS_PINID='\2\';
NODE_NAME     PC6013 1
 '@T6G_MB_LIB.T6G(SCH_1):PAGE380_I3@PURE_QUANTA.Q_CAP(CHIPS)':
 'A': CDS_PINID='A';
NODE_NAME     PC6015 1
 '@T6G_MB_LIB.T6G(SCH_1):PAGE380_I10@PURE_QUANTA.Q_CAP(CHIPS)':
 'A': CDS_PINID='A';
NODE_NAME     PC6011 1
 '@T6G_MB_LIB.T6G(SCH_1):PAGE380_I12@PURE_QUANTA.Q_CAP(CHIPS)':
 'A': CDS_PINID='A';
NODE_NAME     PU6001 3
 '@T6G_MB_LIB.T6G(SCH_1):PAGE380_I16@PURE_QUANTA.MPQ8626GDZ(CHIPS)':
 'VIN': CDS_PINID='VIN';
NET_NAME
'SW_P12V_AUX_P1V8_AUX_FLT'
 '@T6G_MB_LIB.T6G(SCH_1):SW_P12V_AUX_P1V8_AUX_FLT':
 C_SIGNAL='@t6g_mb_lib.t6g(sch_1):sw_p12v_aux_p1v8_aux_flt';
NODE_NAME     PL6002 2
 '@T6G_MB_LIB.T6G(SCH_1):PAGE315_I7@PURE_QUANTA.Q_INDUCTOR(CHIPS)':
 '2': CDS_PINID='\2\';
NODE_NAME     PC6012 1
 '@T6G_MB_LIB.T6G(SCH_1):PAGE315_I8@PURE_QUANTA.Q_CAP(CHIPS)':
 'A': CDS_PINID='A';
NODE_NAME     PC6014 1
 '@T6G_MB_LIB.T6G(SCH_1):PAGE315_I10@PURE_QUANTA.Q_CAP(CHIPS)':
 'A': CDS_PINID='A';
NODE_NAME     PU6000 3
 '@T6G_MB_LIB.T6G(SCH_1):PAGE315_I18@PURE_QUANTA.MPQ8626GDZ(CHIPS)':
 'VIN': CDS_PINID='VIN';
NODE_NAME     PC6010 1
 '@T6G_MB_LIB.T6G(SCH_1):PAGE315_I19@PURE_QUANTA.Q_CAP(CHIPS)':
 'A': CDS_PINID='A';
NET_NAME
'SW_P12V_AUX_P1V8_RETIMER_CPU0_FLT'
 '@T6G_MB_LIB.T6G(SCH_1):SW_P12V_AUX_P1V8_RETIMER_CPU0_FLT':
 C_SIGNAL='@t6g_mb_lib.t6g(sch_1):sw_p12v_aux_p1v8_retimer_cpu0_flt';
NODE_NAME     PC6800 1
 '@T6G_MB_LIB.T6G(SCH_1):PAGE469_I6@PURE_QUANTA.Q_CAPP(CHIPS)':
 'A': CDS_PINID='A';
NODE_NAME     PC6802 1
 '@T6G_MB_LIB.T6G(SCH_1):PAGE469_I7@PURE_QUANTA.Q_CAP(CHIPS)':
 'A': CDS_PINID='A';
NODE_NAME     PL6500 2
 '@T6G_MB_LIB.T6G(SCH_1):PAGE469_I9@PURE_QUANTA.Q_INDUCTOR(CHIPS)':
 '2': CDS_PINID='\2\';
NODE_NAME     PC6501 1
 '@T6G_MB_LIB.T6G(SCH_1):PAGE469_I16@PURE_QUANTA.Q_CAP(CHIPS)':
 'A': CDS_PINID='A';
NODE_NAME     PC6502 1
 '@T6G_MB_LIB.T6G(SCH_1):PAGE469_I17@PURE_QUANTA.Q_CAP(CHIPS)':
 'A': CDS_PINID='A';
NODE_NAME     PC6503 1
 '@T6G_MB_LIB.T6G(SCH_1):PAGE469_I18@PURE_QUANTA.Q_CAP(CHIPS)':
 'A': CDS_PINID='A';
NODE_NAME     PC6504 1
 '@T6G_MB_LIB.T6G(SCH_1):PAGE469_I22@PURE_QUANTA.Q_CAP(CHIPS)':
 'A': CDS_PINID='A';
NODE_NAME     PC6505 1
 '@T6G_MB_LIB.T6G(SCH_1):PAGE469_I23@PURE_QUANTA.Q_CAP(CHIPS)':
 'A': CDS_PINID='A';
NODE_NAME     PU6500 10
 '@T6G_MB_LIB.T6G(SCH_1):PAGE469_I51@PURE_QUANTA.MPQ8633BGLEC838Z(CHIPS)':
 'VIN1': CDS_PINID='VIN1';
NODE_NAME     PU6500 21
 '@T6G_MB_LIB.T6G(SCH_1):PAGE469_I51@PURE_QUANTA.MPQ8633BGLEC838Z(CHIPS)':
 'VIN2': CDS_PINID='VIN2';
NODE_NAME     PC6902 1
 '@T6G_MB_LIB.T6G(SCH_1):PAGE469_I56@PURE_QUANTA.Q_CAP(CHIPS)':
 'A': CDS_PINID='A';
NODE_NAME     PC6901 1
 '@T6G_MB_LIB.T6G(SCH_1):PAGE469_I57@PURE_QUANTA.Q_CAP(CHIPS)':
 'A': CDS_PINID='A';
NODE_NAME     PC6900 1
 '@T6G_MB_LIB.T6G(SCH_1):PAGE469_I58@PURE_QUANTA.Q_CAP(CHIPS)':
 'A': CDS_PINID='A';
NET_NAME
'SW_P12V_AUX_P1V8_RETIMER_CPU1_FLT'
 '@T6G_MB_LIB.T6G(SCH_1):SW_P12V_AUX_P1V8_RETIMER_CPU1_FLT':
 C_SIGNAL='@t6g_mb_lib.t6g(sch_1):sw_p12v_aux_p1v8_retimer_cpu1_flt';
NODE_NAME     PC6801 1
 '@T6G_MB_LIB.T6G(SCH_1):PAGE470_I6@PURE_QUANTA.Q_CAPP(CHIPS)':
 'A': CDS_PINID='A';
NODE_NAME     PC6803 1
 '@T6G_MB_LIB.T6G(SCH_1):PAGE470_I7@PURE_QUANTA.Q_CAP(CHIPS)':
 'A': CDS_PINID='A';
NODE_NAME     PL6503 2
 '@T6G_MB_LIB.T6G(SCH_1):PAGE470_I9@PURE_QUANTA.Q_INDUCTOR(CHIPS)':
 '2': CDS_PINID='\2\';
NODE_NAME     PC6520 1
 '@T6G_MB_LIB.T6G(SCH_1):PAGE470_I16@PURE_QUANTA.Q_CAP(CHIPS)':
 'A': CDS_PINID='A';
NODE_NAME     PC6521 1
 '@T6G_MB_LIB.T6G(SCH_1):PAGE470_I17@PURE_QUANTA.Q_CAP(CHIPS)':
 'A': CDS_PINID='A';
NODE_NAME     PC6522 1
 '@T6G_MB_LIB.T6G(SCH_1):PAGE470_I18@PURE_QUANTA.Q_CAP(CHIPS)':
 'A': CDS_PINID='A';
NODE_NAME     PC6523 1
 '@T6G_MB_LIB.T6G(SCH_1):PAGE470_I22@PURE_QUANTA.Q_CAP(CHIPS)':
 'A': CDS_PINID='A';
NODE_NAME     PC6524 1
 '@T6G_MB_LIB.T6G(SCH_1):PAGE470_I23@PURE_QUANTA.Q_CAP(CHIPS)':
 'A': CDS_PINID='A';
NODE_NAME     PU6501 10
 '@T6G_MB_LIB.T6G(SCH_1):PAGE470_I51@PURE_QUANTA.MPQ8633BGLEC838Z(CHIPS)':
 'VIN1': CDS_PINID='VIN1';
NODE_NAME     PU6501 21
 '@T6G_MB_LIB.T6G(SCH_1):PAGE470_I51@PURE_QUANTA.MPQ8633BGLEC838Z(CHIPS)':
 'VIN2': CDS_PINID='VIN2';
NODE_NAME     PC6905 1
 '@T6G_MB_LIB.T6G(SCH_1):PAGE470_I55@PURE_QUANTA.Q_CAP(CHIPS)':
 'A': CDS_PINID='A';
NODE_NAME     PC6904 1
 '@T6G_MB_LIB.T6G(SCH_1):PAGE470_I56@PURE_QUANTA.Q_CAP(CHIPS)':
 'A': CDS_PINID='A';
NODE_NAME     PC6903 1
 '@T6G_MB_LIB.T6G(SCH_1):PAGE470_I57@PURE_QUANTA.Q_CAP(CHIPS)':
 'A': CDS_PINID='A';
NET_NAME
'SW_P12V_AUX_PVDD11_S3_P0_FLT'
 '@T6G_MB_LIB.T6G(SCH_1):SW_P12V_AUX_PVDD11_S3_P0_FLT':
 C_SIGNAL='@t6g_mb_lib.t6g(sch_1):sw_p12v_aux_pvdd11_s3_p0_flt',
 CDS_GLOBAL_NET='TRUE';
NODE_NAME     PC210_2 1
 '@T6G_MB_LIB.T6G(SCH_1):PAGE183_I27@PURE_QUANTA.Q_CAP(CHIPS)':
 'A': CDS_PINID='A';
NODE_NAME     PC208_2 1
 '@T6G_MB_LIB.T6G(SCH_1):PAGE183_I29@PURE_QUANTA.Q_CAP(CHIPS)':
 'A': CDS_PINID='A';
NODE_NAME     PC209_1 1
 '@T6G_MB_LIB.T6G(SCH_1):PAGE183_I44@PURE_QUANTA.Q_CAP(CHIPS)':
 'A': CDS_PINID='A';
NODE_NAME     PC211_1 1
 '@T6G_MB_LIB.T6G(SCH_1):PAGE183_I48@PURE_QUANTA.Q_CAP(CHIPS)':
 'A': CDS_PINID='A';
NODE_NAME     PU23 25_29
 '@T6G_MB_LIB.T6G(SCH_1):PAGE183_I13@PURE_QUANTA.ISL99390FRZTR5935(CHIPS)':
 'VIN1': CDS_PINID='VIN1';
NODE_NAME     PU23 30
 '@T6G_MB_LIB.T6G(SCH_1):PAGE183_I13@PURE_QUANTA.ISL99390FRZTR5935(CHIPS)':
 'VIN2': CDS_PINID='VIN2';
NODE_NAME     PC212_2 1
 '@T6G_MB_LIB.T6G(SCH_1):PAGE183_I30@PURE_QUANTA.Q_CAP(CHIPS)':
 'A': CDS_PINID='A';
NODE_NAME     PC214_2 1
 '@T6G_MB_LIB.T6G(SCH_1):PAGE183_I31@PURE_QUANTA.Q_CAP(CHIPS)':
 'A': CDS_PINID='A';
NODE_NAME     PC207_1 1
 '@T6G_MB_LIB.T6G(SCH_1):PAGE183_I47@PURE_QUANTA.Q_CAP(CHIPS)':
 'A': CDS_PINID='A';
NODE_NAME     PC213_1 1
 '@T6G_MB_LIB.T6G(SCH_1):PAGE183_I49@PURE_QUANTA.Q_CAP(CHIPS)':
 'A': CDS_PINID='A';
NODE_NAME     PC216_2 1
 '@T6G_MB_LIB.T6G(SCH_1):PAGE183_I50@PURE_QUANTA.Q_CAP(CHIPS)':
 'A': CDS_PINID='A';
NODE_NAME     PC218_2 1
 '@T6G_MB_LIB.T6G(SCH_1):PAGE183_I54@PURE_QUANTA.Q_CAP(CHIPS)':
 'A': CDS_PINID='A';
NODE_NAME     PC220 1
 '@T6G_MB_LIB.T6G(SCH_1):PAGE183_I75@PURE_QUANTA.Q_CAPP(CHIPS)':
 'A': CDS_PINID='A';
NODE_NAME     PL24 1
 '@T6G_MB_LIB.T6G(SCH_1):PAGE183_I78@PURE_QUANTA.Q_INDUCTOR(CHIPS)':
 '1': CDS_PINID='\1\';
NODE_NAME     PC215_1 1
 '@T6G_MB_LIB.T6G(SCH_1):PAGE183_I87@PURE_QUANTA.Q_CAP(CHIPS)':
 'A': CDS_PINID='A';
NODE_NAME     PC219_1 1
 '@T6G_MB_LIB.T6G(SCH_1):PAGE183_I88@PURE_QUANTA.Q_CAP(CHIPS)':
 'A': CDS_PINID='A';
NODE_NAME     PU22 25_29
 '@T6G_MB_LIB.T6G(SCH_1):PAGE183_I92@PURE_QUANTA.ISL99390FRZTR5935(CHIPS)':
 'VIN1': CDS_PINID='VIN1';
NODE_NAME     PU22 30
 '@T6G_MB_LIB.T6G(SCH_1):PAGE183_I92@PURE_QUANTA.ISL99390FRZTR5935(CHIPS)':
 'VIN2': CDS_PINID='VIN2';
NODE_NAME     PC8004 1
 '@T6G_MB_LIB.T6G(SCH_1):PAGE183_I93@PURE_QUANTA.Q_CAP(CHIPS)':
 'A': CDS_PINID='A';
NODE_NAME     PC8005 1
 '@T6G_MB_LIB.T6G(SCH_1):PAGE183_I94@PURE_QUANTA.Q_CAP(CHIPS)':
 'A': CDS_PINID='A';
NODE_NAME     PC7002 1
 '@T6G_MB_LIB.T6G(SCH_1):PAGE183_I95@PURE_QUANTA.Q_CAP(CHIPS)':
 'A': CDS_PINID='A';
NET_NAME
'SW_P12V_AUX_PVDD11_S3_P1_FLT'
 '@T6G_MB_LIB.T6G(SCH_1):SW_P12V_AUX_PVDD11_S3_P1_FLT':
 C_SIGNAL='@t6g_mb_lib.t6g(sch_1):sw_p12v_aux_pvdd11_s3_p1_flt',
 CDS_GLOBAL_NET='TRUE';
NODE_NAME     PC510_2 1
 '@T6G_MB_LIB.T6G(SCH_1):PAGE200_I29@PURE_QUANTA.Q_CAP(CHIPS)':
 'A': CDS_PINID='A';
NODE_NAME     PC509_1 1
 '@T6G_MB_LIB.T6G(SCH_1):PAGE200_I48@PURE_QUANTA.Q_CAP(CHIPS)':
 'A': CDS_PINID='A';
NODE_NAME     PC518_2 1
 '@T6G_MB_LIB.T6G(SCH_1):PAGE200_I52@PURE_QUANTA.Q_CAP(CHIPS)':
 'A': CDS_PINID='A';
NODE_NAME     PC522 1
 '@T6G_MB_LIB.T6G(SCH_1):PAGE200_I81@PURE_QUANTA.Q_CAPP(CHIPS)':
 'A': CDS_PINID='A';
NODE_NAME     PL56 1
 '@T6G_MB_LIB.T6G(SCH_1):PAGE200_I84@PURE_QUANTA.Q_INDUCTOR(CHIPS)':
 '1': CDS_PINID='\1\';
NODE_NAME     PU44 25_29
 '@T6G_MB_LIB.T6G(SCH_1):PAGE200_I22@PURE_QUANTA.ISL99390FRZTR5935(CHIPS)':
 'VIN1': CDS_PINID='VIN1';
NODE_NAME     PU44 30
 '@T6G_MB_LIB.T6G(SCH_1):PAGE200_I22@PURE_QUANTA.ISL99390FRZTR5935(CHIPS)':
 'VIN2': CDS_PINID='VIN2';
NODE_NAME     PC514_2 1
 '@T6G_MB_LIB.T6G(SCH_1):PAGE200_I30@PURE_QUANTA.Q_CAP(CHIPS)':
 'A': CDS_PINID='A';
NODE_NAME     PC516_2 1
 '@T6G_MB_LIB.T6G(SCH_1):PAGE200_I31@PURE_QUANTA.Q_CAP(CHIPS)':
 'A': CDS_PINID='A';
NODE_NAME     PC511_1 1
 '@T6G_MB_LIB.T6G(SCH_1):PAGE200_I45@PURE_QUANTA.Q_CAP(CHIPS)':
 'A': CDS_PINID='A';
NODE_NAME     PC513_1 1
 '@T6G_MB_LIB.T6G(SCH_1):PAGE200_I49@PURE_QUANTA.Q_CAP(CHIPS)':
 'A': CDS_PINID='A';
NODE_NAME     PC515_1 1
 '@T6G_MB_LIB.T6G(SCH_1):PAGE200_I50@PURE_QUANTA.Q_CAP(CHIPS)':
 'A': CDS_PINID='A';
NODE_NAME     PC517_1 1
 '@T6G_MB_LIB.T6G(SCH_1):PAGE200_I51@PURE_QUANTA.Q_CAP(CHIPS)':
 'A': CDS_PINID='A';
NODE_NAME     PC27 1
 '@T6G_MB_LIB.T6G(SCH_1):PAGE200_I58@PURE_QUANTA.Q_CAP(CHIPS)':
 'A': CDS_PINID='A';
NODE_NAME     PC521_1 1
 '@T6G_MB_LIB.T6G(SCH_1):PAGE200_I80@PURE_QUANTA.Q_CAP(CHIPS)':
 'A': CDS_PINID='A';
NODE_NAME     PC512_2 1
 '@T6G_MB_LIB.T6G(SCH_1):PAGE200_I91@PURE_QUANTA.Q_CAP(CHIPS)':
 'A': CDS_PINID='A';
NODE_NAME     PU45 25_29
 '@T6G_MB_LIB.T6G(SCH_1):PAGE200_I92@PURE_QUANTA.ISL99390FRZTR5935(CHIPS)':
 'VIN1': CDS_PINID='VIN1';
NODE_NAME     PU45 30
 '@T6G_MB_LIB.T6G(SCH_1):PAGE200_I92@PURE_QUANTA.ISL99390FRZTR5935(CHIPS)':
 'VIN2': CDS_PINID='VIN2';
NODE_NAME     PC8006 1
 '@T6G_MB_LIB.T6G(SCH_1):PAGE200_I93@PURE_QUANTA.Q_CAP(CHIPS)':
 'A': CDS_PINID='A';
NODE_NAME     PC8007 1
 '@T6G_MB_LIB.T6G(SCH_1):PAGE200_I94@PURE_QUANTA.Q_CAP(CHIPS)':
 'A': CDS_PINID='A';
NODE_NAME     PC7003 1
 '@T6G_MB_LIB.T6G(SCH_1):PAGE200_I95@PURE_QUANTA.Q_CAP(CHIPS)':
 'A': CDS_PINID='A';
NET_NAME
'SW_P12V_AUX_PVDD18_S5_P0_FLT'
 '@T6G_MB_LIB.T6G(SCH_1):SW_P12V_AUX_PVDD18_S5_P0_FLT':
 C_SIGNAL='@t6g_mb_lib.t6g(sch_1):sw_p12v_aux_pvdd18_s5_p0_flt';
NODE_NAME     PL77 2
 '@T6G_MB_LIB.T6G(SCH_1):PAGE184_I7@PURE_QUANTA.Q_INDUCTOR(CHIPS)':
 '2': CDS_PINID='\2\';
NODE_NAME     PC111 1
 '@T6G_MB_LIB.T6G(SCH_1):PAGE184_I8@PURE_QUANTA.Q_CAP(CHIPS)':
 'A': CDS_PINID='A';
NODE_NAME     PU57 10
 '@T6G_MB_LIB.T6G(SCH_1):PAGE184_I18@PURE_QUANTA.MPQ8633BGLEC838Z(CHIPS)':
 'VIN1': CDS_PINID='VIN1';
NODE_NAME     PU57 21
 '@T6G_MB_LIB.T6G(SCH_1):PAGE184_I18@PURE_QUANTA.MPQ8633BGLEC838Z(CHIPS)':
 'VIN2': CDS_PINID='VIN2';
NODE_NAME     PC227 1
 '@T6G_MB_LIB.T6G(SCH_1):PAGE184_I25@PURE_QUANTA.Q_CAP(CHIPS)':
 'A': CDS_PINID='A';
NODE_NAME     PC254 1
 '@T6G_MB_LIB.T6G(SCH_1):PAGE184_I26@PURE_QUANTA.Q_CAP(CHIPS)':
 'A': CDS_PINID='A';
NODE_NAME     PC81 1
 '@T6G_MB_LIB.T6G(SCH_1):PAGE184_I27@PURE_QUANTA.Q_CAP(CHIPS)':
 'A': CDS_PINID='A';
NODE_NAME     PC237 1
 '@T6G_MB_LIB.T6G(SCH_1):PAGE184_I28@PURE_QUANTA.Q_CAP(CHIPS)':
 'A': CDS_PINID='A';
NODE_NAME     PC8002 1
 '@T6G_MB_LIB.T6G(SCH_1):PAGE184_I57@PURE_QUANTA.Q_CAP(CHIPS)':
 'A': CDS_PINID='A';
NET_NAME
'SW_P12V_AUX_PVDD18_S5_P1_FLT'
 '@T6G_MB_LIB.T6G(SCH_1):SW_P12V_AUX_PVDD18_S5_P1_FLT':
 C_SIGNAL='@t6g_mb_lib.t6g(sch_1):sw_p12v_aux_pvdd18_s5_p1_flt';
NODE_NAME     PU3 10
 '@T6G_MB_LIB.T6G(SCH_1):PAGE201_I15@PURE_QUANTA.MPQ8633BGLEC838Z(CHIPS)':
 'VIN1': CDS_PINID='VIN1';
NODE_NAME     PU3 21
 '@T6G_MB_LIB.T6G(SCH_1):PAGE201_I15@PURE_QUANTA.MPQ8633BGLEC838Z(CHIPS)':
 'VIN2': CDS_PINID='VIN2';
NODE_NAME     PC61 1
 '@T6G_MB_LIB.T6G(SCH_1):PAGE201_I21@PURE_QUANTA.Q_CAP(CHIPS)':
 'A': CDS_PINID='A';
NODE_NAME     PC150 1
 '@T6G_MB_LIB.T6G(SCH_1):PAGE201_I22@PURE_QUANTA.Q_CAP(CHIPS)':
 'A': CDS_PINID='A';
NODE_NAME     PC152 1
 '@T6G_MB_LIB.T6G(SCH_1):PAGE201_I23@PURE_QUANTA.Q_CAP(CHIPS)':
 'A': CDS_PINID='A';
NODE_NAME     PC22 1
 '@T6G_MB_LIB.T6G(SCH_1):PAGE201_I24@PURE_QUANTA.Q_CAP(CHIPS)':
 'A': CDS_PINID='A';
NODE_NAME     PL26 2
 '@T6G_MB_LIB.T6G(SCH_1):PAGE201_I4@PURE_QUANTA.Q_INDUCTOR(CHIPS)':
 '2': CDS_PINID='\2\';
NODE_NAME     PC60 1
 '@T6G_MB_LIB.T6G(SCH_1):PAGE201_I54@PURE_QUANTA.Q_CAP(CHIPS)':
 'A': CDS_PINID='A';
NODE_NAME     PC8003 1
 '@T6G_MB_LIB.T6G(SCH_1):PAGE201_I57@PURE_QUANTA.Q_CAP(CHIPS)':
 'A': CDS_PINID='A';
NET_NAME
'SW_P12V_AUX_PVDDCR_CPU0_P0_FLT'
 '@T6G_MB_LIB.T6G(SCH_1):SW_P12V_AUX_PVDDCR_CPU0_P0_FLT':
 C_SIGNAL='@t6g_mb_lib.t6g(sch_1):sw_p12v_aux_pvddcr_cpu0_p0_flt',
 CDS_GLOBAL_NET='TRUE';
NODE_NAME     PU43 25_29
 '@T6G_MB_LIB.T6G(SCH_1):PAGE169_I16@PURE_QUANTA.ISL99390FRZTR5935(CHIPS)':
 'VIN1': CDS_PINID='VIN1';
NODE_NAME     PU43 30
 '@T6G_MB_LIB.T6G(SCH_1):PAGE169_I16@PURE_QUANTA.ISL99390FRZTR5935(CHIPS)':
 'VIN2': CDS_PINID='VIN2';
NODE_NAME     PU6 25_29
 '@T6G_MB_LIB.T6G(SCH_1):PAGE169_I26@PURE_QUANTA.ISL99390FRZTR5935(CHIPS)':
 'VIN1': CDS_PINID='VIN1';
NODE_NAME     PU6 30
 '@T6G_MB_LIB.T6G(SCH_1):PAGE169_I26@PURE_QUANTA.ISL99390FRZTR5935(CHIPS)':
 'VIN2': CDS_PINID='VIN2';
NODE_NAME     PC482_2 1
 '@T6G_MB_LIB.T6G(SCH_1):PAGE169_I33@PURE_QUANTA.Q_CAP(CHIPS)':
 'A': CDS_PINID='A';
NODE_NAME     PC551_4 1
 '@T6G_MB_LIB.T6G(SCH_1):PAGE170_I21@PURE_QUANTA.Q_CAP(CHIPS)':
 'A': CDS_PINID='A';
NODE_NAME     PC555_4 1
 '@T6G_MB_LIB.T6G(SCH_1):PAGE170_I23@PURE_QUANTA.Q_CAP(CHIPS)':
 'A': CDS_PINID='A';
NODE_NAME     PC480_2 1
 '@T6G_MB_LIB.T6G(SCH_1):PAGE169_I34@PURE_QUANTA.Q_CAP(CHIPS)':
 'A': CDS_PINID='A';
NODE_NAME     PC484_2 1
 '@T6G_MB_LIB.T6G(SCH_1):PAGE169_I36@PURE_QUANTA.Q_CAP(CHIPS)':
 'A': CDS_PINID='A';
NODE_NAME     PC486_2 1
 '@T6G_MB_LIB.T6G(SCH_1):PAGE169_I37@PURE_QUANTA.Q_CAP(CHIPS)':
 'A': CDS_PINID='A';
NODE_NAME     PC488_2 1
 '@T6G_MB_LIB.T6G(SCH_1):PAGE169_I39@PURE_QUANTA.Q_CAP(CHIPS)':
 'A': CDS_PINID='A';
NODE_NAME     PC479_1 1
 '@T6G_MB_LIB.T6G(SCH_1):PAGE169_I52@PURE_QUANTA.Q_CAP(CHIPS)':
 'A': CDS_PINID='A';
NODE_NAME     PC481_1 1
 '@T6G_MB_LIB.T6G(SCH_1):PAGE169_I53@PURE_QUANTA.Q_CAP(CHIPS)':
 'A': CDS_PINID='A';
NODE_NAME     PC483_1 1
 '@T6G_MB_LIB.T6G(SCH_1):PAGE169_I57@PURE_QUANTA.Q_CAP(CHIPS)':
 'A': CDS_PINID='A';
NODE_NAME     PC485_1 1
 '@T6G_MB_LIB.T6G(SCH_1):PAGE169_I58@PURE_QUANTA.Q_CAP(CHIPS)':
 'A': CDS_PINID='A';
NODE_NAME     PC487_1 1
 '@T6G_MB_LIB.T6G(SCH_1):PAGE169_I59@PURE_QUANTA.Q_CAP(CHIPS)':
 'A': CDS_PINID='A';
NODE_NAME     PC491 1
 '@T6G_MB_LIB.T6G(SCH_1):PAGE169_I79@PURE_QUANTA.Q_CAPP(CHIPS)':
 'A': CDS_PINID='A';
NODE_NAME     PC492 1
 '@T6G_MB_LIB.T6G(SCH_1):PAGE169_I81@PURE_QUANTA.Q_CAPP(CHIPS)':
 'A': CDS_PINID='A';
NODE_NAME     PL53 1
 '@T6G_MB_LIB.T6G(SCH_1):PAGE169_I82@PURE_QUANTA.Q_INDUCTOR(CHIPS)':
 '1': CDS_PINID='\1\';
NODE_NAME     PU47 25_29
 '@T6G_MB_LIB.T6G(SCH_1):PAGE170_I9@PURE_QUANTA.ISL99390FRZTR5935(CHIPS)':
 'VIN1': CDS_PINID='VIN1';
NODE_NAME     PU47 30
 '@T6G_MB_LIB.T6G(SCH_1):PAGE170_I9@PURE_QUANTA.ISL99390FRZTR5935(CHIPS)':
 'VIN2': CDS_PINID='VIN2';
NODE_NAME     PC553_4 1
 '@T6G_MB_LIB.T6G(SCH_1):PAGE170_I22@PURE_QUANTA.Q_CAP(CHIPS)':
 'A': CDS_PINID='A';
NODE_NAME     PC557_4 1
 '@T6G_MB_LIB.T6G(SCH_1):PAGE170_I24@PURE_QUANTA.Q_CAP(CHIPS)':
 'A': CDS_PINID='A';
NODE_NAME     PU46 25_29
 '@T6G_MB_LIB.T6G(SCH_1):PAGE170_I38@PURE_QUANTA.ISL99390FRZTR5935(CHIPS)':
 'VIN1': CDS_PINID='VIN1';
NODE_NAME     PU46 30
 '@T6G_MB_LIB.T6G(SCH_1):PAGE170_I38@PURE_QUANTA.ISL99390FRZTR5935(CHIPS)':
 'VIN2': CDS_PINID='VIN2';
NODE_NAME     PC552_3 1
 '@T6G_MB_LIB.T6G(SCH_1):PAGE170_I43@PURE_QUANTA.Q_CAP(CHIPS)':
 'A': CDS_PINID='A';
NODE_NAME     PC550_3 1
 '@T6G_MB_LIB.T6G(SCH_1):PAGE170_I47@PURE_QUANTA.Q_CAP(CHIPS)':
 'A': CDS_PINID='A';
NODE_NAME     PC554_3 1
 '@T6G_MB_LIB.T6G(SCH_1):PAGE170_I48@PURE_QUANTA.Q_CAP(CHIPS)':
 'A': CDS_PINID='A';
NODE_NAME     PC556_3 1
 '@T6G_MB_LIB.T6G(SCH_1):PAGE170_I49@PURE_QUANTA.Q_CAP(CHIPS)':
 'A': CDS_PINID='A';
NODE_NAME     PC559_4 1
 '@T6G_MB_LIB.T6G(SCH_1):PAGE170_I55@PURE_QUANTA.Q_CAP(CHIPS)':
 'A': CDS_PINID='A';
NODE_NAME     PC558_3 1
 '@T6G_MB_LIB.T6G(SCH_1):PAGE170_I66@PURE_QUANTA.Q_CAP(CHIPS)':
 'A': CDS_PINID='A';
NODE_NAME     PU48 25_29
 '@T6G_MB_LIB.T6G(SCH_1):PAGE171_I18@PURE_QUANTA.ISL99390FRZTR5935(CHIPS)':
 'VIN1': CDS_PINID='VIN1';
NODE_NAME     PU48 30
 '@T6G_MB_LIB.T6G(SCH_1):PAGE171_I18@PURE_QUANTA.ISL99390FRZTR5935(CHIPS)':
 'VIN2': CDS_PINID='VIN2';
NODE_NAME     PC153_6 1
 '@T6G_MB_LIB.T6G(SCH_1):PAGE171_I24@PURE_QUANTA.Q_CAP(CHIPS)':
 'A': CDS_PINID='A';
NODE_NAME     PC154_6 1
 '@T6G_MB_LIB.T6G(SCH_1):PAGE171_I27@PURE_QUANTA.Q_CAP(CHIPS)':
 'A': CDS_PINID='A';
NODE_NAME     PC157_6 1
 '@T6G_MB_LIB.T6G(SCH_1):PAGE171_I28@PURE_QUANTA.Q_CAP(CHIPS)':
 'A': CDS_PINID='A';
NODE_NAME     PC158_6 1
 '@T6G_MB_LIB.T6G(SCH_1):PAGE171_I29@PURE_QUANTA.Q_CAP(CHIPS)':
 'A': CDS_PINID='A';
NODE_NAME     PC570_5 1
 '@T6G_MB_LIB.T6G(SCH_1):PAGE171_I44@PURE_QUANTA.Q_CAP(CHIPS)':
 'A': CDS_PINID='A';
NODE_NAME     PC569_5 1
 '@T6G_MB_LIB.T6G(SCH_1):PAGE171_I47@PURE_QUANTA.Q_CAP(CHIPS)':
 'A': CDS_PINID='A';
NODE_NAME     PC571_5 1
 '@T6G_MB_LIB.T6G(SCH_1):PAGE171_I48@PURE_QUANTA.Q_CAP(CHIPS)':
 'A': CDS_PINID='A';
NODE_NAME     PC572_5 1
 '@T6G_MB_LIB.T6G(SCH_1):PAGE171_I49@PURE_QUANTA.Q_CAP(CHIPS)':
 'A': CDS_PINID='A';
NODE_NAME     PC159_6 1
 '@T6G_MB_LIB.T6G(SCH_1):PAGE171_I55@PURE_QUANTA.Q_CAP(CHIPS)':
 'A': CDS_PINID='A';
NODE_NAME     PC573_5 1
 '@T6G_MB_LIB.T6G(SCH_1):PAGE171_I66@PURE_QUANTA.Q_CAP(CHIPS)':
 'A': CDS_PINID='A';
NODE_NAME     PU10 25_29
 '@T6G_MB_LIB.T6G(SCH_1):PAGE171_I73@PURE_QUANTA.ISL99390FRZTR5935(CHIPS)':
 'VIN1': CDS_PINID='VIN1';
NODE_NAME     PU10 30
 '@T6G_MB_LIB.T6G(SCH_1):PAGE171_I73@PURE_QUANTA.ISL99390FRZTR5935(CHIPS)':
 'VIN2': CDS_PINID='VIN2';
NET_NAME
'SW_P12V_AUX_PVDDCR_CPU0_P1_FLT'
 '@T6G_MB_LIB.T6G(SCH_1):SW_P12V_AUX_PVDDCR_CPU0_P1_FLT':
 C_SIGNAL='@t6g_mb_lib.t6g(sch_1):sw_p12v_aux_pvddcr_cpu0_p1_flt',
 CDS_GLOBAL_NET='TRUE';
NODE_NAME     PC263_2 1
 '@T6G_MB_LIB.T6G(SCH_1):PAGE186_I26@PURE_QUANTA.Q_CAP(CHIPS)':
 'A': CDS_PINID='A';
NODE_NAME     PC269_2 1
 '@T6G_MB_LIB.T6G(SCH_1):PAGE186_I31@PURE_QUANTA.Q_CAP(CHIPS)':
 'A': CDS_PINID='A';
NODE_NAME     PC260_1 1
 '@T6G_MB_LIB.T6G(SCH_1):PAGE186_I46@PURE_QUANTA.Q_CAP(CHIPS)':
 'A': CDS_PINID='A';
NODE_NAME     PC273 1
 '@T6G_MB_LIB.T6G(SCH_1):PAGE186_I71@PURE_QUANTA.Q_CAPP(CHIPS)':
 'A': CDS_PINID='A';
NODE_NAME     PC261_2 1
 '@T6G_MB_LIB.T6G(SCH_1):PAGE186_I25@PURE_QUANTA.Q_CAP(CHIPS)':
 'A': CDS_PINID='A';
NODE_NAME     PC265_2 1
 '@T6G_MB_LIB.T6G(SCH_1):PAGE186_I28@PURE_QUANTA.Q_CAP(CHIPS)':
 'A': CDS_PINID='A';
NODE_NAME     PC267_2 1
 '@T6G_MB_LIB.T6G(SCH_1):PAGE186_I29@PURE_QUANTA.Q_CAP(CHIPS)':
 'A': CDS_PINID='A';
NODE_NAME     PC262_1 1
 '@T6G_MB_LIB.T6G(SCH_1):PAGE186_I47@PURE_QUANTA.Q_CAP(CHIPS)':
 'A': CDS_PINID='A';
NODE_NAME     PC264_1 1
 '@T6G_MB_LIB.T6G(SCH_1):PAGE186_I51@PURE_QUANTA.Q_CAP(CHIPS)':
 'A': CDS_PINID='A';
NODE_NAME     PC266_1 1
 '@T6G_MB_LIB.T6G(SCH_1):PAGE186_I52@PURE_QUANTA.Q_CAP(CHIPS)':
 'A': CDS_PINID='A';
NODE_NAME     PC268_1 1
 '@T6G_MB_LIB.T6G(SCH_1):PAGE186_I53@PURE_QUANTA.Q_CAP(CHIPS)':
 'A': CDS_PINID='A';
NODE_NAME     PC272 1
 '@T6G_MB_LIB.T6G(SCH_1):PAGE186_I70@PURE_QUANTA.Q_CAPP(CHIPS)':
 'A': CDS_PINID='A';
NODE_NAME     PL30 1
 '@T6G_MB_LIB.T6G(SCH_1):PAGE186_I73@PURE_QUANTA.Q_INDUCTOR(CHIPS)':
 '1': CDS_PINID='\1\';
NODE_NAME     PU4 25_29
 '@T6G_MB_LIB.T6G(SCH_1):PAGE186_I88@PURE_QUANTA.ISL99390FRZTR5935(CHIPS)':
 'VIN1': CDS_PINID='VIN1';
NODE_NAME     PU4 30
 '@T6G_MB_LIB.T6G(SCH_1):PAGE186_I88@PURE_QUANTA.ISL99390FRZTR5935(CHIPS)':
 'VIN2': CDS_PINID='VIN2';
NODE_NAME     PU26 25_29
 '@T6G_MB_LIB.T6G(SCH_1):PAGE186_I91@PURE_QUANTA.ISL99390FRZTR5935(CHIPS)':
 'VIN1': CDS_PINID='VIN1';
NODE_NAME     PU26 30
 '@T6G_MB_LIB.T6G(SCH_1):PAGE186_I91@PURE_QUANTA.ISL99390FRZTR5935(CHIPS)':
 'VIN2': CDS_PINID='VIN2';
NODE_NAME     PU28 25_29
 '@T6G_MB_LIB.T6G(SCH_1):PAGE187_I9@PURE_QUANTA.ISL99390FRZTR5935(CHIPS)':
 'VIN1': CDS_PINID='VIN1';
NODE_NAME     PU28 30
 '@T6G_MB_LIB.T6G(SCH_1):PAGE187_I9@PURE_QUANTA.ISL99390FRZTR5935(CHIPS)':
 'VIN2': CDS_PINID='VIN2';
NODE_NAME     PC293_4 1
 '@T6G_MB_LIB.T6G(SCH_1):PAGE187_I22@PURE_QUANTA.Q_CAP(CHIPS)':
 'A': CDS_PINID='A';
NODE_NAME     PC291_4 1
 '@T6G_MB_LIB.T6G(SCH_1):PAGE187_I23@PURE_QUANTA.Q_CAP(CHIPS)':
 'A': CDS_PINID='A';
NODE_NAME     PC295_4 1
 '@T6G_MB_LIB.T6G(SCH_1):PAGE187_I24@PURE_QUANTA.Q_CAP(CHIPS)':
 'A': CDS_PINID='A';
NODE_NAME     PC297_4 1
 '@T6G_MB_LIB.T6G(SCH_1):PAGE187_I25@PURE_QUANTA.Q_CAP(CHIPS)':
 'A': CDS_PINID='A';
NODE_NAME     PU27 25_29
 '@T6G_MB_LIB.T6G(SCH_1):PAGE187_I39@PURE_QUANTA.ISL99390FRZTR5935(CHIPS)':
 'VIN1': CDS_PINID='VIN1';
NODE_NAME     PU27 30
 '@T6G_MB_LIB.T6G(SCH_1):PAGE187_I39@PURE_QUANTA.ISL99390FRZTR5935(CHIPS)':
 'VIN2': CDS_PINID='VIN2';
NODE_NAME     PC290_3 1
 '@T6G_MB_LIB.T6G(SCH_1):PAGE187_I44@PURE_QUANTA.Q_CAP(CHIPS)':
 'A': CDS_PINID='A';
NODE_NAME     PC292_3 1
 '@T6G_MB_LIB.T6G(SCH_1):PAGE187_I48@PURE_QUANTA.Q_CAP(CHIPS)':
 'A': CDS_PINID='A';
NODE_NAME     PC294_3 1
 '@T6G_MB_LIB.T6G(SCH_1):PAGE187_I49@PURE_QUANTA.Q_CAP(CHIPS)':
 'A': CDS_PINID='A';
NODE_NAME     PC296_3 1
 '@T6G_MB_LIB.T6G(SCH_1):PAGE187_I50@PURE_QUANTA.Q_CAP(CHIPS)':
 'A': CDS_PINID='A';
NODE_NAME     PC299_4 1
 '@T6G_MB_LIB.T6G(SCH_1):PAGE187_I55@PURE_QUANTA.Q_CAP(CHIPS)':
 'A': CDS_PINID='A';
NODE_NAME     PC298_3 1
 '@T6G_MB_LIB.T6G(SCH_1):PAGE187_I65@PURE_QUANTA.Q_CAP(CHIPS)':
 'A': CDS_PINID='A';
NODE_NAME     PU29 25_29
 '@T6G_MB_LIB.T6G(SCH_1):PAGE188_I18@PURE_QUANTA.ISL99390FRZTR5935(CHIPS)':
 'VIN1': CDS_PINID='VIN1';
NODE_NAME     PU29 30
 '@T6G_MB_LIB.T6G(SCH_1):PAGE188_I18@PURE_QUANTA.ISL99390FRZTR5935(CHIPS)':
 'VIN2': CDS_PINID='VIN2';
NODE_NAME     PC127_6 1
 '@T6G_MB_LIB.T6G(SCH_1):PAGE188_I25@PURE_QUANTA.Q_CAP(CHIPS)':
 'A': CDS_PINID='A';
NODE_NAME     PC128_6 1
 '@T6G_MB_LIB.T6G(SCH_1):PAGE188_I27@PURE_QUANTA.Q_CAP(CHIPS)':
 'A': CDS_PINID='A';
NODE_NAME     PC129_6 1
 '@T6G_MB_LIB.T6G(SCH_1):PAGE188_I29@PURE_QUANTA.Q_CAP(CHIPS)':
 'A': CDS_PINID='A';
NODE_NAME     PC130_6 1
 '@T6G_MB_LIB.T6G(SCH_1):PAGE188_I30@PURE_QUANTA.Q_CAP(CHIPS)':
 'A': CDS_PINID='A';
NODE_NAME     PC309_5 1
 '@T6G_MB_LIB.T6G(SCH_1):PAGE188_I45@PURE_QUANTA.Q_CAP(CHIPS)':
 'A': CDS_PINID='A';
NODE_NAME     PC310_5 1
 '@T6G_MB_LIB.T6G(SCH_1):PAGE188_I48@PURE_QUANTA.Q_CAP(CHIPS)':
 'A': CDS_PINID='A';
NODE_NAME     PC311_5 1
 '@T6G_MB_LIB.T6G(SCH_1):PAGE188_I49@PURE_QUANTA.Q_CAP(CHIPS)':
 'A': CDS_PINID='A';
NODE_NAME     PC312_5 1
 '@T6G_MB_LIB.T6G(SCH_1):PAGE188_I50@PURE_QUANTA.Q_CAP(CHIPS)':
 'A': CDS_PINID='A';
NODE_NAME     PC132_6 1
 '@T6G_MB_LIB.T6G(SCH_1):PAGE188_I55@PURE_QUANTA.Q_CAP(CHIPS)':
 'A': CDS_PINID='A';
NODE_NAME     PC313_5 1
 '@T6G_MB_LIB.T6G(SCH_1):PAGE188_I66@PURE_QUANTA.Q_CAP(CHIPS)':
 'A': CDS_PINID='A';
NODE_NAME     PU24 25_29
 '@T6G_MB_LIB.T6G(SCH_1):PAGE188_I73@PURE_QUANTA.ISL99390FRZTR5935(CHIPS)':
 'VIN1': CDS_PINID='VIN1';
NODE_NAME     PU24 30
 '@T6G_MB_LIB.T6G(SCH_1):PAGE188_I73@PURE_QUANTA.ISL99390FRZTR5935(CHIPS)':
 'VIN2': CDS_PINID='VIN2';
NET_NAME
'SW_P12V_AUX_PVDDCR_CPU1_P0_FLT'
 '@T6G_MB_LIB.T6G(SCH_1):SW_P12V_AUX_PVDDCR_CPU1_P0_FLT':
 C_SIGNAL='@t6g_mb_lib.t6g(sch_1):sw_p12v_aux_pvddcr_cpu1_p0_flt',
 CDS_GLOBAL_NET='TRUE';
NODE_NAME     PC88_2 1
 '@T6G_MB_LIB.T6G(SCH_1):PAGE176_I47@PURE_QUANTA.Q_CAP(CHIPS)':
 'A': CDS_PINID='A';
NODE_NAME     PC95_1 1
 '@T6G_MB_LIB.T6G(SCH_1):PAGE176_I65@PURE_QUANTA.Q_CAP(CHIPS)':
 'A': CDS_PINID='A';
NODE_NAME     PC101 1
 '@T6G_MB_LIB.T6G(SCH_1):PAGE176_I66@PURE_QUANTA.Q_CAPP(CHIPS)':
 'A': CDS_PINID='A';
NODE_NAME     PC114_6 1
 '@T6G_MB_LIB.T6G(SCH_1):PAGE178_I40@PURE_QUANTA.Q_CAP(CHIPS)':
 'A': CDS_PINID='A';
NODE_NAME     PC135_5 1
 '@T6G_MB_LIB.T6G(SCH_1):PAGE178_I59@PURE_QUANTA.Q_CAP(CHIPS)':
 'A': CDS_PINID='A';
NODE_NAME     PC136_5 1
 '@T6G_MB_LIB.T6G(SCH_1):PAGE178_I60@PURE_QUANTA.Q_CAP(CHIPS)':
 'A': CDS_PINID='A';
NODE_NAME     PU2 25_29
 '@T6G_MB_LIB.T6G(SCH_1):PAGE176_I33@PURE_QUANTA.ISL99390FRZTR5935(CHIPS)':
 'VIN1': CDS_PINID='VIN1';
NODE_NAME     PU2 30
 '@T6G_MB_LIB.T6G(SCH_1):PAGE176_I33@PURE_QUANTA.ISL99390FRZTR5935(CHIPS)':
 'VIN2': CDS_PINID='VIN2';
NODE_NAME     PU13 25_29
 '@T6G_MB_LIB.T6G(SCH_1):PAGE176_I35@PURE_QUANTA.ISL99390FRZTR5935(CHIPS)':
 'VIN1': CDS_PINID='VIN1';
NODE_NAME     PU13 30
 '@T6G_MB_LIB.T6G(SCH_1):PAGE176_I35@PURE_QUANTA.ISL99390FRZTR5935(CHIPS)':
 'VIN2': CDS_PINID='VIN2';
NODE_NAME     PC86_2 1
 '@T6G_MB_LIB.T6G(SCH_1):PAGE176_I37@PURE_QUANTA.Q_CAP(CHIPS)':
 'A': CDS_PINID='A';
NODE_NAME     PC90_2 1
 '@T6G_MB_LIB.T6G(SCH_1):PAGE176_I48@PURE_QUANTA.Q_CAP(CHIPS)':
 'A': CDS_PINID='A';
NODE_NAME     PC93_2 1
 '@T6G_MB_LIB.T6G(SCH_1):PAGE176_I51@PURE_QUANTA.Q_CAP(CHIPS)':
 'A': CDS_PINID='A';
NODE_NAME     PC96_2 1
 '@T6G_MB_LIB.T6G(SCH_1):PAGE176_I52@PURE_QUANTA.Q_CAP(CHIPS)':
 'A': CDS_PINID='A';
NODE_NAME     PC85_1 1
 '@T6G_MB_LIB.T6G(SCH_1):PAGE176_I55@PURE_QUANTA.Q_CAP(CHIPS)':
 'A': CDS_PINID='A';
NODE_NAME     PC87_1 1
 '@T6G_MB_LIB.T6G(SCH_1):PAGE176_I59@PURE_QUANTA.Q_CAP(CHIPS)':
 'A': CDS_PINID='A';
NODE_NAME     PC89_1 1
 '@T6G_MB_LIB.T6G(SCH_1):PAGE176_I60@PURE_QUANTA.Q_CAP(CHIPS)':
 'A': CDS_PINID='A';
NODE_NAME     PC91_1 1
 '@T6G_MB_LIB.T6G(SCH_1):PAGE176_I64@PURE_QUANTA.Q_CAP(CHIPS)':
 'A': CDS_PINID='A';
NODE_NAME     PC104 1
 '@T6G_MB_LIB.T6G(SCH_1):PAGE176_I82@PURE_QUANTA.Q_CAPP(CHIPS)':
 'A': CDS_PINID='A';
NODE_NAME     PL12 1
 '@T6G_MB_LIB.T6G(SCH_1):PAGE176_I83@PURE_QUANTA.Q_INDUCTOR(CHIPS)':
 '1': CDS_PINID='\1\';
NODE_NAME     PU14 25_29
 '@T6G_MB_LIB.T6G(SCH_1):PAGE177_I21@PURE_QUANTA.ISL99390FRZTR5935(CHIPS)':
 'VIN1': CDS_PINID='VIN1';
NODE_NAME     PU14 30
 '@T6G_MB_LIB.T6G(SCH_1):PAGE177_I21@PURE_QUANTA.ISL99390FRZTR5935(CHIPS)':
 'VIN2': CDS_PINID='VIN2';
NODE_NAME     PU15 25_29
 '@T6G_MB_LIB.T6G(SCH_1):PAGE177_I23@PURE_QUANTA.ISL99390FRZTR5935(CHIPS)':
 'VIN1': CDS_PINID='VIN1';
NODE_NAME     PU15 30
 '@T6G_MB_LIB.T6G(SCH_1):PAGE177_I23@PURE_QUANTA.ISL99390FRZTR5935(CHIPS)':
 'VIN2': CDS_PINID='VIN2';
NODE_NAME     PC115_4 1
 '@T6G_MB_LIB.T6G(SCH_1):PAGE177_I24@PURE_QUANTA.Q_CAP(CHIPS)':
 'A': CDS_PINID='A';
NODE_NAME     PC116_3 1
 '@T6G_MB_LIB.T6G(SCH_1):PAGE177_I34@PURE_QUANTA.Q_CAP(CHIPS)':
 'A': CDS_PINID='A';
NODE_NAME     PC117_4 1
 '@T6G_MB_LIB.T6G(SCH_1):PAGE177_I43@PURE_QUANTA.Q_CAP(CHIPS)':
 'A': CDS_PINID='A';
NODE_NAME     PC119_4 1
 '@T6G_MB_LIB.T6G(SCH_1):PAGE177_I44@PURE_QUANTA.Q_CAP(CHIPS)':
 'A': CDS_PINID='A';
NODE_NAME     PC123_4 1
 '@T6G_MB_LIB.T6G(SCH_1):PAGE177_I47@PURE_QUANTA.Q_CAP(CHIPS)':
 'A': CDS_PINID='A';
NODE_NAME     PC125_4 1
 '@T6G_MB_LIB.T6G(SCH_1):PAGE177_I49@PURE_QUANTA.Q_CAP(CHIPS)':
 'A': CDS_PINID='A';
NODE_NAME     PC118_3 1
 '@T6G_MB_LIB.T6G(SCH_1):PAGE177_I60@PURE_QUANTA.Q_CAP(CHIPS)':
 'A': CDS_PINID='A';
NODE_NAME     PC120_3 1
 '@T6G_MB_LIB.T6G(SCH_1):PAGE177_I61@PURE_QUANTA.Q_CAP(CHIPS)':
 'A': CDS_PINID='A';
NODE_NAME     PC124_3 1
 '@T6G_MB_LIB.T6G(SCH_1):PAGE177_I65@PURE_QUANTA.Q_CAP(CHIPS)':
 'A': CDS_PINID='A';
NODE_NAME     PC126_3 1
 '@T6G_MB_LIB.T6G(SCH_1):PAGE177_I66@PURE_QUANTA.Q_CAP(CHIPS)':
 'A': CDS_PINID='A';
NODE_NAME     PU16 25_29
 '@T6G_MB_LIB.T6G(SCH_1):PAGE178_I22@PURE_QUANTA.ISL99390FRZTR5935(CHIPS)':
 'VIN1': CDS_PINID='VIN1';
NODE_NAME     PU16 30
 '@T6G_MB_LIB.T6G(SCH_1):PAGE178_I22@PURE_QUANTA.ISL99390FRZTR5935(CHIPS)':
 'VIN2': CDS_PINID='VIN2';
NODE_NAME     PC115_6 1
 '@T6G_MB_LIB.T6G(SCH_1):PAGE178_I41@PURE_QUANTA.Q_CAP(CHIPS)':
 'A': CDS_PINID='A';
NODE_NAME     PC116_6 1
 '@T6G_MB_LIB.T6G(SCH_1):PAGE178_I42@PURE_QUANTA.Q_CAP(CHIPS)':
 'A': CDS_PINID='A';
NODE_NAME     PC118_6 1
 '@T6G_MB_LIB.T6G(SCH_1):PAGE178_I45@PURE_QUANTA.Q_CAP(CHIPS)':
 'A': CDS_PINID='A';
NODE_NAME     PC119_6 1
 '@T6G_MB_LIB.T6G(SCH_1):PAGE178_I47@PURE_QUANTA.Q_CAP(CHIPS)':
 'A': CDS_PINID='A';
NODE_NAME     PC134_5 1
 '@T6G_MB_LIB.T6G(SCH_1):PAGE178_I58@PURE_QUANTA.Q_CAP(CHIPS)':
 'A': CDS_PINID='A';
NODE_NAME     PC138_5 1
 '@T6G_MB_LIB.T6G(SCH_1):PAGE178_I65@PURE_QUANTA.Q_CAP(CHIPS)':
 'A': CDS_PINID='A';
NODE_NAME     PC139_5 1
 '@T6G_MB_LIB.T6G(SCH_1):PAGE178_I66@PURE_QUANTA.Q_CAP(CHIPS)':
 'A': CDS_PINID='A';
NODE_NAME     PU11 25_29
 '@T6G_MB_LIB.T6G(SCH_1):PAGE178_I73@PURE_QUANTA.ISL99390FRZTR5935(CHIPS)':
 'VIN1': CDS_PINID='VIN1';
NODE_NAME     PU11 30
 '@T6G_MB_LIB.T6G(SCH_1):PAGE178_I73@PURE_QUANTA.ISL99390FRZTR5935(CHIPS)':
 'VIN2': CDS_PINID='VIN2';
NET_NAME
'SW_P12V_AUX_PVDDCR_CPU1_P1_FLT'
 '@T6G_MB_LIB.T6G(SCH_1):SW_P12V_AUX_PVDDCR_CPU1_P1_FLT':
 C_SIGNAL='@t6g_mb_lib.t6g(sch_1):sw_p12v_aux_pvddcr_cpu1_p1_flt',
 CDS_GLOBAL_NET='TRUE';
NODE_NAME     PC382_2 1
 '@T6G_MB_LIB.T6G(SCH_1):PAGE193_I46@PURE_QUANTA.Q_CAP(CHIPS)':
 'A': CDS_PINID='A';
NODE_NAME     PC409_4 1
 '@T6G_MB_LIB.T6G(SCH_1):PAGE194_I42@PURE_QUANTA.Q_CAP(CHIPS)':
 'A': CDS_PINID='A';
NODE_NAME     PC410_3 1
 '@T6G_MB_LIB.T6G(SCH_1):PAGE194_I55@PURE_QUANTA.Q_CAP(CHIPS)':
 'A': CDS_PINID='A';
NODE_NAME     PC140_6 1
 '@T6G_MB_LIB.T6G(SCH_1):PAGE195_I40@PURE_QUANTA.Q_CAP(CHIPS)':
 'A': CDS_PINID='A';
NODE_NAME     PC427_5 1
 '@T6G_MB_LIB.T6G(SCH_1):PAGE195_I60@PURE_QUANTA.Q_CAP(CHIPS)':
 'A': CDS_PINID='A';
NODE_NAME     PU5 25_29
 '@T6G_MB_LIB.T6G(SCH_1):PAGE193_I31@PURE_QUANTA.ISL99390FRZTR5935(CHIPS)':
 'VIN1': CDS_PINID='VIN1';
NODE_NAME     PU5 30
 '@T6G_MB_LIB.T6G(SCH_1):PAGE193_I31@PURE_QUANTA.ISL99390FRZTR5935(CHIPS)':
 'VIN2': CDS_PINID='VIN2';
NODE_NAME     PC376_2 1
 '@T6G_MB_LIB.T6G(SCH_1):PAGE193_I34@PURE_QUANTA.Q_CAP(CHIPS)':
 'A': CDS_PINID='A';
NODE_NAME     PC378_2 1
 '@T6G_MB_LIB.T6G(SCH_1):PAGE193_I42@PURE_QUANTA.Q_CAP(CHIPS)':
 'A': CDS_PINID='A';
NODE_NAME     PC380_2 1
 '@T6G_MB_LIB.T6G(SCH_1):PAGE193_I43@PURE_QUANTA.Q_CAP(CHIPS)':
 'A': CDS_PINID='A';
NODE_NAME     PC385_2 1
 '@T6G_MB_LIB.T6G(SCH_1):PAGE193_I48@PURE_QUANTA.Q_CAP(CHIPS)':
 'A': CDS_PINID='A';
NODE_NAME     PC375_1 1
 '@T6G_MB_LIB.T6G(SCH_1):PAGE193_I50@PURE_QUANTA.Q_CAP(CHIPS)':
 'A': CDS_PINID='A';
NODE_NAME     PC377_1 1
 '@T6G_MB_LIB.T6G(SCH_1):PAGE193_I53@PURE_QUANTA.Q_CAP(CHIPS)':
 'A': CDS_PINID='A';
NODE_NAME     PC379_1 1
 '@T6G_MB_LIB.T6G(SCH_1):PAGE193_I54@PURE_QUANTA.Q_CAP(CHIPS)':
 'A': CDS_PINID='A';
NODE_NAME     PC381_1 1
 '@T6G_MB_LIB.T6G(SCH_1):PAGE193_I58@PURE_QUANTA.Q_CAP(CHIPS)':
 'A': CDS_PINID='A';
NODE_NAME     PC384_1 1
 '@T6G_MB_LIB.T6G(SCH_1):PAGE193_I60@PURE_QUANTA.Q_CAP(CHIPS)':
 'A': CDS_PINID='A';
NODE_NAME     PL42 1
 '@T6G_MB_LIB.T6G(SCH_1):PAGE193_I79@PURE_QUANTA.Q_INDUCTOR(CHIPS)':
 '1': CDS_PINID='\1\';
NODE_NAME     PU35 25_29
 '@T6G_MB_LIB.T6G(SCH_1):PAGE193_I91@PURE_QUANTA.ISL99390FRZTR5935(CHIPS)':
 'VIN1': CDS_PINID='VIN1';
NODE_NAME     PU35 30
 '@T6G_MB_LIB.T6G(SCH_1):PAGE193_I91@PURE_QUANTA.ISL99390FRZTR5935(CHIPS)':
 'VIN2': CDS_PINID='VIN2';
NODE_NAME     PU36 25_29
 '@T6G_MB_LIB.T6G(SCH_1):PAGE194_I21@PURE_QUANTA.ISL99390FRZTR5935(CHIPS)':
 'VIN1': CDS_PINID='VIN1';
NODE_NAME     PU36 30
 '@T6G_MB_LIB.T6G(SCH_1):PAGE194_I21@PURE_QUANTA.ISL99390FRZTR5935(CHIPS)':
 'VIN2': CDS_PINID='VIN2';
NODE_NAME     PC405_4 1
 '@T6G_MB_LIB.T6G(SCH_1):PAGE194_I23@PURE_QUANTA.Q_CAP(CHIPS)':
 'A': CDS_PINID='A';
NODE_NAME     PC408_3 1
 '@T6G_MB_LIB.T6G(SCH_1):PAGE194_I33@PURE_QUANTA.Q_CAP(CHIPS)':
 'A': CDS_PINID='A';
NODE_NAME     PC407_4 1
 '@T6G_MB_LIB.T6G(SCH_1):PAGE194_I41@PURE_QUANTA.Q_CAP(CHIPS)':
 'A': CDS_PINID='A';
NODE_NAME     PC411_4 1
 '@T6G_MB_LIB.T6G(SCH_1):PAGE194_I45@PURE_QUANTA.Q_CAP(CHIPS)':
 'A': CDS_PINID='A';
NODE_NAME     PC415_4 1
 '@T6G_MB_LIB.T6G(SCH_1):PAGE194_I47@PURE_QUANTA.Q_CAP(CHIPS)':
 'A': CDS_PINID='A';
NODE_NAME     PC406_3 1
 '@T6G_MB_LIB.T6G(SCH_1):PAGE194_I54@PURE_QUANTA.Q_CAP(CHIPS)':
 'A': CDS_PINID='A';
NODE_NAME     PC412_3 1
 '@T6G_MB_LIB.T6G(SCH_1):PAGE194_I59@PURE_QUANTA.Q_CAP(CHIPS)':
 'A': CDS_PINID='A';
NODE_NAME     PC416_3 1
 '@T6G_MB_LIB.T6G(SCH_1):PAGE194_I60@PURE_QUANTA.Q_CAP(CHIPS)':
 'A': CDS_PINID='A';
NODE_NAME     PU37 25_29
 '@T6G_MB_LIB.T6G(SCH_1):PAGE194_I72@PURE_QUANTA.ISL99390FRZTR5935(CHIPS)':
 'VIN1': CDS_PINID='VIN1';
NODE_NAME     PU37 30
 '@T6G_MB_LIB.T6G(SCH_1):PAGE194_I72@PURE_QUANTA.ISL99390FRZTR5935(CHIPS)':
 'VIN2': CDS_PINID='VIN2';
NODE_NAME     PU33 25_29
 '@T6G_MB_LIB.T6G(SCH_1):PAGE195_I19@PURE_QUANTA.ISL99390FRZTR5935(CHIPS)':
 'VIN1': CDS_PINID='VIN1';
NODE_NAME     PU33 30
 '@T6G_MB_LIB.T6G(SCH_1):PAGE195_I19@PURE_QUANTA.ISL99390FRZTR5935(CHIPS)':
 'VIN2': CDS_PINID='VIN2';
NODE_NAME     PC141_6 1
 '@T6G_MB_LIB.T6G(SCH_1):PAGE195_I38@PURE_QUANTA.Q_CAP(CHIPS)':
 'A': CDS_PINID='A';
NODE_NAME     PC144_6 1
 '@T6G_MB_LIB.T6G(SCH_1):PAGE195_I41@PURE_QUANTA.Q_CAP(CHIPS)':
 'A': CDS_PINID='A';
NODE_NAME     PC145_6 1
 '@T6G_MB_LIB.T6G(SCH_1):PAGE195_I44@PURE_QUANTA.Q_CAP(CHIPS)':
 'A': CDS_PINID='A';
NODE_NAME     PC147_6 1
 '@T6G_MB_LIB.T6G(SCH_1):PAGE195_I47@PURE_QUANTA.Q_CAP(CHIPS)':
 'A': CDS_PINID='A';
NODE_NAME     PC425_5 1
 '@T6G_MB_LIB.T6G(SCH_1):PAGE195_I54@PURE_QUANTA.Q_CAP(CHIPS)':
 'A': CDS_PINID='A';
NODE_NAME     PC424_5 1
 '@T6G_MB_LIB.T6G(SCH_1):PAGE195_I55@PURE_QUANTA.Q_CAP(CHIPS)':
 'A': CDS_PINID='A';
NODE_NAME     PC426_5 1
 '@T6G_MB_LIB.T6G(SCH_1):PAGE195_I56@PURE_QUANTA.Q_CAP(CHIPS)':
 'A': CDS_PINID='A';
NODE_NAME     PC429_5 1
 '@T6G_MB_LIB.T6G(SCH_1):PAGE195_I61@PURE_QUANTA.Q_CAP(CHIPS)':
 'A': CDS_PINID='A';
NODE_NAME     PU38 25_29
 '@T6G_MB_LIB.T6G(SCH_1):PAGE195_I73@PURE_QUANTA.ISL99390FRZTR5935(CHIPS)':
 'VIN1': CDS_PINID='VIN1';
NODE_NAME     PU38 30
 '@T6G_MB_LIB.T6G(SCH_1):PAGE195_I73@PURE_QUANTA.ISL99390FRZTR5935(CHIPS)':
 'VIN2': CDS_PINID='VIN2';
NODE_NAME     PC393 1
 '@T6G_MB_LIB.T6G(SCH_1):PAGE193_I92@PURE_QUANTA.Q_CAPP(CHIPS)':
 'A': CDS_PINID='A';
NODE_NAME     PC390 1
 '@T6G_MB_LIB.T6G(SCH_1):PAGE193_I93@PURE_QUANTA.Q_CAPP(CHIPS)':
 'A': CDS_PINID='A';
NET_NAME
'SW_P12V_AUX_PVDDCR_SOC_P0_FLT'
 '@T6G_MB_LIB.T6G(SCH_1):SW_P12V_AUX_PVDDCR_SOC_P0_FLT':
 C_SIGNAL='@t6g_mb_lib.t6g(sch_1):sw_p12v_aux_pvddcr_soc_p0_flt',
 CDS_GLOBAL_NET='TRUE';
NODE_NAME     PC584_2 1
 '@T6G_MB_LIB.T6G(SCH_1):PAGE173_I23@PURE_QUANTA.Q_CAP(CHIPS)':
 'A': CDS_PINID='A';
NODE_NAME     PC588_2 1
 '@T6G_MB_LIB.T6G(SCH_1):PAGE173_I24@PURE_QUANTA.Q_CAP(CHIPS)':
 'A': CDS_PINID='A';
NODE_NAME     PC590_2 1
 '@T6G_MB_LIB.T6G(SCH_1):PAGE173_I25@PURE_QUANTA.Q_CAP(CHIPS)':
 'A': CDS_PINID='A';
NODE_NAME     PC583_1 1
 '@T6G_MB_LIB.T6G(SCH_1):PAGE173_I43@PURE_QUANTA.Q_CAP(CHIPS)':
 'A': CDS_PINID='A';
NODE_NAME     PC608_3 1
 '@T6G_MB_LIB.T6G(SCH_1):PAGE174_I21@PURE_QUANTA.Q_CAP(CHIPS)':
 'A': CDS_PINID='A';
NODE_NAME     PC610_3 1
 '@T6G_MB_LIB.T6G(SCH_1):PAGE174_I22@PURE_QUANTA.Q_CAP(CHIPS)':
 'A': CDS_PINID='A';
NODE_NAME     PC611_3 1
 '@T6G_MB_LIB.T6G(SCH_1):PAGE174_I31@PURE_QUANTA.Q_CAP(CHIPS)':
 'A': CDS_PINID='A';
NODE_NAME     PC613_3 1
 '@T6G_MB_LIB.T6G(SCH_1):PAGE174_I32@PURE_QUANTA.Q_CAP(CHIPS)':
 'A': CDS_PINID='A';
NODE_NAME     PC609_3 1
 '@T6G_MB_LIB.T6G(SCH_1):PAGE174_I37@PURE_QUANTA.Q_CAP(CHIPS)':
 'A': CDS_PINID='A';
NODE_NAME     PU51 25_29
 '@T6G_MB_LIB.T6G(SCH_1):PAGE174_I38@PURE_QUANTA.ISL99390FRZTR5935(CHIPS)':
 'VIN1': CDS_PINID='VIN1';
NODE_NAME     PU51 30
 '@T6G_MB_LIB.T6G(SCH_1):PAGE174_I38@PURE_QUANTA.ISL99390FRZTR5935(CHIPS)':
 'VIN2': CDS_PINID='VIN2';
NODE_NAME     PC586_2 1
 '@T6G_MB_LIB.T6G(SCH_1):PAGE173_I21@PURE_QUANTA.Q_CAP(CHIPS)':
 'A': CDS_PINID='A';
NODE_NAME     PU49 25_29
 '@T6G_MB_LIB.T6G(SCH_1):PAGE173_I41@PURE_QUANTA.ISL99390FRZTR5935(CHIPS)':
 'VIN1': CDS_PINID='VIN1';
NODE_NAME     PU49 30
 '@T6G_MB_LIB.T6G(SCH_1):PAGE173_I41@PURE_QUANTA.ISL99390FRZTR5935(CHIPS)':
 'VIN2': CDS_PINID='VIN2';
NODE_NAME     PC585_1 1
 '@T6G_MB_LIB.T6G(SCH_1):PAGE173_I44@PURE_QUANTA.Q_CAP(CHIPS)':
 'A': CDS_PINID='A';
NODE_NAME     PC587_1 1
 '@T6G_MB_LIB.T6G(SCH_1):PAGE173_I49@PURE_QUANTA.Q_CAP(CHIPS)':
 'A': CDS_PINID='A';
NODE_NAME     PC589_1 1
 '@T6G_MB_LIB.T6G(SCH_1):PAGE173_I50@PURE_QUANTA.Q_CAP(CHIPS)':
 'A': CDS_PINID='A';
NODE_NAME     PC591_1 1
 '@T6G_MB_LIB.T6G(SCH_1):PAGE173_I51@PURE_QUANTA.Q_CAP(CHIPS)':
 'A': CDS_PINID='A';
NODE_NAME     PC592_2 1
 '@T6G_MB_LIB.T6G(SCH_1):PAGE173_I56@PURE_QUANTA.Q_CAP(CHIPS)':
 'A': CDS_PINID='A';
NODE_NAME     PC595_2 1
 '@T6G_MB_LIB.T6G(SCH_1):PAGE173_I57@PURE_QUANTA.Q_CAP(CHIPS)':
 'A': CDS_PINID='A';
NODE_NAME     PC593_1 1
 '@T6G_MB_LIB.T6G(SCH_1):PAGE173_I72@PURE_QUANTA.Q_CAP(CHIPS)':
 'A': CDS_PINID='A';
NODE_NAME     PC596 1
 '@T6G_MB_LIB.T6G(SCH_1):PAGE173_I73@PURE_QUANTA.Q_CAPP(CHIPS)':
 'A': CDS_PINID='A';
NODE_NAME     PL65 1
 '@T6G_MB_LIB.T6G(SCH_1):PAGE173_I74@PURE_QUANTA.Q_INDUCTOR(CHIPS)':
 '1': CDS_PINID='\1\';
NODE_NAME     PU50 25_29
 '@T6G_MB_LIB.T6G(SCH_1):PAGE173_I86@PURE_QUANTA.ISL99390FRZTR5935(CHIPS)':
 'VIN1': CDS_PINID='VIN1';
NODE_NAME     PU50 30
 '@T6G_MB_LIB.T6G(SCH_1):PAGE173_I86@PURE_QUANTA.ISL99390FRZTR5935(CHIPS)':
 'VIN2': CDS_PINID='VIN2';
NODE_NAME     PC612_3 1
 '@T6G_MB_LIB.T6G(SCH_1):PAGE174_I34@PURE_QUANTA.Q_CAP(CHIPS)':
 'A': CDS_PINID='A';
NODE_NAME     PC8009 1
 '@T6G_MB_LIB.T6G(SCH_1):PAGE173_I87@PURE_QUANTA.Q_CAP(CHIPS)':
 'A': CDS_PINID='A';
NODE_NAME     PC8010 1
 '@T6G_MB_LIB.T6G(SCH_1):PAGE173_I88@PURE_QUANTA.Q_CAP(CHIPS)':
 'A': CDS_PINID='A';
NET_NAME
'SW_P12V_AUX_PVDDCR_SOC_P1_FLT'
 '@T6G_MB_LIB.T6G(SCH_1):SW_P12V_AUX_PVDDCR_SOC_P1_FLT':
 C_SIGNAL='@t6g_mb_lib.t6g(sch_1):sw_p12v_aux_pvddcr_soc_p1_flt',
 CDS_GLOBAL_NET='TRUE';
NODE_NAME     PC326_2 1
 '@T6G_MB_LIB.T6G(SCH_1):PAGE190_I22@PURE_QUANTA.Q_CAP(CHIPS)':
 'A': CDS_PINID='A';
NODE_NAME     PC324_2 1
 '@T6G_MB_LIB.T6G(SCH_1):PAGE190_I25@PURE_QUANTA.Q_CAP(CHIPS)':
 'A': CDS_PINID='A';
NODE_NAME     PC328_2 1
 '@T6G_MB_LIB.T6G(SCH_1):PAGE190_I26@PURE_QUANTA.Q_CAP(CHIPS)':
 'A': CDS_PINID='A';
NODE_NAME     PC325_1 1
 '@T6G_MB_LIB.T6G(SCH_1):PAGE190_I43@PURE_QUANTA.Q_CAP(CHIPS)':
 'A': CDS_PINID='A';
NODE_NAME     PC323_1 1
 '@T6G_MB_LIB.T6G(SCH_1):PAGE190_I44@PURE_QUANTA.Q_CAP(CHIPS)':
 'A': CDS_PINID='A';
NODE_NAME     PC327_1 1
 '@T6G_MB_LIB.T6G(SCH_1):PAGE190_I48@PURE_QUANTA.Q_CAP(CHIPS)':
 'A': CDS_PINID='A';
NODE_NAME     PC349_3 1
 '@T6G_MB_LIB.T6G(SCH_1):PAGE191_I20@PURE_QUANTA.Q_CAP(CHIPS)':
 'A': CDS_PINID='A';
NODE_NAME     PC350_3 1
 '@T6G_MB_LIB.T6G(SCH_1):PAGE191_I22@PURE_QUANTA.Q_CAP(CHIPS)':
 'A': CDS_PINID='A';
NODE_NAME     PC351_3 1
 '@T6G_MB_LIB.T6G(SCH_1):PAGE191_I31@PURE_QUANTA.Q_CAP(CHIPS)':
 'A': CDS_PINID='A';
NODE_NAME     PC352_3 1
 '@T6G_MB_LIB.T6G(SCH_1):PAGE191_I32@PURE_QUANTA.Q_CAP(CHIPS)':
 'A': CDS_PINID='A';
NODE_NAME     PC353_3 1
 '@T6G_MB_LIB.T6G(SCH_1):PAGE191_I34@PURE_QUANTA.Q_CAP(CHIPS)':
 'A': CDS_PINID='A';
NODE_NAME     PU32 25_29
 '@T6G_MB_LIB.T6G(SCH_1):PAGE191_I38@PURE_QUANTA.ISL99390FRZTR5935(CHIPS)':
 'VIN1': CDS_PINID='VIN1';
NODE_NAME     PU32 30
 '@T6G_MB_LIB.T6G(SCH_1):PAGE191_I38@PURE_QUANTA.ISL99390FRZTR5935(CHIPS)':
 'VIN2': CDS_PINID='VIN2';
NODE_NAME     PC348_3 1
 '@T6G_MB_LIB.T6G(SCH_1):PAGE191_I19@PURE_QUANTA.Q_CAP(CHIPS)':
 'A': CDS_PINID='A';
NODE_NAME     PU30 25_29
 '@T6G_MB_LIB.T6G(SCH_1):PAGE190_I17@PURE_QUANTA.ISL99390FRZTR5935(CHIPS)':
 'VIN1': CDS_PINID='VIN1';
NODE_NAME     PU30 30
 '@T6G_MB_LIB.T6G(SCH_1):PAGE190_I17@PURE_QUANTA.ISL99390FRZTR5935(CHIPS)':
 'VIN2': CDS_PINID='VIN2';
NODE_NAME     PC330_2 1
 '@T6G_MB_LIB.T6G(SCH_1):PAGE190_I27@PURE_QUANTA.Q_CAP(CHIPS)':
 'A': CDS_PINID='A';
NODE_NAME     PC329_1 1
 '@T6G_MB_LIB.T6G(SCH_1):PAGE190_I49@PURE_QUANTA.Q_CAP(CHIPS)':
 'A': CDS_PINID='A';
NODE_NAME     PC331_1 1
 '@T6G_MB_LIB.T6G(SCH_1):PAGE190_I50@PURE_QUANTA.Q_CAP(CHIPS)':
 'A': CDS_PINID='A';
NODE_NAME     PC332_2 1
 '@T6G_MB_LIB.T6G(SCH_1):PAGE190_I56@PURE_QUANTA.Q_CAP(CHIPS)':
 'A': CDS_PINID='A';
NODE_NAME     PC335_2 1
 '@T6G_MB_LIB.T6G(SCH_1):PAGE190_I57@PURE_QUANTA.Q_CAP(CHIPS)':
 'A': CDS_PINID='A';
NODE_NAME     PC334_1 1
 '@T6G_MB_LIB.T6G(SCH_1):PAGE190_I71@PURE_QUANTA.Q_CAP(CHIPS)':
 'A': CDS_PINID='A';
NODE_NAME     PC336 1
 '@T6G_MB_LIB.T6G(SCH_1):PAGE190_I73@PURE_QUANTA.Q_CAPP(CHIPS)':
 'A': CDS_PINID='A';
NODE_NAME     PL37 1
 '@T6G_MB_LIB.T6G(SCH_1):PAGE190_I74@PURE_QUANTA.Q_INDUCTOR(CHIPS)':
 '1': CDS_PINID='\1\';
NODE_NAME     PU31 25_29
 '@T6G_MB_LIB.T6G(SCH_1):PAGE190_I86@PURE_QUANTA.ISL99390FRZTR5935(CHIPS)':
 'VIN1': CDS_PINID='VIN1';
NODE_NAME     PU31 30
 '@T6G_MB_LIB.T6G(SCH_1):PAGE190_I86@PURE_QUANTA.ISL99390FRZTR5935(CHIPS)':
 'VIN2': CDS_PINID='VIN2';
NODE_NAME     PC8011 1
 '@T6G_MB_LIB.T6G(SCH_1):PAGE190_I87@PURE_QUANTA.Q_CAP(CHIPS)':
 'A': CDS_PINID='A';
NODE_NAME     PC8012 1
 '@T6G_MB_LIB.T6G(SCH_1):PAGE190_I88@PURE_QUANTA.Q_CAP(CHIPS)':
 'A': CDS_PINID='A';
NET_NAME
'SW_P12V_AUX_PVDDIO_P0_FLT'
 '@T6G_MB_LIB.T6G(SCH_1):SW_P12V_AUX_PVDDIO_P0_FLT':
 C_SIGNAL='@t6g_mb_lib.t6g(sch_1):sw_p12v_aux_pvddio_p0_flt',
 CDS_GLOBAL_NET='TRUE';
NODE_NAME     PC182_4 1
 '@T6G_MB_LIB.T6G(SCH_1):PAGE181_I46@PURE_QUANTA.Q_CAP(CHIPS)':
 'A': CDS_PINID='A';
NODE_NAME     PU18 25_29
 '@T6G_MB_LIB.T6G(SCH_1):PAGE180_I15@PURE_QUANTA.ISL99390FRZTR5935(CHIPS)':
 'VIN1': CDS_PINID='VIN1';
NODE_NAME     PU18 30
 '@T6G_MB_LIB.T6G(SCH_1):PAGE180_I15@PURE_QUANTA.ISL99390FRZTR5935(CHIPS)':
 'VIN2': CDS_PINID='VIN2';
NODE_NAME     PC149_2 1
 '@T6G_MB_LIB.T6G(SCH_1):PAGE180_I18@PURE_QUANTA.Q_CAP(CHIPS)':
 'A': CDS_PINID='A';
NODE_NAME     PC151_2 1
 '@T6G_MB_LIB.T6G(SCH_1):PAGE180_I42@PURE_QUANTA.Q_CAP(CHIPS)':
 'A': CDS_PINID='A';
NODE_NAME     PC153_2 1
 '@T6G_MB_LIB.T6G(SCH_1):PAGE180_I43@PURE_QUANTA.Q_CAP(CHIPS)':
 'A': CDS_PINID='A';
NODE_NAME     PC157_2 1
 '@T6G_MB_LIB.T6G(SCH_1):PAGE180_I45@PURE_QUANTA.Q_CAP(CHIPS)':
 'A': CDS_PINID='A';
NODE_NAME     PC159_2 1
 '@T6G_MB_LIB.T6G(SCH_1):PAGE180_I47@PURE_QUANTA.Q_CAP(CHIPS)':
 'A': CDS_PINID='A';
NODE_NAME     PC158_1 1
 '@T6G_MB_LIB.T6G(SCH_1):PAGE180_I66@PURE_QUANTA.Q_CAP(CHIPS)':
 'A': CDS_PINID='A';
NODE_NAME     PC164 1
 '@T6G_MB_LIB.T6G(SCH_1):PAGE180_I67@PURE_QUANTA.Q_CAPP(CHIPS)':
 'A': CDS_PINID='A';
NODE_NAME     PL19 1
 '@T6G_MB_LIB.T6G(SCH_1):PAGE180_I69@PURE_QUANTA.Q_INDUCTOR(CHIPS)':
 '1': CDS_PINID='\1\';
NODE_NAME     PC154_1 1
 '@T6G_MB_LIB.T6G(SCH_1):PAGE180_I80@PURE_QUANTA.Q_CAP(CHIPS)':
 'A': CDS_PINID='A';
NODE_NAME     PC152_1 1
 '@T6G_MB_LIB.T6G(SCH_1):PAGE180_I81@PURE_QUANTA.Q_CAP(CHIPS)':
 'A': CDS_PINID='A';
NODE_NAME     PC150_1 1
 '@T6G_MB_LIB.T6G(SCH_1):PAGE180_I82@PURE_QUANTA.Q_CAP(CHIPS)':
 'A': CDS_PINID='A';
NODE_NAME     PC148_1 1
 '@T6G_MB_LIB.T6G(SCH_1):PAGE180_I83@PURE_QUANTA.Q_CAP(CHIPS)':
 'A': CDS_PINID='A';
NODE_NAME     PU17 25_29
 '@T6G_MB_LIB.T6G(SCH_1):PAGE180_I84@PURE_QUANTA.ISL99390FRZTR5935(CHIPS)':
 'VIN1': CDS_PINID='VIN1';
NODE_NAME     PU17 30
 '@T6G_MB_LIB.T6G(SCH_1):PAGE180_I84@PURE_QUANTA.ISL99390FRZTR5935(CHIPS)':
 'VIN2': CDS_PINID='VIN2';
NODE_NAME     PC178_4 1
 '@T6G_MB_LIB.T6G(SCH_1):PAGE181_I17@PURE_QUANTA.Q_CAP(CHIPS)':
 'A': CDS_PINID='A';
NODE_NAME     PU19 25_29
 '@T6G_MB_LIB.T6G(SCH_1):PAGE181_I32@PURE_QUANTA.ISL99390FRZTR5935(CHIPS)':
 'VIN1': CDS_PINID='VIN1';
NODE_NAME     PU19 30
 '@T6G_MB_LIB.T6G(SCH_1):PAGE181_I32@PURE_QUANTA.ISL99390FRZTR5935(CHIPS)':
 'VIN2': CDS_PINID='VIN2';
NODE_NAME     PC177_3 1
 '@T6G_MB_LIB.T6G(SCH_1):PAGE181_I35@PURE_QUANTA.Q_CAP(CHIPS)':
 'A': CDS_PINID='A';
NODE_NAME     PC179_3 1
 '@T6G_MB_LIB.T6G(SCH_1):PAGE181_I36@PURE_QUANTA.Q_CAP(CHIPS)':
 'A': CDS_PINID='A';
NODE_NAME     PC180_4 1
 '@T6G_MB_LIB.T6G(SCH_1):PAGE181_I45@PURE_QUANTA.Q_CAP(CHIPS)':
 'A': CDS_PINID='A';
NODE_NAME     PC185_4 1
 '@T6G_MB_LIB.T6G(SCH_1):PAGE181_I47@PURE_QUANTA.Q_CAP(CHIPS)':
 'A': CDS_PINID='A';
NODE_NAME     PC188_4 1
 '@T6G_MB_LIB.T6G(SCH_1):PAGE181_I49@PURE_QUANTA.Q_CAP(CHIPS)':
 'A': CDS_PINID='A';
NODE_NAME     PC181_3 1
 '@T6G_MB_LIB.T6G(SCH_1):PAGE181_I58@PURE_QUANTA.Q_CAP(CHIPS)':
 'A': CDS_PINID='A';
NODE_NAME     PC184_3 1
 '@T6G_MB_LIB.T6G(SCH_1):PAGE181_I60@PURE_QUANTA.Q_CAP(CHIPS)':
 'A': CDS_PINID='A';
NODE_NAME     PC187_3 1
 '@T6G_MB_LIB.T6G(SCH_1):PAGE181_I63@PURE_QUANTA.Q_CAP(CHIPS)':
 'A': CDS_PINID='A';
NODE_NAME     PU20 25_29
 '@T6G_MB_LIB.T6G(SCH_1):PAGE181_I73@PURE_QUANTA.ISL99390FRZTR5935(CHIPS)':
 'VIN1': CDS_PINID='VIN1';
NODE_NAME     PU20 30
 '@T6G_MB_LIB.T6G(SCH_1):PAGE181_I73@PURE_QUANTA.ISL99390FRZTR5935(CHIPS)':
 'VIN2': CDS_PINID='VIN2';
NODE_NAME     PC7000 1
 '@T6G_MB_LIB.T6G(SCH_1):PAGE180_I85@PURE_QUANTA.Q_CAP(CHIPS)':
 'A': CDS_PINID='A';
NET_NAME
'SW_P12V_AUX_PVDDIO_P1_FLT'
 '@T6G_MB_LIB.T6G(SCH_1):SW_P12V_AUX_PVDDIO_P1_FLT':
 C_SIGNAL='@t6g_mb_lib.t6g(sch_1):sw_p12v_aux_pvddio_p1_flt',
 CDS_GLOBAL_NET='TRUE';
NODE_NAME     PU53 25_29
 '@T6G_MB_LIB.T6G(SCH_1):PAGE198_I15@PURE_QUANTA.ISL99390FRZTR5935(CHIPS)':
 'VIN1': CDS_PINID='VIN1';
NODE_NAME     PU53 30
 '@T6G_MB_LIB.T6G(SCH_1):PAGE198_I15@PURE_QUANTA.ISL99390FRZTR5935(CHIPS)':
 'VIN2': CDS_PINID='VIN2';
NODE_NAME     PC629_4 1
 '@T6G_MB_LIB.T6G(SCH_1):PAGE198_I46@PURE_QUANTA.Q_CAP(CHIPS)':
 'A': CDS_PINID='A';
NODE_NAME     PC632_3 1
 '@T6G_MB_LIB.T6G(SCH_1):PAGE198_I65@PURE_QUANTA.Q_CAP(CHIPS)':
 'A': CDS_PINID='A';
NODE_NAME     PC439_2 1
 '@T6G_MB_LIB.T6G(SCH_1):PAGE197_I21@PURE_QUANTA.Q_CAP(CHIPS)':
 'A': CDS_PINID='A';
NODE_NAME     PC441_2 1
 '@T6G_MB_LIB.T6G(SCH_1):PAGE197_I23@PURE_QUANTA.Q_CAP(CHIPS)':
 'A': CDS_PINID='A';
NODE_NAME     PU39 25_29
 '@T6G_MB_LIB.T6G(SCH_1):PAGE197_I39@PURE_QUANTA.ISL99390FRZTR5935(CHIPS)':
 'VIN1': CDS_PINID='VIN1';
NODE_NAME     PU39 30
 '@T6G_MB_LIB.T6G(SCH_1):PAGE197_I39@PURE_QUANTA.ISL99390FRZTR5935(CHIPS)':
 'VIN2': CDS_PINID='VIN2';
NODE_NAME     PC438_1 1
 '@T6G_MB_LIB.T6G(SCH_1):PAGE197_I41@PURE_QUANTA.Q_CAP(CHIPS)':
 'A': CDS_PINID='A';
NODE_NAME     PC440_1 1
 '@T6G_MB_LIB.T6G(SCH_1):PAGE197_I42@PURE_QUANTA.Q_CAP(CHIPS)':
 'A': CDS_PINID='A';
NODE_NAME     PC442_1 1
 '@T6G_MB_LIB.T6G(SCH_1):PAGE197_I44@PURE_QUANTA.Q_CAP(CHIPS)':
 'A': CDS_PINID='A';
NODE_NAME     PC443_2 1
 '@T6G_MB_LIB.T6G(SCH_1):PAGE197_I48@PURE_QUANTA.Q_CAP(CHIPS)':
 'A': CDS_PINID='A';
NODE_NAME     PC446_2 1
 '@T6G_MB_LIB.T6G(SCH_1):PAGE197_I49@PURE_QUANTA.Q_CAP(CHIPS)':
 'A': CDS_PINID='A';
NODE_NAME     PC449_2 1
 '@T6G_MB_LIB.T6G(SCH_1):PAGE197_I52@PURE_QUANTA.Q_CAP(CHIPS)':
 'A': CDS_PINID='A';
NODE_NAME     PC444_1 1
 '@T6G_MB_LIB.T6G(SCH_1):PAGE197_I66@PURE_QUANTA.Q_CAP(CHIPS)':
 'A': CDS_PINID='A';
NODE_NAME     PC448_1 1
 '@T6G_MB_LIB.T6G(SCH_1):PAGE197_I69@PURE_QUANTA.Q_CAP(CHIPS)':
 'A': CDS_PINID='A';
NODE_NAME     PL49 1
 '@T6G_MB_LIB.T6G(SCH_1):PAGE197_I72@PURE_QUANTA.Q_INDUCTOR(CHIPS)':
 '1': CDS_PINID='\1\';
NODE_NAME     PU40 25_29
 '@T6G_MB_LIB.T6G(SCH_1):PAGE197_I84@PURE_QUANTA.ISL99390FRZTR5935(CHIPS)':
 'VIN1': CDS_PINID='VIN1';
NODE_NAME     PU40 30
 '@T6G_MB_LIB.T6G(SCH_1):PAGE197_I84@PURE_QUANTA.ISL99390FRZTR5935(CHIPS)':
 'VIN2': CDS_PINID='VIN2';
NODE_NAME     PC623_4 1
 '@T6G_MB_LIB.T6G(SCH_1):PAGE198_I18@PURE_QUANTA.Q_CAP(CHIPS)':
 'A': CDS_PINID='A';
NODE_NAME     PC622_3 1
 '@T6G_MB_LIB.T6G(SCH_1):PAGE198_I35@PURE_QUANTA.Q_CAP(CHIPS)':
 'A': CDS_PINID='A';
NODE_NAME     PC624_3 1
 '@T6G_MB_LIB.T6G(SCH_1):PAGE198_I36@PURE_QUANTA.Q_CAP(CHIPS)':
 'A': CDS_PINID='A';
NODE_NAME     PC625_4 1
 '@T6G_MB_LIB.T6G(SCH_1):PAGE198_I45@PURE_QUANTA.Q_CAP(CHIPS)':
 'A': CDS_PINID='A';
NODE_NAME     PC633_4 1
 '@T6G_MB_LIB.T6G(SCH_1):PAGE198_I48@PURE_QUANTA.Q_CAP(CHIPS)':
 'A': CDS_PINID='A';
NODE_NAME     PC626_3 1
 '@T6G_MB_LIB.T6G(SCH_1):PAGE198_I60@PURE_QUANTA.Q_CAP(CHIPS)':
 'A': CDS_PINID='A';
NODE_NAME     PC628_3 1
 '@T6G_MB_LIB.T6G(SCH_1):PAGE198_I61@PURE_QUANTA.Q_CAP(CHIPS)':
 'A': CDS_PINID='A';
NODE_NAME     PC627_4 1
 '@T6G_MB_LIB.T6G(SCH_1):PAGE198_I72@PURE_QUANTA.Q_CAP(CHIPS)':
 'A': CDS_PINID='A';
NODE_NAME     PU52 25_29
 '@T6G_MB_LIB.T6G(SCH_1):PAGE198_I73@PURE_QUANTA.ISL99390FRZTR5935(CHIPS)':
 'VIN1': CDS_PINID='VIN1';
NODE_NAME     PU52 30
 '@T6G_MB_LIB.T6G(SCH_1):PAGE198_I73@PURE_QUANTA.ISL99390FRZTR5935(CHIPS)':
 'VIN2': CDS_PINID='VIN2';
NODE_NAME     PC454 1
 '@T6G_MB_LIB.T6G(SCH_1):PAGE197_I85@PURE_QUANTA.Q_CAPP(CHIPS)':
 'A': CDS_PINID='A';
NODE_NAME     PC7001 1
 '@T6G_MB_LIB.T6G(SCH_1):PAGE197_I86@PURE_QUANTA.Q_CAP(CHIPS)':
 'A': CDS_PINID='A';
NET_NAME
'SW_P12V_AUX_PVDD_33_S5_FLT'
 '@T6G_MB_LIB.T6G(SCH_1):SW_P12V_AUX_PVDD_33_S5_FLT':
 C_SIGNAL='@t6g_mb_lib.t6g(sch_1):sw_p12v_aux_pvdd_33_s5_flt';
NODE_NAME     PL71 2
 '@T6G_MB_LIB.T6G(SCH_1):PAGE167_I10@PURE_QUANTA.Q_INDUCTOR(CHIPS)':
 '2': CDS_PINID='\2\';
NODE_NAME     PC119 1
 '@T6G_MB_LIB.T6G(SCH_1):PAGE167_I12@PURE_QUANTA.Q_CAP(CHIPS)':
 'A': CDS_PINID='A';
NODE_NAME     PC120 1
 '@T6G_MB_LIB.T6G(SCH_1):PAGE167_I13@PURE_QUANTA.Q_CAP(CHIPS)':
 'A': CDS_PINID='A';
NODE_NAME     PC123 1
 '@T6G_MB_LIB.T6G(SCH_1):PAGE167_I29@PURE_QUANTA.Q_CAP(CHIPS)':
 'A': CDS_PINID='A';
NODE_NAME     PC126 1
 '@T6G_MB_LIB.T6G(SCH_1):PAGE167_I30@PURE_QUANTA.Q_CAP(CHIPS)':
 'A': CDS_PINID='A';
NODE_NAME     PU55 10
 '@T6G_MB_LIB.T6G(SCH_1):PAGE167_I41@PURE_QUANTA.MPQ8633AGLEC807Z(CHIPS)':
 'VIN1': CDS_PINID='VIN1';
NODE_NAME     PU55 21
 '@T6G_MB_LIB.T6G(SCH_1):PAGE167_I41@PURE_QUANTA.MPQ8633AGLEC807Z(CHIPS)':
 'VIN2': CDS_PINID='VIN2';
NODE_NAME     PC8000 1
 '@T6G_MB_LIB.T6G(SCH_1):PAGE167_I44@PURE_QUANTA.Q_CAP(CHIPS)':
 'A': CDS_PINID='A';
NODE_NAME     PC8001 1
 '@T6G_MB_LIB.T6G(SCH_1):PAGE167_I45@PURE_QUANTA.Q_CAP(CHIPS)':
 'A': CDS_PINID='A';
NET_NAME
'SW_P1V2_AUX_BT'
 '@T6G_MB_LIB.T6G(SCH_1):SW_P1V2_AUX_BT':
 C_SIGNAL='@t6g_mb_lib.t6g(sch_1):sw_p1v2_aux_bt';
NODE_NAME     PU6001 10
 '@T6G_MB_LIB.T6G(SCH_1):PAGE380_I16@PURE_QUANTA.MPQ8626GDZ(CHIPS)':
 'BST': CDS_PINID='BST';
NODE_NAME     PR8004 1
 '@T6G_MB_LIB.T6G(SCH_1):PAGE380_I45@PURE_QUANTA.Q_RES(CHIPS)':
 'A': CDS_PINID='A';
NET_NAME
'SW_P1V2_AUX_BT_R'
 '@T6G_MB_LIB.T6G(SCH_1):SW_P1V2_AUX_BT_R':
 C_SIGNAL='@t6g_mb_lib.t6g(sch_1):sw_p1v2_aux_bt_r';
NODE_NAME     PC6017 1
 '@T6G_MB_LIB.T6G(SCH_1):PAGE380_I18@PURE_QUANTA.Q_CAP(CHIPS)':
 'A': CDS_PINID='A';
NODE_NAME     PR8004 2
 '@T6G_MB_LIB.T6G(SCH_1):PAGE380_I45@PURE_QUANTA.Q_RES(CHIPS)':
 'B': CDS_PINID='B';
NET_NAME
'SW_P1V2_AUX_PH'
 '@T6G_MB_LIB.T6G(SCH_1):SW_P1V2_AUX_PH':
 C_SIGNAL='@t6g_mb_lib.t6g(sch_1):sw_p1v2_aux_ph';
NODE_NAME     PU6001 2
 '@T6G_MB_LIB.T6G(SCH_1):PAGE380_I16@PURE_QUANTA.MPQ8626GDZ(CHIPS)':
 'SW1': CDS_PINID='SW1';
NODE_NAME     PU6001 11
 '@T6G_MB_LIB.T6G(SCH_1):PAGE380_I16@PURE_QUANTA.MPQ8626GDZ(CHIPS)':
 'SW2': CDS_PINID='SW2';
NODE_NAME     PC6017 2
 '@T6G_MB_LIB.T6G(SCH_1):PAGE380_I18@PURE_QUANTA.Q_CAP(CHIPS)':
 'B': CDS_PINID='B';
NODE_NAME     PL6001 1
 '@T6G_MB_LIB.T6G(SCH_1):PAGE380_I24@PURE_QUANTA.Q_INDUCTOR(CHIPS)':
 '1': CDS_PINID='\1\';
NET_NAME
'SW_P1V8_AUX_BT'
 '@T6G_MB_LIB.T6G(SCH_1):SW_P1V8_AUX_BT':
 C_SIGNAL='@t6g_mb_lib.t6g(sch_1):sw_p1v8_aux_bt';
NODE_NAME     PU6000 10
 '@T6G_MB_LIB.T6G(SCH_1):PAGE315_I18@PURE_QUANTA.MPQ8626GDZ(CHIPS)':
 'BST': CDS_PINID='BST';
NODE_NAME     PR8003 1
 '@T6G_MB_LIB.T6G(SCH_1):PAGE315_I45@PURE_QUANTA.Q_RES(CHIPS)':
 'A': CDS_PINID='A';
NET_NAME
'SW_P1V8_AUX_BT_R'
 '@T6G_MB_LIB.T6G(SCH_1):SW_P1V8_AUX_BT_R':
 C_SIGNAL='@t6g_mb_lib.t6g(sch_1):sw_p1v8_aux_bt_r';
NODE_NAME     PC641 1
 '@T6G_MB_LIB.T6G(SCH_1):PAGE315_I30@PURE_QUANTA.Q_CAP(CHIPS)':
 'A': CDS_PINID='A';
NODE_NAME     PR8003 2
 '@T6G_MB_LIB.T6G(SCH_1):PAGE315_I45@PURE_QUANTA.Q_RES(CHIPS)':
 'B': CDS_PINID='B';
NET_NAME
'SW_P1V8_AUX_PH'
 '@T6G_MB_LIB.T6G(SCH_1):SW_P1V8_AUX_PH':
 C_SIGNAL='@t6g_mb_lib.t6g(sch_1):sw_p1v8_aux_ph';
NODE_NAME     PU6000 2
 '@T6G_MB_LIB.T6G(SCH_1):PAGE315_I18@PURE_QUANTA.MPQ8626GDZ(CHIPS)':
 'SW1': CDS_PINID='SW1';
NODE_NAME     PU6000 11
 '@T6G_MB_LIB.T6G(SCH_1):PAGE315_I18@PURE_QUANTA.MPQ8626GDZ(CHIPS)':
 'SW2': CDS_PINID='SW2';
NODE_NAME     PL6000 1
 '@T6G_MB_LIB.T6G(SCH_1):PAGE315_I25@PURE_QUANTA.Q_INDUCTOR(CHIPS)':
 '1': CDS_PINID='\1\';
NODE_NAME     PC641 2
 '@T6G_MB_LIB.T6G(SCH_1):PAGE315_I30@PURE_QUANTA.Q_CAP(CHIPS)':
 'B': CDS_PINID='B';
NET_NAME
'SW_P1V8_RETIMER_CPU0_BST'
 '@T6G_MB_LIB.T6G(SCH_1):SW_P1V8_RETIMER_CPU0_BST':
 C_SIGNAL='@t6g_mb_lib.t6g(sch_1):sw_p1v8_retimer_cpu0_bst';
NODE_NAME     PR6800 1
 '@T6G_MB_LIB.T6G(SCH_1):PAGE469_I29@PURE_QUANTA.Q_RES(CHIPS)':
 'A': CDS_PINID='A';
NODE_NAME     PU6500 1
 '@T6G_MB_LIB.T6G(SCH_1):PAGE469_I51@PURE_QUANTA.MPQ8633BGLEC838Z(CHIPS)':
 'BST': CDS_PINID='BST';
NET_NAME
'SW_P1V8_RETIMER_CPU0_BST_R'
 '@T6G_MB_LIB.T6G(SCH_1):SW_P1V8_RETIMER_CPU0_BST_R':
 C_SIGNAL='@t6g_mb_lib.t6g(sch_1):sw_p1v8_retimer_cpu0_bst_r';
NODE_NAME     PR6800 2
 '@T6G_MB_LIB.T6G(SCH_1):PAGE469_I29@PURE_QUANTA.Q_RES(CHIPS)':
 'B': CDS_PINID='B';
NODE_NAME     PC6507 1
 '@T6G_MB_LIB.T6G(SCH_1):PAGE469_I32@PURE_QUANTA.Q_CAP(CHIPS)':
 'A': CDS_PINID='A';
NET_NAME
'SW_P1V8_RETIMER_CPU0_SW'
 '@T6G_MB_LIB.T6G(SCH_1):SW_P1V8_RETIMER_CPU0_SW':
 C_SIGNAL='@t6g_mb_lib.t6g(sch_1):sw_p1v8_retimer_cpu0_sw';
NODE_NAME     PC6507 2
 '@T6G_MB_LIB.T6G(SCH_1):PAGE469_I32@PURE_QUANTA.Q_CAP(CHIPS)':
 'B': CDS_PINID='B';
NODE_NAME     PL6501 1
 '@T6G_MB_LIB.T6G(SCH_1):PAGE469_I36@PURE_QUANTA.Q_INDUCTOR(CHIPS)':
 '1': CDS_PINID='\1\';
NODE_NAME     PU6500 20
 '@T6G_MB_LIB.T6G(SCH_1):PAGE469_I51@PURE_QUANTA.MPQ8633BGLEC838Z(CHIPS)':
 'SW': CDS_PINID='SW';
NET_NAME
'SW_P1V8_RETIMER_CPU1_BST'
 '@T6G_MB_LIB.T6G(SCH_1):SW_P1V8_RETIMER_CPU1_BST':
 C_SIGNAL='@t6g_mb_lib.t6g(sch_1):sw_p1v8_retimer_cpu1_bst';
NODE_NAME     PR6801 1
 '@T6G_MB_LIB.T6G(SCH_1):PAGE470_I28@PURE_QUANTA.Q_RES(CHIPS)':
 'A': CDS_PINID='A';
NODE_NAME     PU6501 1
 '@T6G_MB_LIB.T6G(SCH_1):PAGE470_I51@PURE_QUANTA.MPQ8633BGLEC838Z(CHIPS)':
 'BST': CDS_PINID='BST';
NET_NAME
'SW_P1V8_RETIMER_CPU1_BST_R'
 '@T6G_MB_LIB.T6G(SCH_1):SW_P1V8_RETIMER_CPU1_BST_R':
 C_SIGNAL='@t6g_mb_lib.t6g(sch_1):sw_p1v8_retimer_cpu1_bst_r';
NODE_NAME     PR6801 2
 '@T6G_MB_LIB.T6G(SCH_1):PAGE470_I28@PURE_QUANTA.Q_RES(CHIPS)':
 'B': CDS_PINID='B';
NODE_NAME     PC6526 1
 '@T6G_MB_LIB.T6G(SCH_1):PAGE470_I35@PURE_QUANTA.Q_CAP(CHIPS)':
 'A': CDS_PINID='A';
NET_NAME
'SW_P1V8_RETIMER_CPU1_SW'
 '@T6G_MB_LIB.T6G(SCH_1):SW_P1V8_RETIMER_CPU1_SW':
 C_SIGNAL='@t6g_mb_lib.t6g(sch_1):sw_p1v8_retimer_cpu1_sw';
NODE_NAME     PC6526 2
 '@T6G_MB_LIB.T6G(SCH_1):PAGE470_I35@PURE_QUANTA.Q_CAP(CHIPS)':
 'B': CDS_PINID='B';
NODE_NAME     PL6502 1
 '@T6G_MB_LIB.T6G(SCH_1):PAGE470_I37@PURE_QUANTA.Q_INDUCTOR(CHIPS)':
 '1': CDS_PINID='\1\';
NODE_NAME     PU6501 20
 '@T6G_MB_LIB.T6G(SCH_1):PAGE470_I51@PURE_QUANTA.MPQ8633BGLEC838Z(CHIPS)':
 'SW': CDS_PINID='SW';
NET_NAME
'SW_P3V3_AUX_BOOT'
 '@T6G_MB_LIB.T6G(SCH_1):SW_P3V3_AUX_BOOT':
 C_SIGNAL='@t6g_mb_lib.t6g(sch_1):sw_p3v3_aux_boot';
NODE_NAME     PU9 26
 '@T6G_MB_LIB.T6G(SCH_1):PAGE245_I21@PURE_QUANTA.NCP3284AMNTXG(CHIPS)':
 'BOOT': CDS_PINID='BOOT';
NODE_NAME     PR835 1
 '@T6G_MB_LIB.T6G(SCH_1):PAGE245_I49@PURE_QUANTA.Q_RES(CHIPS)':
 'A': CDS_PINID='A';
NET_NAME
'SW_P3V3_AUX_BOOTR'
 '@T6G_MB_LIB.T6G(SCH_1):SW_P3V3_AUX_BOOTR':
 C_SIGNAL='@t6g_mb_lib.t6g(sch_1):sw_p3v3_aux_bootr';
NODE_NAME     PU9 25
 '@T6G_MB_LIB.T6G(SCH_1):PAGE245_I21@PURE_QUANTA.NCP3284AMNTXG(CHIPS)':
 'PHASE': CDS_PINID='PHASE';
NODE_NAME     PC568 1
 '@T6G_MB_LIB.T6G(SCH_1):PAGE245_I48@PURE_QUANTA.Q_CAP(CHIPS)':
 'A': CDS_PINID='A';
NET_NAME
'SW_P3V3_AUX_BOOT_R'
 '@T6G_MB_LIB.T6G(SCH_1):SW_P3V3_AUX_BOOT_R':
 C_SIGNAL='@t6g_mb_lib.t6g(sch_1):sw_p3v3_aux_boot_r';
NODE_NAME     PC568 2
 '@T6G_MB_LIB.T6G(SCH_1):PAGE245_I48@PURE_QUANTA.Q_CAP(CHIPS)':
 'B': CDS_PINID='B';
NODE_NAME     PR835 2
 '@T6G_MB_LIB.T6G(SCH_1):PAGE245_I49@PURE_QUANTA.Q_RES(CHIPS)':
 'B': CDS_PINID='B';
NET_NAME
'SW_P3V3_AUX_FLT'
 '@T6G_MB_LIB.T6G(SCH_1):SW_P3V3_AUX_FLT':
 C_SIGNAL='@t6g_mb_lib.t6g(sch_1):sw_p3v3_aux_flt';
NODE_NAME     PU9 20_24
 '@T6G_MB_LIB.T6G(SCH_1):PAGE245_I21@PURE_QUANTA.NCP3284AMNTXG(CHIPS)':
 'PVIN': CDS_PINID='PVIN';
NODE_NAME     PC2260 1
 '@T6G_MB_LIB.T6G(SCH_1):PAGE245_I26@PURE_QUANTA.Q_CAP(CHIPS)':
 'A': CDS_PINID='A';
NODE_NAME     PC3 1
 '@T6G_MB_LIB.T6G(SCH_1):PAGE245_I29@PURE_QUANTA.Q_CAPP(CHIPS)':
 'A': CDS_PINID='A';
NODE_NAME     PC566 1
 '@T6G_MB_LIB.T6G(SCH_1):PAGE245_I30@PURE_QUANTA.Q_CAPP(CHIPS)':
 'A': CDS_PINID='A';
NODE_NAME     PC2262 1
 '@T6G_MB_LIB.T6G(SCH_1):PAGE245_I31@PURE_QUANTA.Q_CAP(CHIPS)':
 'A': CDS_PINID='A';
NODE_NAME     PC8567 1
 '@T6G_MB_LIB.T6G(SCH_1):PAGE245_I32@PURE_QUANTA.Q_CAP(CHIPS)':
 'A': CDS_PINID='A';
NODE_NAME     PC2263 1
 '@T6G_MB_LIB.T6G(SCH_1):PAGE245_I33@PURE_QUANTA.Q_CAP(CHIPS)':
 'A': CDS_PINID='A';
NODE_NAME     PC2342 1
 '@T6G_MB_LIB.T6G(SCH_1):PAGE245_I34@PURE_QUANTA.Q_CAP(CHIPS)':
 'A': CDS_PINID='A';
NODE_NAME     PC570 1
 '@T6G_MB_LIB.T6G(SCH_1):PAGE245_I35@PURE_QUANTA.Q_CAP(CHIPS)':
 'A': CDS_PINID='A';
NODE_NAME     PC571 1
 '@T6G_MB_LIB.T6G(SCH_1):PAGE245_I36@PURE_QUANTA.Q_CAP(CHIPS)':
 'A': CDS_PINID='A';
NODE_NAME     PC2343 1
 '@T6G_MB_LIB.T6G(SCH_1):PAGE245_I37@PURE_QUANTA.Q_CAP(CHIPS)':
 'A': CDS_PINID='A';
NODE_NAME     PC2344 1
 '@T6G_MB_LIB.T6G(SCH_1):PAGE245_I38@PURE_QUANTA.Q_CAP(CHIPS)':
 'A': CDS_PINID='A';
NODE_NAME     PC576 1
 '@T6G_MB_LIB.T6G(SCH_1):PAGE245_I39@PURE_QUANTA.Q_CAP(CHIPS)':
 'A': CDS_PINID='A';
NODE_NAME     PC8071 1
 '@T6G_MB_LIB.T6G(SCH_1):PAGE245_I40@PURE_QUANTA.Q_CAP(CHIPS)':
 'A': CDS_PINID='A';
NODE_NAME     PC577 1
 '@T6G_MB_LIB.T6G(SCH_1):PAGE245_I41@PURE_QUANTA.Q_CAP(CHIPS)':
 'A': CDS_PINID='A';
NODE_NAME     PL8045 2
 '@T6G_MB_LIB.T6G(SCH_1):PAGE245_I24@PURE_QUANTA.Q_INDUCTOR(CHIPS)':
 '2': CDS_PINID='\2\';
NODE_NAME     PC2261 1
 '@T6G_MB_LIB.T6G(SCH_1):PAGE245_I27@PURE_QUANTA.Q_CAP(CHIPS)':
 'A': CDS_PINID='A';
NODE_NAME     PC8013 1
 '@T6G_MB_LIB.T6G(SCH_1):PAGE245_I70@PURE_QUANTA.Q_CAP(CHIPS)':
 'A': CDS_PINID='A';
NODE_NAME     PC8014 1
 '@T6G_MB_LIB.T6G(SCH_1):PAGE245_I71@PURE_QUANTA.Q_CAP(CHIPS)':
 'A': CDS_PINID='A';
NET_NAME
'SW_P3V3_AUX_SW'
 '@T6G_MB_LIB.T6G(SCH_1):SW_P3V3_AUX_SW':
 C_SIGNAL='@t6g_mb_lib.t6g(sch_1):sw_p3v3_aux_sw';
NODE_NAME     PU9 11_18
 '@T6G_MB_LIB.T6G(SCH_1):PAGE245_I21@PURE_QUANTA.NCP3284AMNTXG(CHIPS)':
 'SW': CDS_PINID='SW';
NODE_NAME     PL8066 1
 '@T6G_MB_LIB.T6G(SCH_1):PAGE245_I55@PURE_QUANTA.Q_INDUCTOR(CHIPS)':
 '1': CDS_PINID='\1\';
NET_NAME
'SW_P3V3_EN'
 '@T6G_MB_LIB.T6G(SCH_1):SW_P3V3_EN':
 C_SIGNAL='@t6g_mb_lib.t6g(sch_1):sw_p3v3_en';
NODE_NAME     U18 Y17
 '@T6G_MB_LIB.T6G(SCH_1):PAGE80_I216@PURE_QUANTA.LCMXO3LF9400C5BG484C(CHIPS)':
 'PB40C': CDS_PINID='PB40C';
NODE_NAME     R6050 1
 '@T6G_MB_LIB.T6G(SCH_1):PAGE273_I91@PURE_QUANTA.Q_RES(CHIPS)':
 'A': CDS_PINID='A';
NODE_NAME     R496 2
 '@T6G_MB_LIB.T6G(SCH_1):PAGE273_I93@PURE_QUANTA.Q_RES(CHIPS)':
 'B': CDS_PINID='B';
NODE_NAME     R487 1
 '@T6G_MB_LIB.T6G(SCH_1):PAGE273_I95@PURE_QUANTA.Q_RES(CHIPS)':
 'A': CDS_PINID='A';
NET_NAME
'SW_P3V3_EN_ISO'
 '@T6G_MB_LIB.T6G(SCH_1):SW_P3V3_EN_ISO':
 C_SIGNAL='@t6g_mb_lib.t6g(sch_1):sw_p3v3_en_iso';
NODE_NAME     Q3 3
 '@T6G_MB_LIB.T6G(SCH_1):PAGE273_I108@PURE_QUANTA.MOSFET_NCH_DUAL(CHIPS)':
 'D2': CDS_PINID='D2';
NODE_NAME     R569 2
 '@T6G_MB_LIB.T6G(SCH_1):PAGE273_I113@PURE_QUANTA.Q_RES(CHIPS)':
 'B': CDS_PINID='B';
NET_NAME
'SW_P3V3_EN_ISO_R'
 '@T6G_MB_LIB.T6G(SCH_1):SW_P3V3_EN_ISO_R':
 C_SIGNAL='@t6g_mb_lib.t6g(sch_1):sw_p3v3_en_iso_r';
NODE_NAME     Q56 4
 '@T6G_MB_LIB.T6G(SCH_1):PAGE273_I50@PURE_QUANTA.MOSFET_NCH_1D3S(CHIPS)':
 '4': CDS_PINID='\4\';
NODE_NAME     R569 1
 '@T6G_MB_LIB.T6G(SCH_1):PAGE273_I113@PURE_QUANTA.Q_RES(CHIPS)':
 'A': CDS_PINID='A';
NODE_NAME     R568 2
 '@T6G_MB_LIB.T6G(SCH_1):PAGE273_I114@PURE_QUANTA.Q_RES(CHIPS)':
 'B': CDS_PINID='B';
NODE_NAME     C29 1
 '@T6G_MB_LIB.T6G(SCH_1):PAGE273_I116@PURE_QUANTA.Q_CAP(CHIPS)':
 'A': CDS_PINID='A';
NET_NAME
'SW_P3V3_EN_N'
 '@T6G_MB_LIB.T6G(SCH_1):SW_P3V3_EN_N':
 C_SIGNAL='@t6g_mb_lib.t6g(sch_1):sw_p3v3_en_n';
NODE_NAME     Q3 6
 '@T6G_MB_LIB.T6G(SCH_1):PAGE273_I107@PURE_QUANTA.MOSFET_NCH_DUAL(CHIPS)':
 'D1': CDS_PINID='D1';
NODE_NAME     Q3 5
 '@T6G_MB_LIB.T6G(SCH_1):PAGE273_I108@PURE_QUANTA.MOSFET_NCH_DUAL(CHIPS)':
 'G2': CDS_PINID='G2';
NODE_NAME     R554 2
 '@T6G_MB_LIB.T6G(SCH_1):PAGE273_I111@PURE_QUANTA.Q_RES(CHIPS)':
 'B': CDS_PINID='B';
NET_NAME
'SW_P3V3_EN_R'
 '@T6G_MB_LIB.T6G(SCH_1):SW_P3V3_EN_R':
 C_SIGNAL='@t6g_mb_lib.t6g(sch_1):sw_p3v3_en_r';
NODE_NAME     R490 2
 '@T6G_MB_LIB.T6G(SCH_1):PAGE273_I88@PURE_QUANTA.Q_RES(CHIPS)':
 'B': CDS_PINID='B';
NODE_NAME     R487 2
 '@T6G_MB_LIB.T6G(SCH_1):PAGE273_I95@PURE_QUANTA.Q_RES(CHIPS)':
 'B': CDS_PINID='B';
NODE_NAME     Q3 2
 '@T6G_MB_LIB.T6G(SCH_1):PAGE273_I107@PURE_QUANTA.MOSFET_NCH_DUAL(CHIPS)':
 'G1': CDS_PINID='G1';
NET_NAME
'SW_P5V_AUX_BST'
 '@T6G_MB_LIB.T6G(SCH_1):SW_P5V_AUX_BST':
 C_SIGNAL='@t6g_mb_lib.t6g(sch_1):sw_p5v_aux_bst';
NODE_NAME     PC1847 1
 '@T6G_MB_LIB.T6G(SCH_1):PAGE244_I24@PURE_QUANTA.Q_CAP(CHIPS)':
 'A': CDS_PINID='A';
NODE_NAME     U326 1
 '@T6G_MB_LIB.T6G(SCH_1):PAGE244_I38@PURE_QUANTA.MPQ8633AGLEC807Z(CHIPS)':
 'BST': CDS_PINID='BST';
NET_NAME
'SW_P5V_AUX_FLT'
 '@T6G_MB_LIB.T6G(SCH_1):SW_P5V_AUX_FLT':
 C_SIGNAL='@t6g_mb_lib.t6g(sch_1):sw_p5v_aux_flt';
NODE_NAME     PL8064 2
 '@T6G_MB_LIB.T6G(SCH_1):PAGE244_I5@PURE_QUANTA.Q_INDUCTOR(CHIPS)':
 '2': CDS_PINID='\2\';
NODE_NAME     PC1849 1
 '@T6G_MB_LIB.T6G(SCH_1):PAGE244_I7@PURE_QUANTA.Q_CAP(CHIPS)':
 'A': CDS_PINID='A';
NODE_NAME     PC1850 1
 '@T6G_MB_LIB.T6G(SCH_1):PAGE244_I10@PURE_QUANTA.Q_CAP(CHIPS)':
 'A': CDS_PINID='A';
NODE_NAME     PC1898 1
 '@T6G_MB_LIB.T6G(SCH_1):PAGE244_I11@PURE_QUANTA.Q_CAP(CHIPS)':
 'A': CDS_PINID='A';
NODE_NAME     PC1846 1
 '@T6G_MB_LIB.T6G(SCH_1):PAGE244_I13@PURE_QUANTA.Q_CAP(CHIPS)':
 'A': CDS_PINID='A';
NODE_NAME     U326 10
 '@T6G_MB_LIB.T6G(SCH_1):PAGE244_I38@PURE_QUANTA.MPQ8633AGLEC807Z(CHIPS)':
 'VIN1': CDS_PINID='VIN1';
NODE_NAME     U326 21
 '@T6G_MB_LIB.T6G(SCH_1):PAGE244_I38@PURE_QUANTA.MPQ8633AGLEC807Z(CHIPS)':
 'VIN2': CDS_PINID='VIN2';
NET_NAME
'SW_P5V_AUX_SW'
 '@T6G_MB_LIB.T6G(SCH_1):SW_P5V_AUX_SW':
 C_SIGNAL='@t6g_mb_lib.t6g(sch_1):sw_p5v_aux_sw';
NODE_NAME     PC1847 2
 '@T6G_MB_LIB.T6G(SCH_1):PAGE244_I24@PURE_QUANTA.Q_CAP(CHIPS)':
 'B': CDS_PINID='B';
NODE_NAME     PL8065 1
 '@T6G_MB_LIB.T6G(SCH_1):PAGE244_I28@PURE_QUANTA.Q_INDUCTOR(CHIPS)':
 '1': CDS_PINID='\1\';
NODE_NAME     U326 20
 '@T6G_MB_LIB.T6G(SCH_1):PAGE244_I38@PURE_QUANTA.MPQ8633AGLEC807Z(CHIPS)':
 'SW': CDS_PINID='SW';
NET_NAME
'SW_PVDD11_S3_P0_BOOT1'
 '@T6G_MB_LIB.T6G(SCH_1):SW_PVDD11_S3_P0_BOOT1':
 C_SIGNAL='@t6g_mb_lib.t6g(sch_1):sw_pvdd11_s3_p0_boot1';
NODE_NAME     PR135 1
 '@T6G_MB_LIB.T6G(SCH_1):PAGE183_I46@PURE_QUANTA.Q_RES(CHIPS)':
 'A': CDS_PINID='A';
NODE_NAME     PU22 33
 '@T6G_MB_LIB.T6G(SCH_1):PAGE183_I92@PURE_QUANTA.ISL99390FRZTR5935(CHIPS)':
 'BOOT': CDS_PINID='BOOT';
NET_NAME
'SW_PVDD11_S3_P0_BOOT1_RC'
 '@T6G_MB_LIB.T6G(SCH_1):SW_PVDD11_S3_P0_BOOT1_RC':
 C_SIGNAL='@t6g_mb_lib.t6g(sch_1):sw_pvdd11_s3_p0_boot1_rc';
NODE_NAME     PR135 2
 '@T6G_MB_LIB.T6G(SCH_1):PAGE183_I46@PURE_QUANTA.Q_RES(CHIPS)':
 'B': CDS_PINID='B';
NODE_NAME     PC217 1
 '@T6G_MB_LIB.T6G(SCH_1):PAGE183_I71@PURE_QUANTA.Q_CAP(CHIPS)':
 'A': CDS_PINID='A';
NET_NAME
'SW_PVDD11_S3_P0_BOOT2'
 '@T6G_MB_LIB.T6G(SCH_1):SW_PVDD11_S3_P0_BOOT2':
 C_SIGNAL='@t6g_mb_lib.t6g(sch_1):sw_pvdd11_s3_p0_boot2';
NODE_NAME     PR136 1
 '@T6G_MB_LIB.T6G(SCH_1):PAGE183_I25@PURE_QUANTA.Q_RES(CHIPS)':
 'A': CDS_PINID='A';
NODE_NAME     PU23 33
 '@T6G_MB_LIB.T6G(SCH_1):PAGE183_I13@PURE_QUANTA.ISL99390FRZTR5935(CHIPS)':
 'BOOT': CDS_PINID='BOOT';
NET_NAME
'SW_PVDD11_S3_P0_BOOT2_RC'
 '@T6G_MB_LIB.T6G(SCH_1):SW_PVDD11_S3_P0_BOOT2_RC':
 C_SIGNAL='@t6g_mb_lib.t6g(sch_1):sw_pvdd11_s3_p0_boot2_rc';
NODE_NAME     PR136 2
 '@T6G_MB_LIB.T6G(SCH_1):PAGE183_I25@PURE_QUANTA.Q_RES(CHIPS)':
 'B': CDS_PINID='B';
NODE_NAME     PC218 1
 '@T6G_MB_LIB.T6G(SCH_1):PAGE183_I51@PURE_QUANTA.Q_CAP(CHIPS)':
 'A': CDS_PINID='A';
NET_NAME
'SW_PVDD11_S3_P0_PH1'
 '@T6G_MB_LIB.T6G(SCH_1):SW_PVDD11_S3_P0_PH1':
 C_SIGNAL='@t6g_mb_lib.t6g(sch_1):sw_pvdd11_s3_p0_ph1';
NODE_NAME     PC217 2
 '@T6G_MB_LIB.T6G(SCH_1):PAGE183_I71@PURE_QUANTA.Q_CAP(CHIPS)':
 'B': CDS_PINID='B';
NODE_NAME     PU22 32
 '@T6G_MB_LIB.T6G(SCH_1):PAGE183_I92@PURE_QUANTA.ISL99390FRZTR5935(CHIPS)':
 'PHASE': CDS_PINID='PHASE';
NET_NAME
'SW_PVDD11_S3_P0_PH2'
 '@T6G_MB_LIB.T6G(SCH_1):SW_PVDD11_S3_P0_PH2':
 C_SIGNAL='@t6g_mb_lib.t6g(sch_1):sw_pvdd11_s3_p0_ph2';
NODE_NAME     PU23 32
 '@T6G_MB_LIB.T6G(SCH_1):PAGE183_I13@PURE_QUANTA.ISL99390FRZTR5935(CHIPS)':
 'PHASE': CDS_PINID='PHASE';
NODE_NAME     PC218 2
 '@T6G_MB_LIB.T6G(SCH_1):PAGE183_I51@PURE_QUANTA.Q_CAP(CHIPS)':
 'B': CDS_PINID='B';
NET_NAME
'SW_PVDD11_S3_P0_SW1'
 '@T6G_MB_LIB.T6G(SCH_1):SW_PVDD11_S3_P0_SW1':
 C_SIGNAL='@t6g_mb_lib.t6g(sch_1):sw_pvdd11_s3_p0_sw1';
NODE_NAME     PC169 1
 '@T6G_MB_LIB.T6G(SCH_1):PAGE183_I45@PURE_QUANTA.Q_CAP(CHIPS)':
 'A': CDS_PINID='A';
NODE_NAME     PL23 1
 '@T6G_MB_LIB.T6G(SCH_1):PAGE183_I73@PURE_QUANTA.Q_INDUCTOR(CHIPS)':
 '1': CDS_PINID='\1\';
NODE_NAME     PU22 10_19
 '@T6G_MB_LIB.T6G(SCH_1):PAGE183_I92@PURE_QUANTA.ISL99390FRZTR5935(CHIPS)':
 'SW': CDS_PINID='SW';
NET_NAME
'SW_PVDD11_S3_P0_SW1_RC'
 '@T6G_MB_LIB.T6G(SCH_1):SW_PVDD11_S3_P0_SW1_RC':
 C_SIGNAL='@t6g_mb_lib.t6g(sch_1):sw_pvdd11_s3_p0_sw1_rc';
NODE_NAME     PR482 1
 '@T6G_MB_LIB.T6G(SCH_1):PAGE183_I33@PURE_QUANTA.Q_RES(CHIPS)':
 'A': CDS_PINID='A';
NODE_NAME     PC169 2
 '@T6G_MB_LIB.T6G(SCH_1):PAGE183_I45@PURE_QUANTA.Q_CAP(CHIPS)':
 'B': CDS_PINID='B';
NET_NAME
'SW_PVDD11_S3_P0_SW2'
 '@T6G_MB_LIB.T6G(SCH_1):SW_PVDD11_S3_P0_SW2':
 C_SIGNAL='@t6g_mb_lib.t6g(sch_1):sw_pvdd11_s3_p0_sw2';
NODE_NAME     PC168 1
 '@T6G_MB_LIB.T6G(SCH_1):PAGE183_I26@PURE_QUANTA.Q_CAP(CHIPS)':
 'A': CDS_PINID='A';
NODE_NAME     PL22 1
 '@T6G_MB_LIB.T6G(SCH_1):PAGE183_I52@PURE_QUANTA.Q_INDUCTOR(CHIPS)':
 '1': CDS_PINID='\1\';
NODE_NAME     PU23 10_19
 '@T6G_MB_LIB.T6G(SCH_1):PAGE183_I13@PURE_QUANTA.ISL99390FRZTR5935(CHIPS)':
 'SW': CDS_PINID='SW';
NET_NAME
'SW_PVDD11_S3_P0_SW2_RC'
 '@T6G_MB_LIB.T6G(SCH_1):SW_PVDD11_S3_P0_SW2_RC':
 C_SIGNAL='@t6g_mb_lib.t6g(sch_1):sw_pvdd11_s3_p0_sw2_rc';
NODE_NAME     PR389 1
 '@T6G_MB_LIB.T6G(SCH_1):PAGE183_I24@PURE_QUANTA.Q_RES(CHIPS)':
 'A': CDS_PINID='A';
NODE_NAME     PC168 2
 '@T6G_MB_LIB.T6G(SCH_1):PAGE183_I26@PURE_QUANTA.Q_CAP(CHIPS)':
 'B': CDS_PINID='B';
NET_NAME
'SW_PVDD11_S3_P1_BOOT1'
 '@T6G_MB_LIB.T6G(SCH_1):SW_PVDD11_S3_P1_BOOT1':
 C_SIGNAL='@t6g_mb_lib.t6g(sch_1):sw_pvdd11_s3_p1_boot1';
NODE_NAME     PU44 33
 '@T6G_MB_LIB.T6G(SCH_1):PAGE200_I22@PURE_QUANTA.ISL99390FRZTR5935(CHIPS)':
 'BOOT': CDS_PINID='BOOT';
NODE_NAME     PR330 1
 '@T6G_MB_LIB.T6G(SCH_1):PAGE200_I47@PURE_QUANTA.Q_RES(CHIPS)':
 'A': CDS_PINID='A';
NET_NAME
'SW_PVDD11_S3_P1_BOOT1_RC'
 '@T6G_MB_LIB.T6G(SCH_1):SW_PVDD11_S3_P1_BOOT1_RC':
 C_SIGNAL='@t6g_mb_lib.t6g(sch_1):sw_pvdd11_s3_p1_boot1_rc';
NODE_NAME     PR330 2
 '@T6G_MB_LIB.T6G(SCH_1):PAGE200_I47@PURE_QUANTA.Q_RES(CHIPS)':
 'B': CDS_PINID='B';
NODE_NAME     PC519 1
 '@T6G_MB_LIB.T6G(SCH_1):PAGE200_I76@PURE_QUANTA.Q_CAP(CHIPS)':
 'A': CDS_PINID='A';
NET_NAME
'SW_PVDD11_S3_P1_BOOT2'
 '@T6G_MB_LIB.T6G(SCH_1):SW_PVDD11_S3_P1_BOOT2':
 C_SIGNAL='@t6g_mb_lib.t6g(sch_1):sw_pvdd11_s3_p1_boot2';
NODE_NAME     PR331 1
 '@T6G_MB_LIB.T6G(SCH_1):PAGE200_I26@PURE_QUANTA.Q_RES(CHIPS)':
 'A': CDS_PINID='A';
NODE_NAME     PU45 33
 '@T6G_MB_LIB.T6G(SCH_1):PAGE200_I92@PURE_QUANTA.ISL99390FRZTR5935(CHIPS)':
 'BOOT': CDS_PINID='BOOT';
NET_NAME
'SW_PVDD11_S3_P1_BOOT2_RC'
 '@T6G_MB_LIB.T6G(SCH_1):SW_PVDD11_S3_P1_BOOT2_RC':
 C_SIGNAL='@t6g_mb_lib.t6g(sch_1):sw_pvdd11_s3_p1_boot2_rc';
NODE_NAME     PR331 2
 '@T6G_MB_LIB.T6G(SCH_1):PAGE200_I26@PURE_QUANTA.Q_RES(CHIPS)':
 'B': CDS_PINID='B';
NODE_NAME     PC520 1
 '@T6G_MB_LIB.T6G(SCH_1):PAGE200_I54@PURE_QUANTA.Q_CAP(CHIPS)':
 'A': CDS_PINID='A';
NET_NAME
'SW_PVDD11_S3_P1_PH1'
 '@T6G_MB_LIB.T6G(SCH_1):SW_PVDD11_S3_P1_PH1':
 C_SIGNAL='@t6g_mb_lib.t6g(sch_1):sw_pvdd11_s3_p1_ph1';
NODE_NAME     PU44 32
 '@T6G_MB_LIB.T6G(SCH_1):PAGE200_I22@PURE_QUANTA.ISL99390FRZTR5935(CHIPS)':
 'PHASE': CDS_PINID='PHASE';
NODE_NAME     PC519 2
 '@T6G_MB_LIB.T6G(SCH_1):PAGE200_I76@PURE_QUANTA.Q_CAP(CHIPS)':
 'B': CDS_PINID='B';
NET_NAME
'SW_PVDD11_S3_P1_PH2'
 '@T6G_MB_LIB.T6G(SCH_1):SW_PVDD11_S3_P1_PH2':
 C_SIGNAL='@t6g_mb_lib.t6g(sch_1):sw_pvdd11_s3_p1_ph2';
NODE_NAME     PC520 2
 '@T6G_MB_LIB.T6G(SCH_1):PAGE200_I54@PURE_QUANTA.Q_CAP(CHIPS)':
 'B': CDS_PINID='B';
NODE_NAME     PU45 32
 '@T6G_MB_LIB.T6G(SCH_1):PAGE200_I92@PURE_QUANTA.ISL99390FRZTR5935(CHIPS)':
 'PHASE': CDS_PINID='PHASE';
NET_NAME
'SW_PVDD11_S3_P1_SW1'
 '@T6G_MB_LIB.T6G(SCH_1):SW_PVDD11_S3_P1_SW1':
 C_SIGNAL='@t6g_mb_lib.t6g(sch_1):sw_pvdd11_s3_p1_sw1';
NODE_NAME     PU44 10_19
 '@T6G_MB_LIB.T6G(SCH_1):PAGE200_I22@PURE_QUANTA.ISL99390FRZTR5935(CHIPS)':
 'SW': CDS_PINID='SW';
NODE_NAME     PC315 1
 '@T6G_MB_LIB.T6G(SCH_1):PAGE200_I46@PURE_QUANTA.Q_CAP(CHIPS)':
 'A': CDS_PINID='A';
NODE_NAME     PL54 1
 '@T6G_MB_LIB.T6G(SCH_1):PAGE200_I78@PURE_QUANTA.Q_INDUCTOR(CHIPS)':
 '1': CDS_PINID='\1\';
NET_NAME
'SW_PVDD11_S3_P1_SW1_RC'
 '@T6G_MB_LIB.T6G(SCH_1):SW_PVDD11_S3_P1_SW1_RC':
 C_SIGNAL='@t6g_mb_lib.t6g(sch_1):sw_pvdd11_s3_p1_sw1_rc';
NODE_NAME     PR520 1
 '@T6G_MB_LIB.T6G(SCH_1):PAGE200_I33@PURE_QUANTA.Q_RES(CHIPS)':
 'A': CDS_PINID='A';
NODE_NAME     PC315 2
 '@T6G_MB_LIB.T6G(SCH_1):PAGE200_I46@PURE_QUANTA.Q_CAP(CHIPS)':
 'B': CDS_PINID='B';
NET_NAME
'SW_PVDD11_S3_P1_SW2'
 '@T6G_MB_LIB.T6G(SCH_1):SW_PVDD11_S3_P1_SW2':
 C_SIGNAL='@t6g_mb_lib.t6g(sch_1):sw_pvdd11_s3_p1_sw2';
NODE_NAME     PC255 1
 '@T6G_MB_LIB.T6G(SCH_1):PAGE200_I27@PURE_QUANTA.Q_CAP(CHIPS)':
 'A': CDS_PINID='A';
NODE_NAME     PL55 1
 '@T6G_MB_LIB.T6G(SCH_1):PAGE200_I55@PURE_QUANTA.Q_INDUCTOR(CHIPS)':
 '1': CDS_PINID='\1\';
NODE_NAME     PU45 10_19
 '@T6G_MB_LIB.T6G(SCH_1):PAGE200_I92@PURE_QUANTA.ISL99390FRZTR5935(CHIPS)':
 'SW': CDS_PINID='SW';
NET_NAME
'SW_PVDD11_S3_P1_SW2_RC'
 '@T6G_MB_LIB.T6G(SCH_1):SW_PVDD11_S3_P1_SW2_RC':
 C_SIGNAL='@t6g_mb_lib.t6g(sch_1):sw_pvdd11_s3_p1_sw2_rc';
NODE_NAME     PR519 1
 '@T6G_MB_LIB.T6G(SCH_1):PAGE200_I25@PURE_QUANTA.Q_RES(CHIPS)':
 'A': CDS_PINID='A';
NODE_NAME     PC255 2
 '@T6G_MB_LIB.T6G(SCH_1):PAGE200_I27@PURE_QUANTA.Q_CAP(CHIPS)':
 'B': CDS_PINID='B';
NET_NAME
'SW_PVDD18_S5_P0_BST'
 '@T6G_MB_LIB.T6G(SCH_1):SW_PVDD18_S5_P0_BST':
 C_SIGNAL='@t6g_mb_lib.t6g(sch_1):sw_pvdd18_s5_p0_bst';
NODE_NAME     PU57 1
 '@T6G_MB_LIB.T6G(SCH_1):PAGE184_I18@PURE_QUANTA.MPQ8633BGLEC838Z(CHIPS)':
 'BST': CDS_PINID='BST';
NODE_NAME     PR8001 1
 '@T6G_MB_LIB.T6G(SCH_1):PAGE184_I58@PURE_QUANTA.Q_RES(CHIPS)':
 'A': CDS_PINID='A';
NET_NAME
'SW_PVDD18_S5_P0_BST_R'
 '@T6G_MB_LIB.T6G(SCH_1):SW_PVDD18_S5_P0_BST_R':
 C_SIGNAL='@t6g_mb_lib.t6g(sch_1):sw_pvdd18_s5_p0_bst_r';
NODE_NAME     PC209 1
 '@T6G_MB_LIB.T6G(SCH_1):PAGE184_I24@PURE_QUANTA.Q_CAP(CHIPS)':
 'A': CDS_PINID='A';
NODE_NAME     PR8001 2
 '@T6G_MB_LIB.T6G(SCH_1):PAGE184_I58@PURE_QUANTA.Q_RES(CHIPS)':
 'B': CDS_PINID='B';
NET_NAME
'SW_PVDD18_S5_P0_SW'
 '@T6G_MB_LIB.T6G(SCH_1):SW_PVDD18_S5_P0_SW':
 C_SIGNAL='@t6g_mb_lib.t6g(sch_1):sw_pvdd18_s5_p0_sw';
NODE_NAME     PU57 20
 '@T6G_MB_LIB.T6G(SCH_1):PAGE184_I18@PURE_QUANTA.MPQ8633BGLEC838Z(CHIPS)':
 'SW': CDS_PINID='SW';
NODE_NAME     PC209 2
 '@T6G_MB_LIB.T6G(SCH_1):PAGE184_I24@PURE_QUANTA.Q_CAP(CHIPS)':
 'B': CDS_PINID='B';
NODE_NAME     PL78 1
 '@T6G_MB_LIB.T6G(SCH_1):PAGE184_I36@PURE_QUANTA.Q_INDUCTOR(CHIPS)':
 '1': CDS_PINID='\1\';
NET_NAME
'SW_PVDD18_S5_P1_BST'
 '@T6G_MB_LIB.T6G(SCH_1):SW_PVDD18_S5_P1_BST':
 C_SIGNAL='@t6g_mb_lib.t6g(sch_1):sw_pvdd18_s5_p1_bst';
NODE_NAME     PU3 1
 '@T6G_MB_LIB.T6G(SCH_1):PAGE201_I15@PURE_QUANTA.MPQ8633BGLEC838Z(CHIPS)':
 'BST': CDS_PINID='BST';
NODE_NAME     PR8002 1
 '@T6G_MB_LIB.T6G(SCH_1):PAGE201_I58@PURE_QUANTA.Q_RES(CHIPS)':
 'A': CDS_PINID='A';
NET_NAME
'SW_PVDD18_S5_P1_BST_R'
 '@T6G_MB_LIB.T6G(SCH_1):SW_PVDD18_S5_P1_BST_R':
 C_SIGNAL='@t6g_mb_lib.t6g(sch_1):sw_pvdd18_s5_p1_bst_r';
NODE_NAME     PC19 1
 '@T6G_MB_LIB.T6G(SCH_1):PAGE201_I25@PURE_QUANTA.Q_CAP(CHIPS)':
 'A': CDS_PINID='A';
NODE_NAME     PR8002 2
 '@T6G_MB_LIB.T6G(SCH_1):PAGE201_I58@PURE_QUANTA.Q_RES(CHIPS)':
 'B': CDS_PINID='B';
NET_NAME
'SW_PVDD18_S5_P1_SW'
 '@T6G_MB_LIB.T6G(SCH_1):SW_PVDD18_S5_P1_SW':
 C_SIGNAL='@t6g_mb_lib.t6g(sch_1):sw_pvdd18_s5_p1_sw';
NODE_NAME     PU3 20
 '@T6G_MB_LIB.T6G(SCH_1):PAGE201_I15@PURE_QUANTA.MPQ8633BGLEC838Z(CHIPS)':
 'SW': CDS_PINID='SW';
NODE_NAME     PC19 2
 '@T6G_MB_LIB.T6G(SCH_1):PAGE201_I25@PURE_QUANTA.Q_CAP(CHIPS)':
 'B': CDS_PINID='B';
NODE_NAME     PL57 1
 '@T6G_MB_LIB.T6G(SCH_1):PAGE201_I33@PURE_QUANTA.Q_INDUCTOR(CHIPS)':
 '1': CDS_PINID='\1\';
NET_NAME
'SW_PVDDCR_CPU0_P0_BOOT1'
 '@T6G_MB_LIB.T6G(SCH_1):SW_PVDDCR_CPU0_P0_BOOT1':
 C_SIGNAL='@t6g_mb_lib.t6g(sch_1):sw_pvddcr_cpu0_p0_boot1';
NODE_NAME     PU6 33
 '@T6G_MB_LIB.T6G(SCH_1):PAGE169_I26@PURE_QUANTA.ISL99390FRZTR5935(CHIPS)':
 'BOOT': CDS_PINID='BOOT';
NODE_NAME     PR322 1
 '@T6G_MB_LIB.T6G(SCH_1):PAGE169_I55@PURE_QUANTA.Q_RES(CHIPS)':
 'A': CDS_PINID='A';
NET_NAME
'SW_PVDDCR_CPU0_P0_BOOT1_RC'
 '@T6G_MB_LIB.T6G(SCH_1):SW_PVDDCR_CPU0_P0_BOOT1_RC':
 C_SIGNAL='@t6g_mb_lib.t6g(sch_1):sw_pvddcr_cpu0_p0_boot1_rc';
NODE_NAME     PR322 2
 '@T6G_MB_LIB.T6G(SCH_1):PAGE169_I55@PURE_QUANTA.Q_RES(CHIPS)':
 'B': CDS_PINID='B';
NODE_NAME     PC489 1
 '@T6G_MB_LIB.T6G(SCH_1):PAGE169_I76@PURE_QUANTA.Q_CAP(CHIPS)':
 'A': CDS_PINID='A';
NET_NAME
'SW_PVDDCR_CPU0_P0_BOOT2'
 '@T6G_MB_LIB.T6G(SCH_1):SW_PVDDCR_CPU0_P0_BOOT2':
 C_SIGNAL='@t6g_mb_lib.t6g(sch_1):sw_pvddcr_cpu0_p0_boot2';
NODE_NAME     PU43 33
 '@T6G_MB_LIB.T6G(SCH_1):PAGE169_I16@PURE_QUANTA.ISL99390FRZTR5935(CHIPS)':
 'BOOT': CDS_PINID='BOOT';
NODE_NAME     PR323 1
 '@T6G_MB_LIB.T6G(SCH_1):PAGE169_I32@PURE_QUANTA.Q_RES(CHIPS)':
 'A': CDS_PINID='A';
NET_NAME
'SW_PVDDCR_CPU0_P0_BOOT2_RC'
 '@T6G_MB_LIB.T6G(SCH_1):SW_PVDDCR_CPU0_P0_BOOT2_RC':
 C_SIGNAL='@t6g_mb_lib.t6g(sch_1):sw_pvddcr_cpu0_p0_boot2_rc';
NODE_NAME     PR323 2
 '@T6G_MB_LIB.T6G(SCH_1):PAGE169_I32@PURE_QUANTA.Q_RES(CHIPS)':
 'B': CDS_PINID='B';
NODE_NAME     PC490 1
 '@T6G_MB_LIB.T6G(SCH_1):PAGE169_I61@PURE_QUANTA.Q_CAP(CHIPS)':
 'A': CDS_PINID='A';
NET_NAME
'SW_PVDDCR_CPU0_P0_BOOT3'
 '@T6G_MB_LIB.T6G(SCH_1):SW_PVDDCR_CPU0_P0_BOOT3':
 C_SIGNAL='@t6g_mb_lib.t6g(sch_1):sw_pvddcr_cpu0_p0_boot3';
NODE_NAME     PU46 33
 '@T6G_MB_LIB.T6G(SCH_1):PAGE170_I38@PURE_QUANTA.ISL99390FRZTR5935(CHIPS)':
 'BOOT': CDS_PINID='BOOT';
NODE_NAME     PR348 1
 '@T6G_MB_LIB.T6G(SCH_1):PAGE170_I46@PURE_QUANTA.Q_RES(CHIPS)':
 'A': CDS_PINID='A';
NET_NAME
'SW_PVDDCR_CPU0_P0_BOOT3_RC'
 '@T6G_MB_LIB.T6G(SCH_1):SW_PVDDCR_CPU0_P0_BOOT3_RC':
 C_SIGNAL='@t6g_mb_lib.t6g(sch_1):sw_pvddcr_cpu0_p0_boot3_rc';
NODE_NAME     PR348 2
 '@T6G_MB_LIB.T6G(SCH_1):PAGE170_I46@PURE_QUANTA.Q_RES(CHIPS)':
 'B': CDS_PINID='B';
NODE_NAME     PC560 1
 '@T6G_MB_LIB.T6G(SCH_1):PAGE170_I63@PURE_QUANTA.Q_CAP(CHIPS)':
 'A': CDS_PINID='A';
NET_NAME
'SW_PVDDCR_CPU0_P0_BOOT4'
 '@T6G_MB_LIB.T6G(SCH_1):SW_PVDDCR_CPU0_P0_BOOT4':
 C_SIGNAL='@t6g_mb_lib.t6g(sch_1):sw_pvddcr_cpu0_p0_boot4';
NODE_NAME     PR349 1
 '@T6G_MB_LIB.T6G(SCH_1):PAGE170_I20@PURE_QUANTA.Q_RES(CHIPS)':
 'A': CDS_PINID='A';
NODE_NAME     PU47 33
 '@T6G_MB_LIB.T6G(SCH_1):PAGE170_I9@PURE_QUANTA.ISL99390FRZTR5935(CHIPS)':
 'BOOT': CDS_PINID='BOOT';
NET_NAME
'SW_PVDDCR_CPU0_P0_BOOT4_RC'
 '@T6G_MB_LIB.T6G(SCH_1):SW_PVDDCR_CPU0_P0_BOOT4_RC':
 C_SIGNAL='@t6g_mb_lib.t6g(sch_1):sw_pvddcr_cpu0_p0_boot4_rc';
NODE_NAME     PR349 2
 '@T6G_MB_LIB.T6G(SCH_1):PAGE170_I20@PURE_QUANTA.Q_RES(CHIPS)':
 'B': CDS_PINID='B';
NODE_NAME     PC561 1
 '@T6G_MB_LIB.T6G(SCH_1):PAGE170_I53@PURE_QUANTA.Q_CAP(CHIPS)':
 'A': CDS_PINID='A';
NET_NAME
'SW_PVDDCR_CPU0_P0_BOOT5'
 '@T6G_MB_LIB.T6G(SCH_1):SW_PVDDCR_CPU0_P0_BOOT5':
 C_SIGNAL='@t6g_mb_lib.t6g(sch_1):sw_pvddcr_cpu0_p0_boot5';
NODE_NAME     PU48 33
 '@T6G_MB_LIB.T6G(SCH_1):PAGE171_I18@PURE_QUANTA.ISL99390FRZTR5935(CHIPS)':
 'BOOT': CDS_PINID='BOOT';
NODE_NAME     PR354 1
 '@T6G_MB_LIB.T6G(SCH_1):PAGE171_I45@PURE_QUANTA.Q_RES(CHIPS)':
 'A': CDS_PINID='A';
NET_NAME
'SW_PVDDCR_CPU0_P0_BOOT5_RC'
 '@T6G_MB_LIB.T6G(SCH_1):SW_PVDDCR_CPU0_P0_BOOT5_RC':
 C_SIGNAL='@t6g_mb_lib.t6g(sch_1):sw_pvddcr_cpu0_p0_boot5_rc';
NODE_NAME     PR354 2
 '@T6G_MB_LIB.T6G(SCH_1):PAGE171_I45@PURE_QUANTA.Q_RES(CHIPS)':
 'B': CDS_PINID='B';
NODE_NAME     PC574 1
 '@T6G_MB_LIB.T6G(SCH_1):PAGE171_I63@PURE_QUANTA.Q_CAP(CHIPS)':
 'A': CDS_PINID='A';
NET_NAME
'SW_PVDDCR_CPU0_P0_BOOT6'
 '@T6G_MB_LIB.T6G(SCH_1):SW_PVDDCR_CPU0_P0_BOOT6':
 C_SIGNAL='@t6g_mb_lib.t6g(sch_1):sw_pvddcr_cpu0_p0_boot6';
NODE_NAME     PR432 1
 '@T6G_MB_LIB.T6G(SCH_1):PAGE171_I26@PURE_QUANTA.Q_RES(CHIPS)':
 'A': CDS_PINID='A';
NODE_NAME     PU10 33
 '@T6G_MB_LIB.T6G(SCH_1):PAGE171_I73@PURE_QUANTA.ISL99390FRZTR5935(CHIPS)':
 'BOOT': CDS_PINID='BOOT';
NET_NAME
'SW_PVDDCR_CPU0_P0_BOOT6_RC'
 '@T6G_MB_LIB.T6G(SCH_1):SW_PVDDCR_CPU0_P0_BOOT6_RC':
 C_SIGNAL='@t6g_mb_lib.t6g(sch_1):sw_pvddcr_cpu0_p0_boot6_rc';
NODE_NAME     PR432 2
 '@T6G_MB_LIB.T6G(SCH_1):PAGE171_I26@PURE_QUANTA.Q_RES(CHIPS)':
 'B': CDS_PINID='B';
NODE_NAME     PC161 1
 '@T6G_MB_LIB.T6G(SCH_1):PAGE171_I54@PURE_QUANTA.Q_CAP(CHIPS)':
 'A': CDS_PINID='A';
NET_NAME
'SW_PVDDCR_CPU0_P0_PH1'
 '@T6G_MB_LIB.T6G(SCH_1):SW_PVDDCR_CPU0_P0_PH1':
 C_SIGNAL='@t6g_mb_lib.t6g(sch_1):sw_pvddcr_cpu0_p0_ph1';
NODE_NAME     PU6 32
 '@T6G_MB_LIB.T6G(SCH_1):PAGE169_I26@PURE_QUANTA.ISL99390FRZTR5935(CHIPS)':
 'PHASE': CDS_PINID='PHASE';
NODE_NAME     PC489 2
 '@T6G_MB_LIB.T6G(SCH_1):PAGE169_I76@PURE_QUANTA.Q_CAP(CHIPS)':
 'B': CDS_PINID='B';
NET_NAME
'SW_PVDDCR_CPU0_P0_PH2'
 '@T6G_MB_LIB.T6G(SCH_1):SW_PVDDCR_CPU0_P0_PH2':
 C_SIGNAL='@t6g_mb_lib.t6g(sch_1):sw_pvddcr_cpu0_p0_ph2';
NODE_NAME     PU43 32
 '@T6G_MB_LIB.T6G(SCH_1):PAGE169_I16@PURE_QUANTA.ISL99390FRZTR5935(CHIPS)':
 'PHASE': CDS_PINID='PHASE';
NODE_NAME     PC490 2
 '@T6G_MB_LIB.T6G(SCH_1):PAGE169_I61@PURE_QUANTA.Q_CAP(CHIPS)':
 'B': CDS_PINID='B';
NET_NAME
'SW_PVDDCR_CPU0_P0_PH3'
 '@T6G_MB_LIB.T6G(SCH_1):SW_PVDDCR_CPU0_P0_PH3':
 C_SIGNAL='@t6g_mb_lib.t6g(sch_1):sw_pvddcr_cpu0_p0_ph3';
NODE_NAME     PU46 32
 '@T6G_MB_LIB.T6G(SCH_1):PAGE170_I38@PURE_QUANTA.ISL99390FRZTR5935(CHIPS)':
 'PHASE': CDS_PINID='PHASE';
NODE_NAME     PC560 2
 '@T6G_MB_LIB.T6G(SCH_1):PAGE170_I63@PURE_QUANTA.Q_CAP(CHIPS)':
 'B': CDS_PINID='B';
NET_NAME
'SW_PVDDCR_CPU0_P0_PH4'
 '@T6G_MB_LIB.T6G(SCH_1):SW_PVDDCR_CPU0_P0_PH4':
 C_SIGNAL='@t6g_mb_lib.t6g(sch_1):sw_pvddcr_cpu0_p0_ph4';
NODE_NAME     PU47 32
 '@T6G_MB_LIB.T6G(SCH_1):PAGE170_I9@PURE_QUANTA.ISL99390FRZTR5935(CHIPS)':
 'PHASE': CDS_PINID='PHASE';
NODE_NAME     PC561 2
 '@T6G_MB_LIB.T6G(SCH_1):PAGE170_I53@PURE_QUANTA.Q_CAP(CHIPS)':
 'B': CDS_PINID='B';
NET_NAME
'SW_PVDDCR_CPU0_P0_PH5'
 '@T6G_MB_LIB.T6G(SCH_1):SW_PVDDCR_CPU0_P0_PH5':
 C_SIGNAL='@t6g_mb_lib.t6g(sch_1):sw_pvddcr_cpu0_p0_ph5';
NODE_NAME     PU48 32
 '@T6G_MB_LIB.T6G(SCH_1):PAGE171_I18@PURE_QUANTA.ISL99390FRZTR5935(CHIPS)':
 'PHASE': CDS_PINID='PHASE';
NODE_NAME     PC574 2
 '@T6G_MB_LIB.T6G(SCH_1):PAGE171_I63@PURE_QUANTA.Q_CAP(CHIPS)':
 'B': CDS_PINID='B';
NET_NAME
'SW_PVDDCR_CPU0_P0_PH6'
 '@T6G_MB_LIB.T6G(SCH_1):SW_PVDDCR_CPU0_P0_PH6':
 C_SIGNAL='@t6g_mb_lib.t6g(sch_1):sw_pvddcr_cpu0_p0_ph6';
NODE_NAME     PC161 2
 '@T6G_MB_LIB.T6G(SCH_1):PAGE171_I54@PURE_QUANTA.Q_CAP(CHIPS)':
 'B': CDS_PINID='B';
NODE_NAME     PU10 32
 '@T6G_MB_LIB.T6G(SCH_1):PAGE171_I73@PURE_QUANTA.ISL99390FRZTR5935(CHIPS)':
 'PHASE': CDS_PINID='PHASE';
NET_NAME
'SW_PVDDCR_CPU0_P0_SW1'
 '@T6G_MB_LIB.T6G(SCH_1):SW_PVDDCR_CPU0_P0_SW1':
 C_SIGNAL='@t6g_mb_lib.t6g(sch_1):sw_pvddcr_cpu0_p0_sw1';
NODE_NAME     PU6 10_19
 '@T6G_MB_LIB.T6G(SCH_1):PAGE169_I26@PURE_QUANTA.ISL99390FRZTR5935(CHIPS)':
 'SW': CDS_PINID='SW';
NODE_NAME     PC178 1
 '@T6G_MB_LIB.T6G(SCH_1):PAGE169_I54@PURE_QUANTA.Q_CAP(CHIPS)':
 'A': CDS_PINID='A';
NODE_NAME     PL51 1
 '@T6G_MB_LIB.T6G(SCH_1):PAGE169_I77@PURE_QUANTA.Q_INDUCTOR4P_14(CHIPS)':
 '1': CDS_PINID='\1\';
NET_NAME
'SW_PVDDCR_CPU0_P0_SW1_RC'
 '@T6G_MB_LIB.T6G(SCH_1):SW_PVDDCR_CPU0_P0_SW1_RC':
 C_SIGNAL='@t6g_mb_lib.t6g(sch_1):sw_pvddcr_cpu0_p0_sw1_rc';
NODE_NAME     PR495 1
 '@T6G_MB_LIB.T6G(SCH_1):PAGE169_I42@PURE_QUANTA.Q_RES(CHIPS)':
 'A': CDS_PINID='A';
NODE_NAME     PC178 2
 '@T6G_MB_LIB.T6G(SCH_1):PAGE169_I54@PURE_QUANTA.Q_CAP(CHIPS)':
 'B': CDS_PINID='B';
NET_NAME
'SW_PVDDCR_CPU0_P0_SW2'
 '@T6G_MB_LIB.T6G(SCH_1):SW_PVDDCR_CPU0_P0_SW2':
 C_SIGNAL='@t6g_mb_lib.t6g(sch_1):sw_pvddcr_cpu0_p0_sw2';
NODE_NAME     PU43 10_19
 '@T6G_MB_LIB.T6G(SCH_1):PAGE169_I16@PURE_QUANTA.ISL99390FRZTR5935(CHIPS)':
 'SW': CDS_PINID='SW';
NODE_NAME     PC179 1
 '@T6G_MB_LIB.T6G(SCH_1):PAGE169_I31@PURE_QUANTA.Q_CAP(CHIPS)':
 'A': CDS_PINID='A';
NODE_NAME     PL52 1
 '@T6G_MB_LIB.T6G(SCH_1):PAGE169_I62@PURE_QUANTA.Q_INDUCTOR4P_14(CHIPS)':
 '1': CDS_PINID='\1\';
NET_NAME
'SW_PVDDCR_CPU0_P0_SW2_RC'
 '@T6G_MB_LIB.T6G(SCH_1):SW_PVDDCR_CPU0_P0_SW2_RC':
 C_SIGNAL='@t6g_mb_lib.t6g(sch_1):sw_pvddcr_cpu0_p0_sw2_rc';
NODE_NAME     PC179 2
 '@T6G_MB_LIB.T6G(SCH_1):PAGE169_I31@PURE_QUANTA.Q_CAP(CHIPS)':
 'B': CDS_PINID='B';
NODE_NAME     PR496 1
 '@T6G_MB_LIB.T6G(SCH_1):PAGE169_I28@PURE_QUANTA.Q_RES(CHIPS)':
 'A': CDS_PINID='A';
NET_NAME
'SW_PVDDCR_CPU0_P0_SW3'
 '@T6G_MB_LIB.T6G(SCH_1):SW_PVDDCR_CPU0_P0_SW3':
 C_SIGNAL='@t6g_mb_lib.t6g(sch_1):sw_pvddcr_cpu0_p0_sw3';
NODE_NAME     PU46 10_19
 '@T6G_MB_LIB.T6G(SCH_1):PAGE170_I38@PURE_QUANTA.ISL99390FRZTR5935(CHIPS)':
 'SW': CDS_PINID='SW';
NODE_NAME     PC180 1
 '@T6G_MB_LIB.T6G(SCH_1):PAGE170_I45@PURE_QUANTA.Q_CAP(CHIPS)':
 'A': CDS_PINID='A';
NODE_NAME     PL59 1
 '@T6G_MB_LIB.T6G(SCH_1):PAGE170_I64@PURE_QUANTA.Q_INDUCTOR4P_14(CHIPS)':
 '1': CDS_PINID='\1\';
NET_NAME
'SW_PVDDCR_CPU0_P0_SW3_RC'
 '@T6G_MB_LIB.T6G(SCH_1):SW_PVDDCR_CPU0_P0_SW3_RC':
 C_SIGNAL='@t6g_mb_lib.t6g(sch_1):sw_pvddcr_cpu0_p0_sw3_rc';
NODE_NAME     PR498 1
 '@T6G_MB_LIB.T6G(SCH_1):PAGE170_I44@PURE_QUANTA.Q_RES(CHIPS)':
 'A': CDS_PINID='A';
NODE_NAME     PC180 2
 '@T6G_MB_LIB.T6G(SCH_1):PAGE170_I45@PURE_QUANTA.Q_CAP(CHIPS)':
 'B': CDS_PINID='B';
NET_NAME
'SW_PVDDCR_CPU0_P0_SW4'
 '@T6G_MB_LIB.T6G(SCH_1):SW_PVDDCR_CPU0_P0_SW4':
 C_SIGNAL='@t6g_mb_lib.t6g(sch_1):sw_pvddcr_cpu0_p0_sw4';
NODE_NAME     PC181 1
 '@T6G_MB_LIB.T6G(SCH_1):PAGE170_I19@PURE_QUANTA.Q_CAP(CHIPS)':
 'A': CDS_PINID='A';
NODE_NAME     PU47 10_19
 '@T6G_MB_LIB.T6G(SCH_1):PAGE170_I9@PURE_QUANTA.ISL99390FRZTR5935(CHIPS)':
 'SW': CDS_PINID='SW';
NODE_NAME     PL60 1
 '@T6G_MB_LIB.T6G(SCH_1):PAGE170_I52@PURE_QUANTA.Q_INDUCTOR4P_14(CHIPS)':
 '1': CDS_PINID='\1\';
NET_NAME
'SW_PVDDCR_CPU0_P0_SW4_RC'
 '@T6G_MB_LIB.T6G(SCH_1):SW_PVDDCR_CPU0_P0_SW4_RC':
 C_SIGNAL='@t6g_mb_lib.t6g(sch_1):sw_pvddcr_cpu0_p0_sw4_rc';
NODE_NAME     PR499 1
 '@T6G_MB_LIB.T6G(SCH_1):PAGE170_I18@PURE_QUANTA.Q_RES(CHIPS)':
 'A': CDS_PINID='A';
NODE_NAME     PC181 2
 '@T6G_MB_LIB.T6G(SCH_1):PAGE170_I19@PURE_QUANTA.Q_CAP(CHIPS)':
 'B': CDS_PINID='B';
NET_NAME
'SW_PVDDCR_CPU0_P0_SW5'
 '@T6G_MB_LIB.T6G(SCH_1):SW_PVDDCR_CPU0_P0_SW5':
 C_SIGNAL='@t6g_mb_lib.t6g(sch_1):sw_pvddcr_cpu0_p0_sw5';
NODE_NAME     PU48 10_19
 '@T6G_MB_LIB.T6G(SCH_1):PAGE171_I18@PURE_QUANTA.ISL99390FRZTR5935(CHIPS)':
 'SW': CDS_PINID='SW';
NODE_NAME     PC184 1
 '@T6G_MB_LIB.T6G(SCH_1):PAGE171_I46@PURE_QUANTA.Q_CAP(CHIPS)':
 'A': CDS_PINID='A';
NODE_NAME     PL61 1
 '@T6G_MB_LIB.T6G(SCH_1):PAGE171_I64@PURE_QUANTA.Q_INDUCTOR4P_14(CHIPS)':
 '1': CDS_PINID='\1\';
NET_NAME
'SW_PVDDCR_CPU0_P0_SW5_RC'
 '@T6G_MB_LIB.T6G(SCH_1):SW_PVDDCR_CPU0_P0_SW5_RC':
 C_SIGNAL='@t6g_mb_lib.t6g(sch_1):sw_pvddcr_cpu0_p0_sw5_rc';
NODE_NAME     PR501 1
 '@T6G_MB_LIB.T6G(SCH_1):PAGE171_I31@PURE_QUANTA.Q_RES(CHIPS)':
 'A': CDS_PINID='A';
NODE_NAME     PC184 2
 '@T6G_MB_LIB.T6G(SCH_1):PAGE171_I46@PURE_QUANTA.Q_CAP(CHIPS)':
 'B': CDS_PINID='B';
NET_NAME
'SW_PVDDCR_CPU0_P0_SW6'
 '@T6G_MB_LIB.T6G(SCH_1):SW_PVDDCR_CPU0_P0_SW6':
 C_SIGNAL='@t6g_mb_lib.t6g(sch_1):sw_pvddcr_cpu0_p0_sw6';
NODE_NAME     PC182 1
 '@T6G_MB_LIB.T6G(SCH_1):PAGE171_I23@PURE_QUANTA.Q_CAP(CHIPS)':
 'A': CDS_PINID='A';
NODE_NAME     PL70 1
 '@T6G_MB_LIB.T6G(SCH_1):PAGE171_I52@PURE_QUANTA.Q_INDUCTOR4P_14(CHIPS)':
 '1': CDS_PINID='\1\';
NODE_NAME     PU10 10_19
 '@T6G_MB_LIB.T6G(SCH_1):PAGE171_I73@PURE_QUANTA.ISL99390FRZTR5935(CHIPS)':
 'SW': CDS_PINID='SW';
NET_NAME
'SW_PVDDCR_CPU0_P0_SW6_RC'
 '@T6G_MB_LIB.T6G(SCH_1):SW_PVDDCR_CPU0_P0_SW6_RC':
 C_SIGNAL='@t6g_mb_lib.t6g(sch_1):sw_pvddcr_cpu0_p0_sw6_rc';
NODE_NAME     PR500 1
 '@T6G_MB_LIB.T6G(SCH_1):PAGE171_I22@PURE_QUANTA.Q_RES(CHIPS)':
 'A': CDS_PINID='A';
NODE_NAME     PC182 2
 '@T6G_MB_LIB.T6G(SCH_1):PAGE171_I23@PURE_QUANTA.Q_CAP(CHIPS)':
 'B': CDS_PINID='B';
NET_NAME
'SW_PVDDCR_CPU0_P1_BOOT1'
 '@T6G_MB_LIB.T6G(SCH_1):SW_PVDDCR_CPU0_P1_BOOT1':
 C_SIGNAL='@t6g_mb_lib.t6g(sch_1):sw_pvddcr_cpu0_p1_boot1';
NODE_NAME     PR189 1
 '@T6G_MB_LIB.T6G(SCH_1):PAGE186_I49@PURE_QUANTA.Q_RES(CHIPS)':
 'A': CDS_PINID='A';
NODE_NAME     PU4 33
 '@T6G_MB_LIB.T6G(SCH_1):PAGE186_I88@PURE_QUANTA.ISL99390FRZTR5935(CHIPS)':
 'BOOT': CDS_PINID='BOOT';
NET_NAME
'SW_PVDDCR_CPU0_P1_BOOT1_RC'
 '@T6G_MB_LIB.T6G(SCH_1):SW_PVDDCR_CPU0_P1_BOOT1_RC':
 C_SIGNAL='@t6g_mb_lib.t6g(sch_1):sw_pvddcr_cpu0_p1_boot1_rc';
NODE_NAME     PR189 2
 '@T6G_MB_LIB.T6G(SCH_1):PAGE186_I49@PURE_QUANTA.Q_RES(CHIPS)':
 'B': CDS_PINID='B';
NODE_NAME     PC270 1
 '@T6G_MB_LIB.T6G(SCH_1):PAGE186_I89@PURE_QUANTA.Q_CAP(CHIPS)':
 'A': CDS_PINID='A';
NET_NAME
'SW_PVDDCR_CPU0_P1_BOOT2'
 '@T6G_MB_LIB.T6G(SCH_1):SW_PVDDCR_CPU0_P1_BOOT2':
 C_SIGNAL='@t6g_mb_lib.t6g(sch_1):sw_pvddcr_cpu0_p1_boot2';
NODE_NAME     PR190 1
 '@T6G_MB_LIB.T6G(SCH_1):PAGE186_I83@PURE_QUANTA.Q_RES(CHIPS)':
 'A': CDS_PINID='A';
NODE_NAME     PU26 33
 '@T6G_MB_LIB.T6G(SCH_1):PAGE186_I91@PURE_QUANTA.ISL99390FRZTR5935(CHIPS)':
 'BOOT': CDS_PINID='BOOT';
NET_NAME
'SW_PVDDCR_CPU0_P1_BOOT2_RC'
 '@T6G_MB_LIB.T6G(SCH_1):SW_PVDDCR_CPU0_P1_BOOT2_RC':
 C_SIGNAL='@t6g_mb_lib.t6g(sch_1):sw_pvddcr_cpu0_p1_boot2_rc';
NODE_NAME     PC271 1
 '@T6G_MB_LIB.T6G(SCH_1):PAGE186_I55@PURE_QUANTA.Q_CAP(CHIPS)':
 'A': CDS_PINID='A';
NODE_NAME     PR190 2
 '@T6G_MB_LIB.T6G(SCH_1):PAGE186_I83@PURE_QUANTA.Q_RES(CHIPS)':
 'B': CDS_PINID='B';
NET_NAME
'SW_PVDDCR_CPU0_P1_BOOT3'
 '@T6G_MB_LIB.T6G(SCH_1):SW_PVDDCR_CPU0_P1_BOOT3':
 C_SIGNAL='@t6g_mb_lib.t6g(sch_1):sw_pvddcr_cpu0_p1_boot3';
NODE_NAME     PU27 33
 '@T6G_MB_LIB.T6G(SCH_1):PAGE187_I39@PURE_QUANTA.ISL99390FRZTR5935(CHIPS)':
 'BOOT': CDS_PINID='BOOT';
NODE_NAME     PR197 1
 '@T6G_MB_LIB.T6G(SCH_1):PAGE187_I47@PURE_QUANTA.Q_RES(CHIPS)':
 'A': CDS_PINID='A';
NET_NAME
'SW_PVDDCR_CPU0_P1_BOOT3_RC'
 '@T6G_MB_LIB.T6G(SCH_1):SW_PVDDCR_CPU0_P1_BOOT3_RC':
 C_SIGNAL='@t6g_mb_lib.t6g(sch_1):sw_pvddcr_cpu0_p1_boot3_rc';
NODE_NAME     PR197 2
 '@T6G_MB_LIB.T6G(SCH_1):PAGE187_I47@PURE_QUANTA.Q_RES(CHIPS)':
 'B': CDS_PINID='B';
NODE_NAME     PC300 1
 '@T6G_MB_LIB.T6G(SCH_1):PAGE187_I63@PURE_QUANTA.Q_CAP(CHIPS)':
 'A': CDS_PINID='A';
NET_NAME
'SW_PVDDCR_CPU0_P1_BOOT4'
 '@T6G_MB_LIB.T6G(SCH_1):SW_PVDDCR_CPU0_P1_BOOT4':
 C_SIGNAL='@t6g_mb_lib.t6g(sch_1):sw_pvddcr_cpu0_p1_boot4';
NODE_NAME     PU28 33
 '@T6G_MB_LIB.T6G(SCH_1):PAGE187_I9@PURE_QUANTA.ISL99390FRZTR5935(CHIPS)':
 'BOOT': CDS_PINID='BOOT';
NODE_NAME     PR198 1
 '@T6G_MB_LIB.T6G(SCH_1):PAGE187_I21@PURE_QUANTA.Q_RES(CHIPS)':
 'A': CDS_PINID='A';
NET_NAME
'SW_PVDDCR_CPU0_P1_BOOT4_RC'
 '@T6G_MB_LIB.T6G(SCH_1):SW_PVDDCR_CPU0_P1_BOOT4_RC':
 C_SIGNAL='@t6g_mb_lib.t6g(sch_1):sw_pvddcr_cpu0_p1_boot4_rc';
NODE_NAME     PR198 2
 '@T6G_MB_LIB.T6G(SCH_1):PAGE187_I21@PURE_QUANTA.Q_RES(CHIPS)':
 'B': CDS_PINID='B';
NODE_NAME     PC301 1
 '@T6G_MB_LIB.T6G(SCH_1):PAGE187_I52@PURE_QUANTA.Q_CAP(CHIPS)':
 'A': CDS_PINID='A';
NET_NAME
'SW_PVDDCR_CPU0_P1_BOOT5'
 '@T6G_MB_LIB.T6G(SCH_1):SW_PVDDCR_CPU0_P1_BOOT5':
 C_SIGNAL='@t6g_mb_lib.t6g(sch_1):sw_pvddcr_cpu0_p1_boot5';
NODE_NAME     PU29 33
 '@T6G_MB_LIB.T6G(SCH_1):PAGE188_I18@PURE_QUANTA.ISL99390FRZTR5935(CHIPS)':
 'BOOT': CDS_PINID='BOOT';
NODE_NAME     PR203 1
 '@T6G_MB_LIB.T6G(SCH_1):PAGE188_I47@PURE_QUANTA.Q_RES(CHIPS)':
 'A': CDS_PINID='A';
NET_NAME
'SW_PVDDCR_CPU0_P1_BOOT5_RC'
 '@T6G_MB_LIB.T6G(SCH_1):SW_PVDDCR_CPU0_P1_BOOT5_RC':
 C_SIGNAL='@t6g_mb_lib.t6g(sch_1):sw_pvddcr_cpu0_p1_boot5_rc';
NODE_NAME     PR203 2
 '@T6G_MB_LIB.T6G(SCH_1):PAGE188_I47@PURE_QUANTA.Q_RES(CHIPS)':
 'B': CDS_PINID='B';
NODE_NAME     PC314 1
 '@T6G_MB_LIB.T6G(SCH_1):PAGE188_I63@PURE_QUANTA.Q_CAP(CHIPS)':
 'A': CDS_PINID='A';
NET_NAME
'SW_PVDDCR_CPU0_P1_BOOT6'
 '@T6G_MB_LIB.T6G(SCH_1):SW_PVDDCR_CPU0_P1_BOOT6':
 C_SIGNAL='@t6g_mb_lib.t6g(sch_1):sw_pvddcr_cpu0_p1_boot6';
NODE_NAME     PR424 1
 '@T6G_MB_LIB.T6G(SCH_1):PAGE188_I28@PURE_QUANTA.Q_RES(CHIPS)':
 'A': CDS_PINID='A';
NODE_NAME     PU24 33
 '@T6G_MB_LIB.T6G(SCH_1):PAGE188_I73@PURE_QUANTA.ISL99390FRZTR5935(CHIPS)':
 'BOOT': CDS_PINID='BOOT';
NET_NAME
'SW_PVDDCR_CPU0_P1_BOOT6_RC'
 '@T6G_MB_LIB.T6G(SCH_1):SW_PVDDCR_CPU0_P1_BOOT6_RC':
 C_SIGNAL='@t6g_mb_lib.t6g(sch_1):sw_pvddcr_cpu0_p1_boot6_rc';
NODE_NAME     PR424 2
 '@T6G_MB_LIB.T6G(SCH_1):PAGE188_I28@PURE_QUANTA.Q_RES(CHIPS)':
 'B': CDS_PINID='B';
NODE_NAME     PC133 1
 '@T6G_MB_LIB.T6G(SCH_1):PAGE188_I52@PURE_QUANTA.Q_CAP(CHIPS)':
 'A': CDS_PINID='A';
NET_NAME
'SW_PVDDCR_CPU0_P1_PH1'
 '@T6G_MB_LIB.T6G(SCH_1):SW_PVDDCR_CPU0_P1_PH1':
 C_SIGNAL='@t6g_mb_lib.t6g(sch_1):sw_pvddcr_cpu0_p1_ph1';
NODE_NAME     PU4 32
 '@T6G_MB_LIB.T6G(SCH_1):PAGE186_I88@PURE_QUANTA.ISL99390FRZTR5935(CHIPS)':
 'PHASE': CDS_PINID='PHASE';
NODE_NAME     PC270 2
 '@T6G_MB_LIB.T6G(SCH_1):PAGE186_I89@PURE_QUANTA.Q_CAP(CHIPS)':
 'B': CDS_PINID='B';
NET_NAME
'SW_PVDDCR_CPU0_P1_PH2'
 '@T6G_MB_LIB.T6G(SCH_1):SW_PVDDCR_CPU0_P1_PH2':
 C_SIGNAL='@t6g_mb_lib.t6g(sch_1):sw_pvddcr_cpu0_p1_ph2';
NODE_NAME     PC271 2
 '@T6G_MB_LIB.T6G(SCH_1):PAGE186_I55@PURE_QUANTA.Q_CAP(CHIPS)':
 'B': CDS_PINID='B';
NODE_NAME     PU26 32
 '@T6G_MB_LIB.T6G(SCH_1):PAGE186_I91@PURE_QUANTA.ISL99390FRZTR5935(CHIPS)':
 'PHASE': CDS_PINID='PHASE';
NET_NAME
'SW_PVDDCR_CPU0_P1_PH3'
 '@T6G_MB_LIB.T6G(SCH_1):SW_PVDDCR_CPU0_P1_PH3':
 C_SIGNAL='@t6g_mb_lib.t6g(sch_1):sw_pvddcr_cpu0_p1_ph3';
NODE_NAME     PU27 32
 '@T6G_MB_LIB.T6G(SCH_1):PAGE187_I39@PURE_QUANTA.ISL99390FRZTR5935(CHIPS)':
 'PHASE': CDS_PINID='PHASE';
NODE_NAME     PC300 2
 '@T6G_MB_LIB.T6G(SCH_1):PAGE187_I63@PURE_QUANTA.Q_CAP(CHIPS)':
 'B': CDS_PINID='B';
NET_NAME
'SW_PVDDCR_CPU0_P1_PH4'
 '@T6G_MB_LIB.T6G(SCH_1):SW_PVDDCR_CPU0_P1_PH4':
 C_SIGNAL='@t6g_mb_lib.t6g(sch_1):sw_pvddcr_cpu0_p1_ph4';
NODE_NAME     PU28 32
 '@T6G_MB_LIB.T6G(SCH_1):PAGE187_I9@PURE_QUANTA.ISL99390FRZTR5935(CHIPS)':
 'PHASE': CDS_PINID='PHASE';
NODE_NAME     PC301 2
 '@T6G_MB_LIB.T6G(SCH_1):PAGE187_I52@PURE_QUANTA.Q_CAP(CHIPS)':
 'B': CDS_PINID='B';
NET_NAME
'SW_PVDDCR_CPU0_P1_PH5'
 '@T6G_MB_LIB.T6G(SCH_1):SW_PVDDCR_CPU0_P1_PH5':
 C_SIGNAL='@t6g_mb_lib.t6g(sch_1):sw_pvddcr_cpu0_p1_ph5';
NODE_NAME     PU29 32
 '@T6G_MB_LIB.T6G(SCH_1):PAGE188_I18@PURE_QUANTA.ISL99390FRZTR5935(CHIPS)':
 'PHASE': CDS_PINID='PHASE';
NODE_NAME     PC314 2
 '@T6G_MB_LIB.T6G(SCH_1):PAGE188_I63@PURE_QUANTA.Q_CAP(CHIPS)':
 'B': CDS_PINID='B';
NET_NAME
'SW_PVDDCR_CPU0_P1_PH6'
 '@T6G_MB_LIB.T6G(SCH_1):SW_PVDDCR_CPU0_P1_PH6':
 C_SIGNAL='@t6g_mb_lib.t6g(sch_1):sw_pvddcr_cpu0_p1_ph6';
NODE_NAME     PC133 2
 '@T6G_MB_LIB.T6G(SCH_1):PAGE188_I52@PURE_QUANTA.Q_CAP(CHIPS)':
 'B': CDS_PINID='B';
NODE_NAME     PU24 32
 '@T6G_MB_LIB.T6G(SCH_1):PAGE188_I73@PURE_QUANTA.ISL99390FRZTR5935(CHIPS)':
 'PHASE': CDS_PINID='PHASE';
NET_NAME
'SW_PVDDCR_CPU0_P1_SW1'
 '@T6G_MB_LIB.T6G(SCH_1):SW_PVDDCR_CPU0_P1_SW1':
 C_SIGNAL='@t6g_mb_lib.t6g(sch_1):sw_pvddcr_cpu0_p1_sw1';
NODE_NAME     PC170 1
 '@T6G_MB_LIB.T6G(SCH_1):PAGE186_I48@PURE_QUANTA.Q_CAP(CHIPS)':
 'A': CDS_PINID='A';
NODE_NAME     PU4 10_19
 '@T6G_MB_LIB.T6G(SCH_1):PAGE186_I88@PURE_QUANTA.ISL99390FRZTR5935(CHIPS)':
 'SW': CDS_PINID='SW';
NODE_NAME     PL28 1
 '@T6G_MB_LIB.T6G(SCH_1):PAGE186_I90@PURE_QUANTA.Q_INDUCTOR4P_14(CHIPS)':
 '1': CDS_PINID='\1\';
NET_NAME
'SW_PVDDCR_CPU0_P1_SW1_RC'
 '@T6G_MB_LIB.T6G(SCH_1):SW_PVDDCR_CPU0_P1_SW1_RC':
 C_SIGNAL='@t6g_mb_lib.t6g(sch_1):sw_pvddcr_cpu0_p1_sw1_rc';
NODE_NAME     PC170 2
 '@T6G_MB_LIB.T6G(SCH_1):PAGE186_I48@PURE_QUANTA.Q_CAP(CHIPS)':
 'B': CDS_PINID='B';
NODE_NAME     PR485 1
 '@T6G_MB_LIB.T6G(SCH_1):PAGE186_I34@PURE_QUANTA.Q_RES(CHIPS)':
 'A': CDS_PINID='A';
NET_NAME
'SW_PVDDCR_CPU0_P1_SW2'
 '@T6G_MB_LIB.T6G(SCH_1):SW_PVDDCR_CPU0_P1_SW2':
 C_SIGNAL='@t6g_mb_lib.t6g(sch_1):sw_pvddcr_cpu0_p1_sw2';
NODE_NAME     PC173 1
 '@T6G_MB_LIB.T6G(SCH_1):PAGE186_I24@PURE_QUANTA.Q_CAP(CHIPS)':
 'A': CDS_PINID='A';
NODE_NAME     PL29 1
 '@T6G_MB_LIB.T6G(SCH_1):PAGE186_I56@PURE_QUANTA.Q_INDUCTOR4P_14(CHIPS)':
 '1': CDS_PINID='\1\';
NODE_NAME     PU26 10_19
 '@T6G_MB_LIB.T6G(SCH_1):PAGE186_I91@PURE_QUANTA.ISL99390FRZTR5935(CHIPS)':
 'SW': CDS_PINID='SW';
NET_NAME
'SW_PVDDCR_CPU0_P1_SW2_RC'
 '@T6G_MB_LIB.T6G(SCH_1):SW_PVDDCR_CPU0_P1_SW2_RC':
 C_SIGNAL='@t6g_mb_lib.t6g(sch_1):sw_pvddcr_cpu0_p1_sw2_rc';
NODE_NAME     PC173 2
 '@T6G_MB_LIB.T6G(SCH_1):PAGE186_I24@PURE_QUANTA.Q_CAP(CHIPS)':
 'B': CDS_PINID='B';
NODE_NAME     PR486 1
 '@T6G_MB_LIB.T6G(SCH_1):PAGE186_I22@PURE_QUANTA.Q_RES(CHIPS)':
 'A': CDS_PINID='A';
NET_NAME
'SW_PVDDCR_CPU0_P1_SW3'
 '@T6G_MB_LIB.T6G(SCH_1):SW_PVDDCR_CPU0_P1_SW3':
 C_SIGNAL='@t6g_mb_lib.t6g(sch_1):sw_pvddcr_cpu0_p1_sw3';
NODE_NAME     PU27 10_19
 '@T6G_MB_LIB.T6G(SCH_1):PAGE187_I39@PURE_QUANTA.ISL99390FRZTR5935(CHIPS)':
 'SW': CDS_PINID='SW';
NODE_NAME     PC316 1
 '@T6G_MB_LIB.T6G(SCH_1):PAGE187_I46@PURE_QUANTA.Q_CAP(CHIPS)':
 'A': CDS_PINID='A';
NODE_NAME     PL31 1
 '@T6G_MB_LIB.T6G(SCH_1):PAGE187_I67@PURE_QUANTA.Q_INDUCTOR4P_14(CHIPS)':
 '1': CDS_PINID='\1\';
NET_NAME
'SW_PVDDCR_CPU0_P1_SW3_RC'
 '@T6G_MB_LIB.T6G(SCH_1):SW_PVDDCR_CPU0_P1_SW3_RC':
 C_SIGNAL='@t6g_mb_lib.t6g(sch_1):sw_pvddcr_cpu0_p1_sw3_rc';
NODE_NAME     PR522 1
 '@T6G_MB_LIB.T6G(SCH_1):PAGE187_I45@PURE_QUANTA.Q_RES(CHIPS)':
 'A': CDS_PINID='A';
NODE_NAME     PC316 2
 '@T6G_MB_LIB.T6G(SCH_1):PAGE187_I46@PURE_QUANTA.Q_CAP(CHIPS)':
 'B': CDS_PINID='B';
NET_NAME
'SW_PVDDCR_CPU0_P1_SW4'
 '@T6G_MB_LIB.T6G(SCH_1):SW_PVDDCR_CPU0_P1_SW4':
 C_SIGNAL='@t6g_mb_lib.t6g(sch_1):sw_pvddcr_cpu0_p1_sw4';
NODE_NAME     PU28 10_19
 '@T6G_MB_LIB.T6G(SCH_1):PAGE187_I9@PURE_QUANTA.ISL99390FRZTR5935(CHIPS)':
 'SW': CDS_PINID='SW';
NODE_NAME     PC317 1
 '@T6G_MB_LIB.T6G(SCH_1):PAGE187_I20@PURE_QUANTA.Q_CAP(CHIPS)':
 'A': CDS_PINID='A';
NODE_NAME     PL32 1
 '@T6G_MB_LIB.T6G(SCH_1):PAGE187_I53@PURE_QUANTA.Q_INDUCTOR4P_14(CHIPS)':
 '1': CDS_PINID='\1\';
NET_NAME
'SW_PVDDCR_CPU0_P1_SW4_RC'
 '@T6G_MB_LIB.T6G(SCH_1):SW_PVDDCR_CPU0_P1_SW4_RC':
 C_SIGNAL='@t6g_mb_lib.t6g(sch_1):sw_pvddcr_cpu0_p1_sw4_rc';
NODE_NAME     PR523 1
 '@T6G_MB_LIB.T6G(SCH_1):PAGE187_I19@PURE_QUANTA.Q_RES(CHIPS)':
 'A': CDS_PINID='A';
NODE_NAME     PC317 2
 '@T6G_MB_LIB.T6G(SCH_1):PAGE187_I20@PURE_QUANTA.Q_CAP(CHIPS)':
 'B': CDS_PINID='B';
NET_NAME
'SW_PVDDCR_CPU0_P1_SW5'
 '@T6G_MB_LIB.T6G(SCH_1):SW_PVDDCR_CPU0_P1_SW5':
 C_SIGNAL='@t6g_mb_lib.t6g(sch_1):sw_pvddcr_cpu0_p1_sw5';
NODE_NAME     PU29 10_19
 '@T6G_MB_LIB.T6G(SCH_1):PAGE188_I18@PURE_QUANTA.ISL99390FRZTR5935(CHIPS)':
 'SW': CDS_PINID='SW';
NODE_NAME     PC318 1
 '@T6G_MB_LIB.T6G(SCH_1):PAGE188_I46@PURE_QUANTA.Q_CAP(CHIPS)':
 'A': CDS_PINID='A';
NODE_NAME     PL33 1
 '@T6G_MB_LIB.T6G(SCH_1):PAGE188_I64@PURE_QUANTA.Q_INDUCTOR4P_14(CHIPS)':
 '1': CDS_PINID='\1\';
NET_NAME
'SW_PVDDCR_CPU0_P1_SW5_RC'
 '@T6G_MB_LIB.T6G(SCH_1):SW_PVDDCR_CPU0_P1_SW5_RC':
 C_SIGNAL='@t6g_mb_lib.t6g(sch_1):sw_pvddcr_cpu0_p1_sw5_rc';
NODE_NAME     PR46 1
 '@T6G_MB_LIB.T6G(SCH_1):PAGE188_I32@PURE_QUANTA.Q_RES(CHIPS)':
 'A': CDS_PINID='A';
NODE_NAME     PC318 2
 '@T6G_MB_LIB.T6G(SCH_1):PAGE188_I46@PURE_QUANTA.Q_CAP(CHIPS)':
 'B': CDS_PINID='B';
NET_NAME
'SW_PVDDCR_CPU0_P1_SW6'
 '@T6G_MB_LIB.T6G(SCH_1):SW_PVDDCR_CPU0_P1_SW6':
 C_SIGNAL='@t6g_mb_lib.t6g(sch_1):sw_pvddcr_cpu0_p1_sw6';
NODE_NAME     PC321 1
 '@T6G_MB_LIB.T6G(SCH_1):PAGE188_I23@PURE_QUANTA.Q_CAP(CHIPS)':
 'A': CDS_PINID='A';
NODE_NAME     PL8 1
 '@T6G_MB_LIB.T6G(SCH_1):PAGE188_I53@PURE_QUANTA.Q_INDUCTOR4P_14(CHIPS)':
 '1': CDS_PINID='\1\';
NODE_NAME     PU24 10_19
 '@T6G_MB_LIB.T6G(SCH_1):PAGE188_I73@PURE_QUANTA.ISL99390FRZTR5935(CHIPS)':
 'SW': CDS_PINID='SW';
NET_NAME
'SW_PVDDCR_CPU0_P1_SW6_RC'
 '@T6G_MB_LIB.T6G(SCH_1):SW_PVDDCR_CPU0_P1_SW6_RC':
 C_SIGNAL='@t6g_mb_lib.t6g(sch_1):sw_pvddcr_cpu0_p1_sw6_rc';
NODE_NAME     PR524 1
 '@T6G_MB_LIB.T6G(SCH_1):PAGE188_I21@PURE_QUANTA.Q_RES(CHIPS)':
 'A': CDS_PINID='A';
NODE_NAME     PC321 2
 '@T6G_MB_LIB.T6G(SCH_1):PAGE188_I23@PURE_QUANTA.Q_CAP(CHIPS)':
 'B': CDS_PINID='B';
NET_NAME
'SW_PVDDCR_CPU1_P0_BOOT1'
 '@T6G_MB_LIB.T6G(SCH_1):SW_PVDDCR_CPU1_P0_BOOT1':
 C_SIGNAL='@t6g_mb_lib.t6g(sch_1):sw_pvddcr_cpu1_p0_boot1';
NODE_NAME     PU13 33
 '@T6G_MB_LIB.T6G(SCH_1):PAGE176_I35@PURE_QUANTA.ISL99390FRZTR5935(CHIPS)':
 'BOOT': CDS_PINID='BOOT';
NODE_NAME     PR82 1
 '@T6G_MB_LIB.T6G(SCH_1):PAGE176_I56@PURE_QUANTA.Q_RES(CHIPS)':
 'A': CDS_PINID='A';
NET_NAME
'SW_PVDDCR_CPU1_P0_BOOT1_R'
 '@T6G_MB_LIB.T6G(SCH_1):SW_PVDDCR_CPU1_P0_BOOT1_R':
 C_SIGNAL='@t6g_mb_lib.t6g(sch_1):sw_pvddcr_cpu1_p0_boot1_r';
NODE_NAME     PR82 2
 '@T6G_MB_LIB.T6G(SCH_1):PAGE176_I56@PURE_QUANTA.Q_RES(CHIPS)':
 'B': CDS_PINID='B';
NODE_NAME     PC92 1
 '@T6G_MB_LIB.T6G(SCH_1):PAGE176_I61@PURE_QUANTA.Q_CAP(CHIPS)':
 'A': CDS_PINID='A';
NET_NAME
'SW_PVDDCR_CPU1_P0_BOOT2'
 '@T6G_MB_LIB.T6G(SCH_1):SW_PVDDCR_CPU1_P0_BOOT2':
 C_SIGNAL='@t6g_mb_lib.t6g(sch_1):sw_pvddcr_cpu1_p0_boot2';
NODE_NAME     PU2 33
 '@T6G_MB_LIB.T6G(SCH_1):PAGE176_I33@PURE_QUANTA.ISL99390FRZTR5935(CHIPS)':
 'BOOT': CDS_PINID='BOOT';
NODE_NAME     PR81 1
 '@T6G_MB_LIB.T6G(SCH_1):PAGE176_I40@PURE_QUANTA.Q_RES(CHIPS)':
 'A': CDS_PINID='A';
NET_NAME
'SW_PVDDCR_CPU1_P0_BOOT2_R'
 '@T6G_MB_LIB.T6G(SCH_1):SW_PVDDCR_CPU1_P0_BOOT2_R':
 C_SIGNAL='@t6g_mb_lib.t6g(sch_1):sw_pvddcr_cpu1_p0_boot2_r';
NODE_NAME     PR81 2
 '@T6G_MB_LIB.T6G(SCH_1):PAGE176_I40@PURE_QUANTA.Q_RES(CHIPS)':
 'B': CDS_PINID='B';
NODE_NAME     PC94 1
 '@T6G_MB_LIB.T6G(SCH_1):PAGE176_I44@PURE_QUANTA.Q_CAP(CHIPS)':
 'A': CDS_PINID='A';
NET_NAME
'SW_PVDDCR_CPU1_P0_BOOT3'
 '@T6G_MB_LIB.T6G(SCH_1):SW_PVDDCR_CPU1_P0_BOOT3':
 C_SIGNAL='@t6g_mb_lib.t6g(sch_1):sw_pvddcr_cpu1_p0_boot3';
NODE_NAME     PU15 33
 '@T6G_MB_LIB.T6G(SCH_1):PAGE177_I23@PURE_QUANTA.ISL99390FRZTR5935(CHIPS)':
 'BOOT': CDS_PINID='BOOT';
NODE_NAME     PR90 1
 '@T6G_MB_LIB.T6G(SCH_1):PAGE177_I57@PURE_QUANTA.Q_RES(CHIPS)':
 'A': CDS_PINID='A';
NET_NAME
'SW_PVDDCR_CPU1_P0_BOOT3_R'
 '@T6G_MB_LIB.T6G(SCH_1):SW_PVDDCR_CPU1_P0_BOOT3_R':
 C_SIGNAL='@t6g_mb_lib.t6g(sch_1):sw_pvddcr_cpu1_p0_boot3_r';
NODE_NAME     PR90 2
 '@T6G_MB_LIB.T6G(SCH_1):PAGE177_I57@PURE_QUANTA.Q_RES(CHIPS)':
 'B': CDS_PINID='B';
NODE_NAME     PC122 1
 '@T6G_MB_LIB.T6G(SCH_1):PAGE177_I62@PURE_QUANTA.Q_CAP(CHIPS)':
 'A': CDS_PINID='A';
NET_NAME
'SW_PVDDCR_CPU1_P0_BOOT4'
 '@T6G_MB_LIB.T6G(SCH_1):SW_PVDDCR_CPU1_P0_BOOT4':
 C_SIGNAL='@t6g_mb_lib.t6g(sch_1):sw_pvddcr_cpu1_p0_boot4';
NODE_NAME     PR89 1
 '@T6G_MB_LIB.T6G(SCH_1):PAGE177_I37@PURE_QUANTA.Q_RES(CHIPS)':
 'A': CDS_PINID='A';
NODE_NAME     PU14 33
 '@T6G_MB_LIB.T6G(SCH_1):PAGE177_I21@PURE_QUANTA.ISL99390FRZTR5935(CHIPS)':
 'BOOT': CDS_PINID='BOOT';
NET_NAME
'SW_PVDDCR_CPU1_P0_BOOT4_R'
 '@T6G_MB_LIB.T6G(SCH_1):SW_PVDDCR_CPU1_P0_BOOT4_R':
 C_SIGNAL='@t6g_mb_lib.t6g(sch_1):sw_pvddcr_cpu1_p0_boot4_r';
NODE_NAME     PR89 2
 '@T6G_MB_LIB.T6G(SCH_1):PAGE177_I37@PURE_QUANTA.Q_RES(CHIPS)':
 'B': CDS_PINID='B';
NODE_NAME     PC121 1
 '@T6G_MB_LIB.T6G(SCH_1):PAGE177_I41@PURE_QUANTA.Q_CAP(CHIPS)':
 'A': CDS_PINID='A';
NET_NAME
'SW_PVDDCR_CPU1_P0_BOOT5'
 '@T6G_MB_LIB.T6G(SCH_1):SW_PVDDCR_CPU1_P0_BOOT5':
 C_SIGNAL='@t6g_mb_lib.t6g(sch_1):sw_pvddcr_cpu1_p0_boot5';
NODE_NAME     PU16 33
 '@T6G_MB_LIB.T6G(SCH_1):PAGE178_I22@PURE_QUANTA.ISL99390FRZTR5935(CHIPS)':
 'BOOT': CDS_PINID='BOOT';
NODE_NAME     PR95 1
 '@T6G_MB_LIB.T6G(SCH_1):PAGE178_I56@PURE_QUANTA.Q_RES(CHIPS)':
 'A': CDS_PINID='A';
NET_NAME
'SW_PVDDCR_CPU1_P0_BOOT5_R'
 '@T6G_MB_LIB.T6G(SCH_1):SW_PVDDCR_CPU1_P0_BOOT5_R':
 C_SIGNAL='@t6g_mb_lib.t6g(sch_1):sw_pvddcr_cpu1_p0_boot5_r';
NODE_NAME     PR95 2
 '@T6G_MB_LIB.T6G(SCH_1):PAGE178_I56@PURE_QUANTA.Q_RES(CHIPS)':
 'B': CDS_PINID='B';
NODE_NAME     PC137 1
 '@T6G_MB_LIB.T6G(SCH_1):PAGE178_I62@PURE_QUANTA.Q_CAP(CHIPS)':
 'A': CDS_PINID='A';
NET_NAME
'SW_PVDDCR_CPU1_P0_BOOT6'
 '@T6G_MB_LIB.T6G(SCH_1):SW_PVDDCR_CPU1_P0_BOOT6':
 C_SIGNAL='@t6g_mb_lib.t6g(sch_1):sw_pvddcr_cpu1_p0_boot6';
NODE_NAME     PR420 1
 '@T6G_MB_LIB.T6G(SCH_1):PAGE178_I39@PURE_QUANTA.Q_RES(CHIPS)':
 'A': CDS_PINID='A';
NODE_NAME     PU11 33
 '@T6G_MB_LIB.T6G(SCH_1):PAGE178_I73@PURE_QUANTA.ISL99390FRZTR5935(CHIPS)':
 'BOOT': CDS_PINID='BOOT';
NET_NAME
'SW_PVDDCR_CPU1_P0_BOOT6_R'
 '@T6G_MB_LIB.T6G(SCH_1):SW_PVDDCR_CPU1_P0_BOOT6_R':
 C_SIGNAL='@t6g_mb_lib.t6g(sch_1):sw_pvddcr_cpu1_p0_boot6_r';
NODE_NAME     PR420 2
 '@T6G_MB_LIB.T6G(SCH_1):PAGE178_I39@PURE_QUANTA.Q_RES(CHIPS)':
 'B': CDS_PINID='B';
NODE_NAME     PC117 1
 '@T6G_MB_LIB.T6G(SCH_1):PAGE178_I37@PURE_QUANTA.Q_CAP(CHIPS)':
 'A': CDS_PINID='A';
NET_NAME
'SW_PVDDCR_CPU1_P0_BOOTR1'
 '@T6G_MB_LIB.T6G(SCH_1):SW_PVDDCR_CPU1_P0_BOOTR1':
 C_SIGNAL='@t6g_mb_lib.t6g(sch_1):sw_pvddcr_cpu1_p0_bootr1';
NODE_NAME     PU13 32
 '@T6G_MB_LIB.T6G(SCH_1):PAGE176_I35@PURE_QUANTA.ISL99390FRZTR5935(CHIPS)':
 'PHASE': CDS_PINID='PHASE';
NODE_NAME     PC92 2
 '@T6G_MB_LIB.T6G(SCH_1):PAGE176_I61@PURE_QUANTA.Q_CAP(CHIPS)':
 'B': CDS_PINID='B';
NET_NAME
'SW_PVDDCR_CPU1_P0_BOOTR2'
 '@T6G_MB_LIB.T6G(SCH_1):SW_PVDDCR_CPU1_P0_BOOTR2':
 C_SIGNAL='@t6g_mb_lib.t6g(sch_1):sw_pvddcr_cpu1_p0_bootr2';
NODE_NAME     PU2 32
 '@T6G_MB_LIB.T6G(SCH_1):PAGE176_I33@PURE_QUANTA.ISL99390FRZTR5935(CHIPS)':
 'PHASE': CDS_PINID='PHASE';
NODE_NAME     PC94 2
 '@T6G_MB_LIB.T6G(SCH_1):PAGE176_I44@PURE_QUANTA.Q_CAP(CHIPS)':
 'B': CDS_PINID='B';
NET_NAME
'SW_PVDDCR_CPU1_P0_BOOTR3'
 '@T6G_MB_LIB.T6G(SCH_1):SW_PVDDCR_CPU1_P0_BOOTR3':
 C_SIGNAL='@t6g_mb_lib.t6g(sch_1):sw_pvddcr_cpu1_p0_bootr3';
NODE_NAME     PU15 32
 '@T6G_MB_LIB.T6G(SCH_1):PAGE177_I23@PURE_QUANTA.ISL99390FRZTR5935(CHIPS)':
 'PHASE': CDS_PINID='PHASE';
NODE_NAME     PC122 2
 '@T6G_MB_LIB.T6G(SCH_1):PAGE177_I62@PURE_QUANTA.Q_CAP(CHIPS)':
 'B': CDS_PINID='B';
NET_NAME
'SW_PVDDCR_CPU1_P0_BOOTR4'
 '@T6G_MB_LIB.T6G(SCH_1):SW_PVDDCR_CPU1_P0_BOOTR4':
 C_SIGNAL='@t6g_mb_lib.t6g(sch_1):sw_pvddcr_cpu1_p0_bootr4';
NODE_NAME     PU14 32
 '@T6G_MB_LIB.T6G(SCH_1):PAGE177_I21@PURE_QUANTA.ISL99390FRZTR5935(CHIPS)':
 'PHASE': CDS_PINID='PHASE';
NODE_NAME     PC121 2
 '@T6G_MB_LIB.T6G(SCH_1):PAGE177_I41@PURE_QUANTA.Q_CAP(CHIPS)':
 'B': CDS_PINID='B';
NET_NAME
'SW_PVDDCR_CPU1_P0_BOOTR5'
 '@T6G_MB_LIB.T6G(SCH_1):SW_PVDDCR_CPU1_P0_BOOTR5':
 C_SIGNAL='@t6g_mb_lib.t6g(sch_1):sw_pvddcr_cpu1_p0_bootr5';
NODE_NAME     PU16 32
 '@T6G_MB_LIB.T6G(SCH_1):PAGE178_I22@PURE_QUANTA.ISL99390FRZTR5935(CHIPS)':
 'PHASE': CDS_PINID='PHASE';
NODE_NAME     PC137 2
 '@T6G_MB_LIB.T6G(SCH_1):PAGE178_I62@PURE_QUANTA.Q_CAP(CHIPS)':
 'B': CDS_PINID='B';
NET_NAME
'SW_PVDDCR_CPU1_P0_BOOTR6'
 '@T6G_MB_LIB.T6G(SCH_1):SW_PVDDCR_CPU1_P0_BOOTR6':
 C_SIGNAL='@t6g_mb_lib.t6g(sch_1):sw_pvddcr_cpu1_p0_bootr6';
NODE_NAME     PC117 2
 '@T6G_MB_LIB.T6G(SCH_1):PAGE178_I37@PURE_QUANTA.Q_CAP(CHIPS)':
 'B': CDS_PINID='B';
NODE_NAME     PU11 32
 '@T6G_MB_LIB.T6G(SCH_1):PAGE178_I73@PURE_QUANTA.ISL99390FRZTR5935(CHIPS)':
 'PHASE': CDS_PINID='PHASE';
NET_NAME
'SW_PVDDCR_CPU1_P0_SW1'
 '@T6G_MB_LIB.T6G(SCH_1):SW_PVDDCR_CPU1_P0_SW1':
 C_SIGNAL='@t6g_mb_lib.t6g(sch_1):sw_pvddcr_cpu1_p0_sw1';
NODE_NAME     PU13 10_19
 '@T6G_MB_LIB.T6G(SCH_1):PAGE176_I35@PURE_QUANTA.ISL99390FRZTR5935(CHIPS)':
 'SW': CDS_PINID='SW';
NODE_NAME     PC189 1
 '@T6G_MB_LIB.T6G(SCH_1):PAGE176_I57@PURE_QUANTA.Q_CAP(CHIPS)':
 'A': CDS_PINID='A';
NODE_NAME     PL10 1
 '@T6G_MB_LIB.T6G(SCH_1):PAGE176_I62@PURE_QUANTA.Q_INDUCTOR4P_14(CHIPS)':
 '1': CDS_PINID='\1\';
NET_NAME
'SW_PVDDCR_CPU1_P0_SW1_RC'
 '@T6G_MB_LIB.T6G(SCH_1):SW_PVDDCR_CPU1_P0_SW1_RC':
 C_SIGNAL='@t6g_mb_lib.t6g(sch_1):sw_pvddcr_cpu1_p0_sw1_rc';
NODE_NAME     PR506 1
 '@T6G_MB_LIB.T6G(SCH_1):PAGE176_I50@PURE_QUANTA.Q_RES(CHIPS)':
 'A': CDS_PINID='A';
NODE_NAME     PC189 2
 '@T6G_MB_LIB.T6G(SCH_1):PAGE176_I57@PURE_QUANTA.Q_CAP(CHIPS)':
 'B': CDS_PINID='B';
NET_NAME
'SW_PVDDCR_CPU1_P0_SW2'
 '@T6G_MB_LIB.T6G(SCH_1):SW_PVDDCR_CPU1_P0_SW2':
 C_SIGNAL='@t6g_mb_lib.t6g(sch_1):sw_pvddcr_cpu1_p0_sw2';
NODE_NAME     PC190 1
 '@T6G_MB_LIB.T6G(SCH_1):PAGE176_I41@PURE_QUANTA.Q_CAP(CHIPS)':
 'A': CDS_PINID='A';
NODE_NAME     PL11 1
 '@T6G_MB_LIB.T6G(SCH_1):PAGE176_I46@PURE_QUANTA.Q_INDUCTOR4P_14(CHIPS)':
 '1': CDS_PINID='\1\';
NODE_NAME     PU2 10_19
 '@T6G_MB_LIB.T6G(SCH_1):PAGE176_I33@PURE_QUANTA.ISL99390FRZTR5935(CHIPS)':
 'SW': CDS_PINID='SW';
NET_NAME
'SW_PVDDCR_CPU1_P0_SW2_RC'
 '@T6G_MB_LIB.T6G(SCH_1):SW_PVDDCR_CPU1_P0_SW2_RC':
 C_SIGNAL='@t6g_mb_lib.t6g(sch_1):sw_pvddcr_cpu1_p0_sw2_rc';
NODE_NAME     PC190 2
 '@T6G_MB_LIB.T6G(SCH_1):PAGE176_I41@PURE_QUANTA.Q_CAP(CHIPS)':
 'B': CDS_PINID='B';
NODE_NAME     PR507 1
 '@T6G_MB_LIB.T6G(SCH_1):PAGE176_I39@PURE_QUANTA.Q_RES(CHIPS)':
 'A': CDS_PINID='A';
NET_NAME
'SW_PVDDCR_CPU1_P0_SW3'
 '@T6G_MB_LIB.T6G(SCH_1):SW_PVDDCR_CPU1_P0_SW3':
 C_SIGNAL='@t6g_mb_lib.t6g(sch_1):sw_pvddcr_cpu1_p0_sw3';
NODE_NAME     PU15 10_19
 '@T6G_MB_LIB.T6G(SCH_1):PAGE177_I23@PURE_QUANTA.ISL99390FRZTR5935(CHIPS)':
 'SW': CDS_PINID='SW';
NODE_NAME     PC192 1
 '@T6G_MB_LIB.T6G(SCH_1):PAGE177_I58@PURE_QUANTA.Q_CAP(CHIPS)':
 'A': CDS_PINID='A';
NODE_NAME     PL14 1
 '@T6G_MB_LIB.T6G(SCH_1):PAGE177_I64@PURE_QUANTA.Q_INDUCTOR4P_14(CHIPS)':
 '1': CDS_PINID='\1\';
NET_NAME
'SW_PVDDCR_CPU1_P0_SW3_RC'
 '@T6G_MB_LIB.T6G(SCH_1):SW_PVDDCR_CPU1_P0_SW3_RC':
 C_SIGNAL='@t6g_mb_lib.t6g(sch_1):sw_pvddcr_cpu1_p0_sw3_rc';
NODE_NAME     PR510 1
 '@T6G_MB_LIB.T6G(SCH_1):PAGE177_I46@PURE_QUANTA.Q_RES(CHIPS)':
 'A': CDS_PINID='A';
NODE_NAME     PC192 2
 '@T6G_MB_LIB.T6G(SCH_1):PAGE177_I58@PURE_QUANTA.Q_CAP(CHIPS)':
 'B': CDS_PINID='B';
NET_NAME
'SW_PVDDCR_CPU1_P0_SW4'
 '@T6G_MB_LIB.T6G(SCH_1):SW_PVDDCR_CPU1_P0_SW4':
 C_SIGNAL='@t6g_mb_lib.t6g(sch_1):sw_pvddcr_cpu1_p0_sw4';
NODE_NAME     PC191 1
 '@T6G_MB_LIB.T6G(SCH_1):PAGE177_I38@PURE_QUANTA.Q_CAP(CHIPS)':
 'A': CDS_PINID='A';
NODE_NAME     PL13 1
 '@T6G_MB_LIB.T6G(SCH_1):PAGE177_I42@PURE_QUANTA.Q_INDUCTOR4P_14(CHIPS)':
 '1': CDS_PINID='\1\';
NODE_NAME     PU14 10_19
 '@T6G_MB_LIB.T6G(SCH_1):PAGE177_I21@PURE_QUANTA.ISL99390FRZTR5935(CHIPS)':
 'SW': CDS_PINID='SW';
NET_NAME
'SW_PVDDCR_CPU1_P0_SW4_RC'
 '@T6G_MB_LIB.T6G(SCH_1):SW_PVDDCR_CPU1_P0_SW4_RC':
 C_SIGNAL='@t6g_mb_lib.t6g(sch_1):sw_pvddcr_cpu1_p0_sw4_rc';
NODE_NAME     PC191 2
 '@T6G_MB_LIB.T6G(SCH_1):PAGE177_I38@PURE_QUANTA.Q_CAP(CHIPS)':
 'B': CDS_PINID='B';
NODE_NAME     PR509 1
 '@T6G_MB_LIB.T6G(SCH_1):PAGE177_I36@PURE_QUANTA.Q_RES(CHIPS)':
 'A': CDS_PINID='A';
NET_NAME
'SW_PVDDCR_CPU1_P0_SW5'
 '@T6G_MB_LIB.T6G(SCH_1):SW_PVDDCR_CPU1_P0_SW5':
 C_SIGNAL='@t6g_mb_lib.t6g(sch_1):sw_pvddcr_cpu1_p0_sw5';
NODE_NAME     PU16 10_19
 '@T6G_MB_LIB.T6G(SCH_1):PAGE178_I22@PURE_QUANTA.ISL99390FRZTR5935(CHIPS)':
 'SW': CDS_PINID='SW';
NODE_NAME     PC157 1
 '@T6G_MB_LIB.T6G(SCH_1):PAGE178_I57@PURE_QUANTA.Q_CAP(CHIPS)':
 'A': CDS_PINID='A';
NODE_NAME     PL15 1
 '@T6G_MB_LIB.T6G(SCH_1):PAGE178_I63@PURE_QUANTA.Q_INDUCTOR4P_14(CHIPS)':
 '1': CDS_PINID='\1\';
NET_NAME
'SW_PVDDCR_CPU1_P0_SW5_RC'
 '@T6G_MB_LIB.T6G(SCH_1):SW_PVDDCR_CPU1_P0_SW5_RC':
 C_SIGNAL='@t6g_mb_lib.t6g(sch_1):sw_pvddcr_cpu1_p0_sw5_rc';
NODE_NAME     PR158 1
 '@T6G_MB_LIB.T6G(SCH_1):PAGE178_I44@PURE_QUANTA.Q_RES(CHIPS)':
 'A': CDS_PINID='A';
NODE_NAME     PC157 2
 '@T6G_MB_LIB.T6G(SCH_1):PAGE178_I57@PURE_QUANTA.Q_CAP(CHIPS)':
 'B': CDS_PINID='B';
NET_NAME
'SW_PVDDCR_CPU1_P0_SW6'
 '@T6G_MB_LIB.T6G(SCH_1):SW_PVDDCR_CPU1_P0_SW6':
 C_SIGNAL='@t6g_mb_lib.t6g(sch_1):sw_pvddcr_cpu1_p0_sw6';
NODE_NAME     PL7 1
 '@T6G_MB_LIB.T6G(SCH_1):PAGE178_I38@PURE_QUANTA.Q_INDUCTOR4P_14(CHIPS)':
 '1': CDS_PINID='\1\';
NODE_NAME     PC154 1
 '@T6G_MB_LIB.T6G(SCH_1):PAGE178_I72@PURE_QUANTA.Q_CAP(CHIPS)':
 'A': CDS_PINID='A';
NODE_NAME     PU11 10_19
 '@T6G_MB_LIB.T6G(SCH_1):PAGE178_I73@PURE_QUANTA.ISL99390FRZTR5935(CHIPS)':
 'SW': CDS_PINID='SW';
NET_NAME
'SW_PVDDCR_CPU1_P0_SW6_RC'
 '@T6G_MB_LIB.T6G(SCH_1):SW_PVDDCR_CPU1_P0_SW6_RC':
 C_SIGNAL='@t6g_mb_lib.t6g(sch_1):sw_pvddcr_cpu1_p0_sw6_rc';
NODE_NAME     PR155 1
 '@T6G_MB_LIB.T6G(SCH_1):PAGE178_I33@PURE_QUANTA.Q_RES(CHIPS)':
 'A': CDS_PINID='A';
NODE_NAME     PC154 2
 '@T6G_MB_LIB.T6G(SCH_1):PAGE178_I72@PURE_QUANTA.Q_CAP(CHIPS)':
 'B': CDS_PINID='B';
NET_NAME
'SW_PVDDCR_CPU1_P1_BOOT1'
 '@T6G_MB_LIB.T6G(SCH_1):SW_PVDDCR_CPU1_P1_BOOT1':
 C_SIGNAL='@t6g_mb_lib.t6g(sch_1):sw_pvddcr_cpu1_p1_boot1';
NODE_NAME     PR258 1
 '@T6G_MB_LIB.T6G(SCH_1):PAGE193_I51@PURE_QUANTA.Q_RES(CHIPS)':
 'A': CDS_PINID='A';
NODE_NAME     PU35 33
 '@T6G_MB_LIB.T6G(SCH_1):PAGE193_I91@PURE_QUANTA.ISL99390FRZTR5935(CHIPS)':
 'BOOT': CDS_PINID='BOOT';
NET_NAME
'SW_PVDDCR_CPU1_P1_BOOT1_R'
 '@T6G_MB_LIB.T6G(SCH_1):SW_PVDDCR_CPU1_P1_BOOT1_R':
 C_SIGNAL='@t6g_mb_lib.t6g(sch_1):sw_pvddcr_cpu1_p1_boot1_r';
NODE_NAME     PR258 2
 '@T6G_MB_LIB.T6G(SCH_1):PAGE193_I51@PURE_QUANTA.Q_RES(CHIPS)':
 'B': CDS_PINID='B';
NODE_NAME     PC383 1
 '@T6G_MB_LIB.T6G(SCH_1):PAGE193_I57@PURE_QUANTA.Q_CAP(CHIPS)':
 'A': CDS_PINID='A';
NET_NAME
'SW_PVDDCR_CPU1_P1_BOOT2'
 '@T6G_MB_LIB.T6G(SCH_1):SW_PVDDCR_CPU1_P1_BOOT2':
 C_SIGNAL='@t6g_mb_lib.t6g(sch_1):sw_pvddcr_cpu1_p1_boot2';
NODE_NAME     PR259 1
 '@T6G_MB_LIB.T6G(SCH_1):PAGE193_I41@PURE_QUANTA.Q_RES(CHIPS)':
 'A': CDS_PINID='A';
NODE_NAME     PU5 33
 '@T6G_MB_LIB.T6G(SCH_1):PAGE193_I31@PURE_QUANTA.ISL99390FRZTR5935(CHIPS)':
 'BOOT': CDS_PINID='BOOT';
NET_NAME
'SW_PVDDCR_CPU1_P1_BOOT2_R'
 '@T6G_MB_LIB.T6G(SCH_1):SW_PVDDCR_CPU1_P1_BOOT2_R':
 C_SIGNAL='@t6g_mb_lib.t6g(sch_1):sw_pvddcr_cpu1_p1_boot2_r';
NODE_NAME     PR259 2
 '@T6G_MB_LIB.T6G(SCH_1):PAGE193_I41@PURE_QUANTA.Q_RES(CHIPS)':
 'B': CDS_PINID='B';
NODE_NAME     PC386 1
 '@T6G_MB_LIB.T6G(SCH_1):PAGE193_I40@PURE_QUANTA.Q_CAP(CHIPS)':
 'A': CDS_PINID='A';
NET_NAME
'SW_PVDDCR_CPU1_P1_BOOT3'
 '@T6G_MB_LIB.T6G(SCH_1):SW_PVDDCR_CPU1_P1_BOOT3':
 C_SIGNAL='@t6g_mb_lib.t6g(sch_1):sw_pvddcr_cpu1_p1_boot3';
NODE_NAME     PR267 1
 '@T6G_MB_LIB.T6G(SCH_1):PAGE194_I52@PURE_QUANTA.Q_RES(CHIPS)':
 'A': CDS_PINID='A';
NODE_NAME     PU37 33
 '@T6G_MB_LIB.T6G(SCH_1):PAGE194_I72@PURE_QUANTA.ISL99390FRZTR5935(CHIPS)':
 'BOOT': CDS_PINID='BOOT';
NET_NAME
'SW_PVDDCR_CPU1_P1_BOOT3_R'
 '@T6G_MB_LIB.T6G(SCH_1):SW_PVDDCR_CPU1_P1_BOOT3_R':
 C_SIGNAL='@t6g_mb_lib.t6g(sch_1):sw_pvddcr_cpu1_p1_boot3_r';
NODE_NAME     PR267 2
 '@T6G_MB_LIB.T6G(SCH_1):PAGE194_I52@PURE_QUANTA.Q_RES(CHIPS)':
 'B': CDS_PINID='B';
NODE_NAME     PC414 1
 '@T6G_MB_LIB.T6G(SCH_1):PAGE194_I57@PURE_QUANTA.Q_CAP(CHIPS)':
 'A': CDS_PINID='A';
NET_NAME
'SW_PVDDCR_CPU1_P1_BOOT4'
 '@T6G_MB_LIB.T6G(SCH_1):SW_PVDDCR_CPU1_P1_BOOT4':
 C_SIGNAL='@t6g_mb_lib.t6g(sch_1):sw_pvddcr_cpu1_p1_boot4';
NODE_NAME     PU36 33
 '@T6G_MB_LIB.T6G(SCH_1):PAGE194_I21@PURE_QUANTA.ISL99390FRZTR5935(CHIPS)':
 'BOOT': CDS_PINID='BOOT';
NODE_NAME     PR266 1
 '@T6G_MB_LIB.T6G(SCH_1):PAGE194_I36@PURE_QUANTA.Q_RES(CHIPS)':
 'A': CDS_PINID='A';
NET_NAME
'SW_PVDDCR_CPU1_P1_BOOT4_R'
 '@T6G_MB_LIB.T6G(SCH_1):SW_PVDDCR_CPU1_P1_BOOT4_R':
 C_SIGNAL='@t6g_mb_lib.t6g(sch_1):sw_pvddcr_cpu1_p1_boot4_r';
NODE_NAME     PC413 1
 '@T6G_MB_LIB.T6G(SCH_1):PAGE194_I40@PURE_QUANTA.Q_CAP(CHIPS)':
 'A': CDS_PINID='A';
NODE_NAME     PR266 2
 '@T6G_MB_LIB.T6G(SCH_1):PAGE194_I36@PURE_QUANTA.Q_RES(CHIPS)':
 'B': CDS_PINID='B';
NET_NAME
'SW_PVDDCR_CPU1_P1_BOOT5'
 '@T6G_MB_LIB.T6G(SCH_1):SW_PVDDCR_CPU1_P1_BOOT5':
 C_SIGNAL='@t6g_mb_lib.t6g(sch_1):sw_pvddcr_cpu1_p1_boot5';
NODE_NAME     PR272 1
 '@T6G_MB_LIB.T6G(SCH_1):PAGE195_I52@PURE_QUANTA.Q_RES(CHIPS)':
 'A': CDS_PINID='A';
NODE_NAME     PU38 33
 '@T6G_MB_LIB.T6G(SCH_1):PAGE195_I73@PURE_QUANTA.ISL99390FRZTR5935(CHIPS)':
 'BOOT': CDS_PINID='BOOT';
NET_NAME
'SW_PVDDCR_CPU1_P1_BOOT5_R'
 '@T6G_MB_LIB.T6G(SCH_1):SW_PVDDCR_CPU1_P1_BOOT5_R':
 C_SIGNAL='@t6g_mb_lib.t6g(sch_1):sw_pvddcr_cpu1_p1_boot5_r';
NODE_NAME     PR272 2
 '@T6G_MB_LIB.T6G(SCH_1):PAGE195_I52@PURE_QUANTA.Q_RES(CHIPS)':
 'B': CDS_PINID='B';
NODE_NAME     PC428 1
 '@T6G_MB_LIB.T6G(SCH_1):PAGE195_I57@PURE_QUANTA.Q_CAP(CHIPS)':
 'A': CDS_PINID='A';
NET_NAME
'SW_PVDDCR_CPU1_P1_BOOT6'
 '@T6G_MB_LIB.T6G(SCH_1):SW_PVDDCR_CPU1_P1_BOOT6':
 C_SIGNAL='@t6g_mb_lib.t6g(sch_1):sw_pvddcr_cpu1_p1_boot6';
NODE_NAME     PR428 1
 '@T6G_MB_LIB.T6G(SCH_1):PAGE195_I39@PURE_QUANTA.Q_RES(CHIPS)':
 'A': CDS_PINID='A';
NODE_NAME     PU33 33
 '@T6G_MB_LIB.T6G(SCH_1):PAGE195_I19@PURE_QUANTA.ISL99390FRZTR5935(CHIPS)':
 'BOOT': CDS_PINID='BOOT';
NET_NAME
'SW_PVDDCR_CPU1_P1_BOOT6_R'
 '@T6G_MB_LIB.T6G(SCH_1):SW_PVDDCR_CPU1_P1_BOOT6_R':
 C_SIGNAL='@t6g_mb_lib.t6g(sch_1):sw_pvddcr_cpu1_p1_boot6_r';
NODE_NAME     PR428 2
 '@T6G_MB_LIB.T6G(SCH_1):PAGE195_I39@PURE_QUANTA.Q_RES(CHIPS)':
 'B': CDS_PINID='B';
NODE_NAME     PC146 1
 '@T6G_MB_LIB.T6G(SCH_1):PAGE195_I45@PURE_QUANTA.Q_CAP(CHIPS)':
 'A': CDS_PINID='A';
NET_NAME
'SW_PVDDCR_CPU1_P1_BOOTR1'
 '@T6G_MB_LIB.T6G(SCH_1):SW_PVDDCR_CPU1_P1_BOOTR1':
 C_SIGNAL='@t6g_mb_lib.t6g(sch_1):sw_pvddcr_cpu1_p1_bootr1';
NODE_NAME     PC383 2
 '@T6G_MB_LIB.T6G(SCH_1):PAGE193_I57@PURE_QUANTA.Q_CAP(CHIPS)':
 'B': CDS_PINID='B';
NODE_NAME     PU35 32
 '@T6G_MB_LIB.T6G(SCH_1):PAGE193_I91@PURE_QUANTA.ISL99390FRZTR5935(CHIPS)':
 'PHASE': CDS_PINID='PHASE';
NET_NAME
'SW_PVDDCR_CPU1_P1_BOOTR2'
 '@T6G_MB_LIB.T6G(SCH_1):SW_PVDDCR_CPU1_P1_BOOTR2':
 C_SIGNAL='@t6g_mb_lib.t6g(sch_1):sw_pvddcr_cpu1_p1_bootr2';
NODE_NAME     PU5 32
 '@T6G_MB_LIB.T6G(SCH_1):PAGE193_I31@PURE_QUANTA.ISL99390FRZTR5935(CHIPS)':
 'PHASE': CDS_PINID='PHASE';
NODE_NAME     PC386 2
 '@T6G_MB_LIB.T6G(SCH_1):PAGE193_I40@PURE_QUANTA.Q_CAP(CHIPS)':
 'B': CDS_PINID='B';
NET_NAME
'SW_PVDDCR_CPU1_P1_BOOTR3'
 '@T6G_MB_LIB.T6G(SCH_1):SW_PVDDCR_CPU1_P1_BOOTR3':
 C_SIGNAL='@t6g_mb_lib.t6g(sch_1):sw_pvddcr_cpu1_p1_bootr3';
NODE_NAME     PC414 2
 '@T6G_MB_LIB.T6G(SCH_1):PAGE194_I57@PURE_QUANTA.Q_CAP(CHIPS)':
 'B': CDS_PINID='B';
NODE_NAME     PU37 32
 '@T6G_MB_LIB.T6G(SCH_1):PAGE194_I72@PURE_QUANTA.ISL99390FRZTR5935(CHIPS)':
 'PHASE': CDS_PINID='PHASE';
NET_NAME
'SW_PVDDCR_CPU1_P1_BOOTR4'
 '@T6G_MB_LIB.T6G(SCH_1):SW_PVDDCR_CPU1_P1_BOOTR4':
 C_SIGNAL='@t6g_mb_lib.t6g(sch_1):sw_pvddcr_cpu1_p1_bootr4';
NODE_NAME     PC413 2
 '@T6G_MB_LIB.T6G(SCH_1):PAGE194_I40@PURE_QUANTA.Q_CAP(CHIPS)':
 'B': CDS_PINID='B';
NODE_NAME     PU36 32
 '@T6G_MB_LIB.T6G(SCH_1):PAGE194_I21@PURE_QUANTA.ISL99390FRZTR5935(CHIPS)':
 'PHASE': CDS_PINID='PHASE';
NET_NAME
'SW_PVDDCR_CPU1_P1_BOOTR5'
 '@T6G_MB_LIB.T6G(SCH_1):SW_PVDDCR_CPU1_P1_BOOTR5':
 C_SIGNAL='@t6g_mb_lib.t6g(sch_1):sw_pvddcr_cpu1_p1_bootr5';
NODE_NAME     PC428 2
 '@T6G_MB_LIB.T6G(SCH_1):PAGE195_I57@PURE_QUANTA.Q_CAP(CHIPS)':
 'B': CDS_PINID='B';
NODE_NAME     PU38 32
 '@T6G_MB_LIB.T6G(SCH_1):PAGE195_I73@PURE_QUANTA.ISL99390FRZTR5935(CHIPS)':
 'PHASE': CDS_PINID='PHASE';
NET_NAME
'SW_PVDDCR_CPU1_P1_BOOTR6'
 '@T6G_MB_LIB.T6G(SCH_1):SW_PVDDCR_CPU1_P1_BOOTR6':
 C_SIGNAL='@t6g_mb_lib.t6g(sch_1):sw_pvddcr_cpu1_p1_bootr6';
NODE_NAME     PU33 32
 '@T6G_MB_LIB.T6G(SCH_1):PAGE195_I19@PURE_QUANTA.ISL99390FRZTR5935(CHIPS)':
 'PHASE': CDS_PINID='PHASE';
NODE_NAME     PC146 2
 '@T6G_MB_LIB.T6G(SCH_1):PAGE195_I45@PURE_QUANTA.Q_CAP(CHIPS)':
 'B': CDS_PINID='B';
NET_NAME
'SW_PVDDCR_CPU1_P1_SW1'
 '@T6G_MB_LIB.T6G(SCH_1):SW_PVDDCR_CPU1_P1_SW1':
 C_SIGNAL='@t6g_mb_lib.t6g(sch_1):sw_pvddcr_cpu1_p1_sw1';
NODE_NAME     PC201 1
 '@T6G_MB_LIB.T6G(SCH_1):PAGE193_I52@PURE_QUANTA.Q_CAP(CHIPS)':
 'A': CDS_PINID='A';
NODE_NAME     PL40 1
 '@T6G_MB_LIB.T6G(SCH_1):PAGE193_I77@PURE_QUANTA.Q_INDUCTOR4P_14(CHIPS)':
 '1': CDS_PINID='\1\';
NODE_NAME     PU35 10_19
 '@T6G_MB_LIB.T6G(SCH_1):PAGE193_I91@PURE_QUANTA.ISL99390FRZTR5935(CHIPS)':
 'SW': CDS_PINID='SW';
NET_NAME
'SW_PVDDCR_CPU1_P1_SW1_RC'
 '@T6G_MB_LIB.T6G(SCH_1):SW_PVDDCR_CPU1_P1_SW1_RC':
 C_SIGNAL='@t6g_mb_lib.t6g(sch_1):sw_pvddcr_cpu1_p1_sw1_rc';
NODE_NAME     PR512 1
 '@T6G_MB_LIB.T6G(SCH_1):PAGE193_I45@PURE_QUANTA.Q_RES(CHIPS)':
 'A': CDS_PINID='A';
NODE_NAME     PC201 2
 '@T6G_MB_LIB.T6G(SCH_1):PAGE193_I52@PURE_QUANTA.Q_CAP(CHIPS)':
 'B': CDS_PINID='B';
NET_NAME
'SW_PVDDCR_CPU1_P1_SW2'
 '@T6G_MB_LIB.T6G(SCH_1):SW_PVDDCR_CPU1_P1_SW2':
 C_SIGNAL='@t6g_mb_lib.t6g(sch_1):sw_pvddcr_cpu1_p1_sw2';
NODE_NAME     PU5 10_19
 '@T6G_MB_LIB.T6G(SCH_1):PAGE193_I31@PURE_QUANTA.ISL99390FRZTR5935(CHIPS)':
 'SW': CDS_PINID='SW';
NODE_NAME     PC202 1
 '@T6G_MB_LIB.T6G(SCH_1):PAGE193_I37@PURE_QUANTA.Q_CAP(CHIPS)':
 'A': CDS_PINID='A';
NODE_NAME     PL41 1
 '@T6G_MB_LIB.T6G(SCH_1):PAGE193_I62@PURE_QUANTA.Q_INDUCTOR4P_14(CHIPS)':
 '1': CDS_PINID='\1\';
NET_NAME
'SW_PVDDCR_CPU1_P1_SW2_RC'
 '@T6G_MB_LIB.T6G(SCH_1):SW_PVDDCR_CPU1_P1_SW2_RC':
 C_SIGNAL='@t6g_mb_lib.t6g(sch_1):sw_pvddcr_cpu1_p1_sw2_rc';
NODE_NAME     PR513 1
 '@T6G_MB_LIB.T6G(SCH_1):PAGE193_I36@PURE_QUANTA.Q_RES(CHIPS)':
 'A': CDS_PINID='A';
NODE_NAME     PC202 2
 '@T6G_MB_LIB.T6G(SCH_1):PAGE193_I37@PURE_QUANTA.Q_CAP(CHIPS)':
 'B': CDS_PINID='B';
NET_NAME
'SW_PVDDCR_CPU1_P1_SW3'
 '@T6G_MB_LIB.T6G(SCH_1):SW_PVDDCR_CPU1_P1_SW3':
 C_SIGNAL='@t6g_mb_lib.t6g(sch_1):sw_pvddcr_cpu1_p1_sw3';
NODE_NAME     PC206 1
 '@T6G_MB_LIB.T6G(SCH_1):PAGE194_I53@PURE_QUANTA.Q_CAP(CHIPS)':
 'A': CDS_PINID='A';
NODE_NAME     PL44 1
 '@T6G_MB_LIB.T6G(SCH_1):PAGE194_I62@PURE_QUANTA.Q_INDUCTOR4P_14(CHIPS)':
 '1': CDS_PINID='\1\';
NODE_NAME     PU37 10_19
 '@T6G_MB_LIB.T6G(SCH_1):PAGE194_I72@PURE_QUANTA.ISL99390FRZTR5935(CHIPS)':
 'SW': CDS_PINID='SW';
NET_NAME
'SW_PVDDCR_CPU1_P1_SW3_RC'
 '@T6G_MB_LIB.T6G(SCH_1):SW_PVDDCR_CPU1_P1_SW3_RC':
 C_SIGNAL='@t6g_mb_lib.t6g(sch_1):sw_pvddcr_cpu1_p1_sw3_rc';
NODE_NAME     PR516 1
 '@T6G_MB_LIB.T6G(SCH_1):PAGE194_I44@PURE_QUANTA.Q_RES(CHIPS)':
 'A': CDS_PINID='A';
NODE_NAME     PC206 2
 '@T6G_MB_LIB.T6G(SCH_1):PAGE194_I53@PURE_QUANTA.Q_CAP(CHIPS)':
 'B': CDS_PINID='B';
NET_NAME
'SW_PVDDCR_CPU1_P1_SW4'
 '@T6G_MB_LIB.T6G(SCH_1):SW_PVDDCR_CPU1_P1_SW4':
 C_SIGNAL='@t6g_mb_lib.t6g(sch_1):sw_pvddcr_cpu1_p1_sw4';
NODE_NAME     PC205 1
 '@T6G_MB_LIB.T6G(SCH_1):PAGE194_I37@PURE_QUANTA.Q_CAP(CHIPS)':
 'A': CDS_PINID='A';
NODE_NAME     PL43 1
 '@T6G_MB_LIB.T6G(SCH_1):PAGE194_I50@PURE_QUANTA.Q_INDUCTOR4P_14(CHIPS)':
 '1': CDS_PINID='\1\';
NODE_NAME     PU36 10_19
 '@T6G_MB_LIB.T6G(SCH_1):PAGE194_I21@PURE_QUANTA.ISL99390FRZTR5935(CHIPS)':
 'SW': CDS_PINID='SW';
NET_NAME
'SW_PVDDCR_CPU1_P1_SW4_RC'
 '@T6G_MB_LIB.T6G(SCH_1):SW_PVDDCR_CPU1_P1_SW4_RC':
 C_SIGNAL='@t6g_mb_lib.t6g(sch_1):sw_pvddcr_cpu1_p1_sw4_rc';
NODE_NAME     PC205 2
 '@T6G_MB_LIB.T6G(SCH_1):PAGE194_I37@PURE_QUANTA.Q_CAP(CHIPS)':
 'B': CDS_PINID='B';
NODE_NAME     PR515 1
 '@T6G_MB_LIB.T6G(SCH_1):PAGE194_I35@PURE_QUANTA.Q_RES(CHIPS)':
 'A': CDS_PINID='A';
NET_NAME
'SW_PVDDCR_CPU1_P1_SW5'
 '@T6G_MB_LIB.T6G(SCH_1):SW_PVDDCR_CPU1_P1_SW5':
 C_SIGNAL='@t6g_mb_lib.t6g(sch_1):sw_pvddcr_cpu1_p1_sw5';
NODE_NAME     PC207 1
 '@T6G_MB_LIB.T6G(SCH_1):PAGE195_I53@PURE_QUANTA.Q_CAP(CHIPS)':
 'A': CDS_PINID='A';
NODE_NAME     PL45 1
 '@T6G_MB_LIB.T6G(SCH_1):PAGE195_I63@PURE_QUANTA.Q_INDUCTOR4P_14(CHIPS)':
 '1': CDS_PINID='\1\';
NODE_NAME     PU38 10_19
 '@T6G_MB_LIB.T6G(SCH_1):PAGE195_I73@PURE_QUANTA.ISL99390FRZTR5935(CHIPS)':
 'SW': CDS_PINID='SW';
NET_NAME
'SW_PVDDCR_CPU1_P1_SW5_RC'
 '@T6G_MB_LIB.T6G(SCH_1):SW_PVDDCR_CPU1_P1_SW5_RC':
 C_SIGNAL='@t6g_mb_lib.t6g(sch_1):sw_pvddcr_cpu1_p1_sw5_rc';
NODE_NAME     PR517 1
 '@T6G_MB_LIB.T6G(SCH_1):PAGE195_I43@PURE_QUANTA.Q_RES(CHIPS)':
 'A': CDS_PINID='A';
NODE_NAME     PC207 2
 '@T6G_MB_LIB.T6G(SCH_1):PAGE195_I53@PURE_QUANTA.Q_CAP(CHIPS)':
 'B': CDS_PINID='B';
NET_NAME
'SW_PVDDCR_CPU1_P1_SW6'
 '@T6G_MB_LIB.T6G(SCH_1):SW_PVDDCR_CPU1_P1_SW6':
 C_SIGNAL='@t6g_mb_lib.t6g(sch_1):sw_pvddcr_cpu1_p1_sw6';
NODE_NAME     PU33 10_19
 '@T6G_MB_LIB.T6G(SCH_1):PAGE195_I19@PURE_QUANTA.ISL99390FRZTR5935(CHIPS)':
 'SW': CDS_PINID='SW';
NODE_NAME     PC208 1
 '@T6G_MB_LIB.T6G(SCH_1):PAGE195_I34@PURE_QUANTA.Q_CAP(CHIPS)':
 'A': CDS_PINID='A';
NODE_NAME     PL69 1
 '@T6G_MB_LIB.T6G(SCH_1):PAGE195_I50@PURE_QUANTA.Q_INDUCTOR4P_14(CHIPS)':
 '1': CDS_PINID='\1\';
NET_NAME
'SW_PVDDCR_CPU1_P1_SW6_RC'
 '@T6G_MB_LIB.T6G(SCH_1):SW_PVDDCR_CPU1_P1_SW6_RC':
 C_SIGNAL='@t6g_mb_lib.t6g(sch_1):sw_pvddcr_cpu1_p1_sw6_rc';
NODE_NAME     PR518 1
 '@T6G_MB_LIB.T6G(SCH_1):PAGE195_I33@PURE_QUANTA.Q_RES(CHIPS)':
 'A': CDS_PINID='A';
NODE_NAME     PC208 2
 '@T6G_MB_LIB.T6G(SCH_1):PAGE195_I34@PURE_QUANTA.Q_CAP(CHIPS)':
 'B': CDS_PINID='B';
NET_NAME
'SW_PVDDCR_SOC_P0_BOOT1'
 '@T6G_MB_LIB.T6G(SCH_1):SW_PVDDCR_SOC_P0_BOOT1':
 C_SIGNAL='@t6g_mb_lib.t6g(sch_1):sw_pvddcr_soc_p0_boot1';
NODE_NAME     PR360 1
 '@T6G_MB_LIB.T6G(SCH_1):PAGE173_I48@PURE_QUANTA.Q_RES(CHIPS)':
 'A': CDS_PINID='A';
NODE_NAME     PU49 33
 '@T6G_MB_LIB.T6G(SCH_1):PAGE173_I41@PURE_QUANTA.ISL99390FRZTR5935(CHIPS)':
 'BOOT': CDS_PINID='BOOT';
NET_NAME
'SW_PVDDCR_SOC_P0_BOOT1_RC'
 '@T6G_MB_LIB.T6G(SCH_1):SW_PVDDCR_SOC_P0_BOOT1_RC':
 C_SIGNAL='@t6g_mb_lib.t6g(sch_1):sw_pvddcr_soc_p0_boot1_rc';
NODE_NAME     PR360 2
 '@T6G_MB_LIB.T6G(SCH_1):PAGE173_I48@PURE_QUANTA.Q_RES(CHIPS)':
 'B': CDS_PINID='B';
NODE_NAME     PC593 1
 '@T6G_MB_LIB.T6G(SCH_1):PAGE173_I68@PURE_QUANTA.Q_CAP(CHIPS)':
 'A': CDS_PINID='A';
NET_NAME
'SW_PVDDCR_SOC_P0_BOOT2'
 '@T6G_MB_LIB.T6G(SCH_1):SW_PVDDCR_SOC_P0_BOOT2':
 C_SIGNAL='@t6g_mb_lib.t6g(sch_1):sw_pvddcr_soc_p0_boot2';
NODE_NAME     PR361 1
 '@T6G_MB_LIB.T6G(SCH_1):PAGE173_I22@PURE_QUANTA.Q_RES(CHIPS)':
 'A': CDS_PINID='A';
NODE_NAME     PU50 33
 '@T6G_MB_LIB.T6G(SCH_1):PAGE173_I86@PURE_QUANTA.ISL99390FRZTR5935(CHIPS)':
 'BOOT': CDS_PINID='BOOT';
NET_NAME
'SW_PVDDCR_SOC_P0_BOOT2_RC'
 '@T6G_MB_LIB.T6G(SCH_1):SW_PVDDCR_SOC_P0_BOOT2_RC':
 C_SIGNAL='@t6g_mb_lib.t6g(sch_1):sw_pvddcr_soc_p0_boot2_rc';
NODE_NAME     PR361 2
 '@T6G_MB_LIB.T6G(SCH_1):PAGE173_I22@PURE_QUANTA.Q_RES(CHIPS)':
 'B': CDS_PINID='B';
NODE_NAME     PC594 1
 '@T6G_MB_LIB.T6G(SCH_1):PAGE173_I52@PURE_QUANTA.Q_CAP(CHIPS)':
 'A': CDS_PINID='A';
NET_NAME
'SW_PVDDCR_SOC_P0_BOOT3'
 '@T6G_MB_LIB.T6G(SCH_1):SW_PVDDCR_SOC_P0_BOOT3':
 C_SIGNAL='@t6g_mb_lib.t6g(sch_1):sw_pvddcr_soc_p0_boot3';
NODE_NAME     PR366 1
 '@T6G_MB_LIB.T6G(SCH_1):PAGE174_I20@PURE_QUANTA.Q_RES(CHIPS)':
 'A': CDS_PINID='A';
NODE_NAME     PU51 33
 '@T6G_MB_LIB.T6G(SCH_1):PAGE174_I38@PURE_QUANTA.ISL99390FRZTR5935(CHIPS)':
 'BOOT': CDS_PINID='BOOT';
NET_NAME
'SW_PVDDCR_SOC_P0_BOOT3_RC'
 '@T6G_MB_LIB.T6G(SCH_1):SW_PVDDCR_SOC_P0_BOOT3_RC':
 C_SIGNAL='@t6g_mb_lib.t6g(sch_1):sw_pvddcr_soc_p0_boot3_rc';
NODE_NAME     PR366 2
 '@T6G_MB_LIB.T6G(SCH_1):PAGE174_I20@PURE_QUANTA.Q_RES(CHIPS)':
 'B': CDS_PINID='B';
NODE_NAME     PC612 1
 '@T6G_MB_LIB.T6G(SCH_1):PAGE174_I30@PURE_QUANTA.Q_CAP(CHIPS)':
 'A': CDS_PINID='A';
NET_NAME
'SW_PVDDCR_SOC_P0_PH1'
 '@T6G_MB_LIB.T6G(SCH_1):SW_PVDDCR_SOC_P0_PH1':
 C_SIGNAL='@t6g_mb_lib.t6g(sch_1):sw_pvddcr_soc_p0_ph1';
NODE_NAME     PC593 2
 '@T6G_MB_LIB.T6G(SCH_1):PAGE173_I68@PURE_QUANTA.Q_CAP(CHIPS)':
 'B': CDS_PINID='B';
NODE_NAME     PU49 32
 '@T6G_MB_LIB.T6G(SCH_1):PAGE173_I41@PURE_QUANTA.ISL99390FRZTR5935(CHIPS)':
 'PHASE': CDS_PINID='PHASE';
NET_NAME
'SW_PVDDCR_SOC_P0_PH2'
 '@T6G_MB_LIB.T6G(SCH_1):SW_PVDDCR_SOC_P0_PH2':
 C_SIGNAL='@t6g_mb_lib.t6g(sch_1):sw_pvddcr_soc_p0_ph2';
NODE_NAME     PC594 2
 '@T6G_MB_LIB.T6G(SCH_1):PAGE173_I52@PURE_QUANTA.Q_CAP(CHIPS)':
 'B': CDS_PINID='B';
NODE_NAME     PU50 32
 '@T6G_MB_LIB.T6G(SCH_1):PAGE173_I86@PURE_QUANTA.ISL99390FRZTR5935(CHIPS)':
 'PHASE': CDS_PINID='PHASE';
NET_NAME
'SW_PVDDCR_SOC_P0_PH3'
 '@T6G_MB_LIB.T6G(SCH_1):SW_PVDDCR_SOC_P0_PH3':
 C_SIGNAL='@t6g_mb_lib.t6g(sch_1):sw_pvddcr_soc_p0_ph3';
NODE_NAME     PU51 32
 '@T6G_MB_LIB.T6G(SCH_1):PAGE174_I38@PURE_QUANTA.ISL99390FRZTR5935(CHIPS)':
 'PHASE': CDS_PINID='PHASE';
NODE_NAME     PC612 2
 '@T6G_MB_LIB.T6G(SCH_1):PAGE174_I30@PURE_QUANTA.Q_CAP(CHIPS)':
 'B': CDS_PINID='B';
NET_NAME
'SW_PVDDCR_SOC_P0_SW1'
 '@T6G_MB_LIB.T6G(SCH_1):SW_PVDDCR_SOC_P0_SW1':
 C_SIGNAL='@t6g_mb_lib.t6g(sch_1):sw_pvddcr_soc_p0_sw1';
NODE_NAME     PL63 1
 '@T6G_MB_LIB.T6G(SCH_1):PAGE173_I69@PURE_QUANTA.Q_INDUCTOR4P_14(CHIPS)':
 '1': CDS_PINID='\1\';
NODE_NAME     PU49 10_19
 '@T6G_MB_LIB.T6G(SCH_1):PAGE173_I41@PURE_QUANTA.ISL99390FRZTR5935(CHIPS)':
 'SW': CDS_PINID='SW';
NODE_NAME     PC185 1
 '@T6G_MB_LIB.T6G(SCH_1):PAGE173_I46@PURE_QUANTA.Q_CAP(CHIPS)':
 'A': CDS_PINID='A';
NET_NAME
'SW_PVDDCR_SOC_P0_SW1_RC'
 '@T6G_MB_LIB.T6G(SCH_1):SW_PVDDCR_SOC_P0_SW1_RC':
 C_SIGNAL='@t6g_mb_lib.t6g(sch_1):sw_pvddcr_soc_p0_sw1_rc';
NODE_NAME     PR502 1
 '@T6G_MB_LIB.T6G(SCH_1):PAGE173_I45@PURE_QUANTA.Q_RES(CHIPS)':
 'A': CDS_PINID='A';
NODE_NAME     PC185 2
 '@T6G_MB_LIB.T6G(SCH_1):PAGE173_I46@PURE_QUANTA.Q_CAP(CHIPS)':
 'B': CDS_PINID='B';
NET_NAME
'SW_PVDDCR_SOC_P0_SW2'
 '@T6G_MB_LIB.T6G(SCH_1):SW_PVDDCR_SOC_P0_SW2':
 C_SIGNAL='@t6g_mb_lib.t6g(sch_1):sw_pvddcr_soc_p0_sw2';
NODE_NAME     PL64 1
 '@T6G_MB_LIB.T6G(SCH_1):PAGE173_I53@PURE_QUANTA.Q_INDUCTOR4P_14(CHIPS)':
 '1': CDS_PINID='\1\';
NODE_NAME     PC187 1
 '@T6G_MB_LIB.T6G(SCH_1):PAGE173_I85@PURE_QUANTA.Q_CAP(CHIPS)':
 'A': CDS_PINID='A';
NODE_NAME     PU50 10_19
 '@T6G_MB_LIB.T6G(SCH_1):PAGE173_I86@PURE_QUANTA.ISL99390FRZTR5935(CHIPS)':
 'SW': CDS_PINID='SW';
NET_NAME
'SW_PVDDCR_SOC_P0_SW2_RC'
 '@T6G_MB_LIB.T6G(SCH_1):SW_PVDDCR_SOC_P0_SW2_RC':
 C_SIGNAL='@t6g_mb_lib.t6g(sch_1):sw_pvddcr_soc_p0_sw2_rc';
NODE_NAME     PR503 1
 '@T6G_MB_LIB.T6G(SCH_1):PAGE173_I19@PURE_QUANTA.Q_RES(CHIPS)':
 'A': CDS_PINID='A';
NODE_NAME     PC187 2
 '@T6G_MB_LIB.T6G(SCH_1):PAGE173_I85@PURE_QUANTA.Q_CAP(CHIPS)':
 'B': CDS_PINID='B';
NET_NAME
'SW_PVDDCR_SOC_P0_SW3'
 '@T6G_MB_LIB.T6G(SCH_1):SW_PVDDCR_SOC_P0_SW3':
 C_SIGNAL='@t6g_mb_lib.t6g(sch_1):sw_pvddcr_soc_p0_sw3';
NODE_NAME     PL66 1
 '@T6G_MB_LIB.T6G(SCH_1):PAGE174_I25@PURE_QUANTA.Q_INDUCTOR4P_14(CHIPS)':
 '1': CDS_PINID='\1\';
NODE_NAME     PU51 10_19
 '@T6G_MB_LIB.T6G(SCH_1):PAGE174_I38@PURE_QUANTA.ISL99390FRZTR5935(CHIPS)':
 'SW': CDS_PINID='SW';
NODE_NAME     PC188 1
 '@T6G_MB_LIB.T6G(SCH_1):PAGE174_I12@PURE_QUANTA.Q_CAP(CHIPS)':
 'A': CDS_PINID='A';
NET_NAME
'SW_PVDDCR_SOC_P0_SW3_RC'
 '@T6G_MB_LIB.T6G(SCH_1):SW_PVDDCR_SOC_P0_SW3_RC':
 C_SIGNAL='@t6g_mb_lib.t6g(sch_1):sw_pvddcr_soc_p0_sw3_rc';
NODE_NAME     PR505 1
 '@T6G_MB_LIB.T6G(SCH_1):PAGE174_I10@PURE_QUANTA.Q_RES(CHIPS)':
 'A': CDS_PINID='A';
NODE_NAME     PC188 2
 '@T6G_MB_LIB.T6G(SCH_1):PAGE174_I12@PURE_QUANTA.Q_CAP(CHIPS)':
 'B': CDS_PINID='B';
NET_NAME
'SW_PVDDCR_SOC_P1_BOOT1'
 '@T6G_MB_LIB.T6G(SCH_1):SW_PVDDCR_SOC_P1_BOOT1':
 C_SIGNAL='@t6g_mb_lib.t6g(sch_1):sw_pvddcr_soc_p1_boot1';
NODE_NAME     PU30 33
 '@T6G_MB_LIB.T6G(SCH_1):PAGE190_I17@PURE_QUANTA.ISL99390FRZTR5935(CHIPS)':
 'BOOT': CDS_PINID='BOOT';
NODE_NAME     PR209 1
 '@T6G_MB_LIB.T6G(SCH_1):PAGE190_I46@PURE_QUANTA.Q_RES(CHIPS)':
 'A': CDS_PINID='A';
NET_NAME
'SW_PVDDCR_SOC_P1_BOOT1_RC'
 '@T6G_MB_LIB.T6G(SCH_1):SW_PVDDCR_SOC_P1_BOOT1_RC':
 C_SIGNAL='@t6g_mb_lib.t6g(sch_1):sw_pvddcr_soc_p1_boot1_rc';
NODE_NAME     PC333 1
 '@T6G_MB_LIB.T6G(SCH_1):PAGE190_I68@PURE_QUANTA.Q_CAP(CHIPS)':
 'A': CDS_PINID='A';
NODE_NAME     PR209 2
 '@T6G_MB_LIB.T6G(SCH_1):PAGE190_I46@PURE_QUANTA.Q_RES(CHIPS)':
 'B': CDS_PINID='B';
NET_NAME
'SW_PVDDCR_SOC_P1_BOOT2'
 '@T6G_MB_LIB.T6G(SCH_1):SW_PVDDCR_SOC_P1_BOOT2':
 C_SIGNAL='@t6g_mb_lib.t6g(sch_1):sw_pvddcr_soc_p1_boot2';
NODE_NAME     PR210 1
 '@T6G_MB_LIB.T6G(SCH_1):PAGE190_I24@PURE_QUANTA.Q_RES(CHIPS)':
 'A': CDS_PINID='A';
NODE_NAME     PU31 33
 '@T6G_MB_LIB.T6G(SCH_1):PAGE190_I86@PURE_QUANTA.ISL99390FRZTR5935(CHIPS)':
 'BOOT': CDS_PINID='BOOT';
NET_NAME
'SW_PVDDCR_SOC_P1_BOOT2_RC'
 '@T6G_MB_LIB.T6G(SCH_1):SW_PVDDCR_SOC_P1_BOOT2_RC':
 C_SIGNAL='@t6g_mb_lib.t6g(sch_1):sw_pvddcr_soc_p1_boot2_rc';
NODE_NAME     PR210 2
 '@T6G_MB_LIB.T6G(SCH_1):PAGE190_I24@PURE_QUANTA.Q_RES(CHIPS)':
 'B': CDS_PINID='B';
NODE_NAME     PC334 1
 '@T6G_MB_LIB.T6G(SCH_1):PAGE190_I54@PURE_QUANTA.Q_CAP(CHIPS)':
 'A': CDS_PINID='A';
NET_NAME
'SW_PVDDCR_SOC_P1_BOOT3'
 '@T6G_MB_LIB.T6G(SCH_1):SW_PVDDCR_SOC_P1_BOOT3':
 C_SIGNAL='@t6g_mb_lib.t6g(sch_1):sw_pvddcr_soc_p1_boot3';
NODE_NAME     PR215 1
 '@T6G_MB_LIB.T6G(SCH_1):PAGE191_I21@PURE_QUANTA.Q_RES(CHIPS)':
 'A': CDS_PINID='A';
NODE_NAME     PU32 33
 '@T6G_MB_LIB.T6G(SCH_1):PAGE191_I38@PURE_QUANTA.ISL99390FRZTR5935(CHIPS)':
 'BOOT': CDS_PINID='BOOT';
NET_NAME
'SW_PVDDCR_SOC_P1_BOOT3_RC'
 '@T6G_MB_LIB.T6G(SCH_1):SW_PVDDCR_SOC_P1_BOOT3_RC':
 C_SIGNAL='@t6g_mb_lib.t6g(sch_1):sw_pvddcr_soc_p1_boot3_rc';
NODE_NAME     PR215 2
 '@T6G_MB_LIB.T6G(SCH_1):PAGE191_I21@PURE_QUANTA.Q_RES(CHIPS)':
 'B': CDS_PINID='B';
NODE_NAME     PC353 1
 '@T6G_MB_LIB.T6G(SCH_1):PAGE191_I33@PURE_QUANTA.Q_CAP(CHIPS)':
 'A': CDS_PINID='A';
NET_NAME
'SW_PVDDCR_SOC_P1_PH1'
 '@T6G_MB_LIB.T6G(SCH_1):SW_PVDDCR_SOC_P1_PH1':
 C_SIGNAL='@t6g_mb_lib.t6g(sch_1):sw_pvddcr_soc_p1_ph1';
NODE_NAME     PC333 2
 '@T6G_MB_LIB.T6G(SCH_1):PAGE190_I68@PURE_QUANTA.Q_CAP(CHIPS)':
 'B': CDS_PINID='B';
NODE_NAME     PU30 32
 '@T6G_MB_LIB.T6G(SCH_1):PAGE190_I17@PURE_QUANTA.ISL99390FRZTR5935(CHIPS)':
 'PHASE': CDS_PINID='PHASE';
NET_NAME
'SW_PVDDCR_SOC_P1_PH2'
 '@T6G_MB_LIB.T6G(SCH_1):SW_PVDDCR_SOC_P1_PH2':
 C_SIGNAL='@t6g_mb_lib.t6g(sch_1):sw_pvddcr_soc_p1_ph2';
NODE_NAME     PC334 2
 '@T6G_MB_LIB.T6G(SCH_1):PAGE190_I54@PURE_QUANTA.Q_CAP(CHIPS)':
 'B': CDS_PINID='B';
NODE_NAME     PU31 32
 '@T6G_MB_LIB.T6G(SCH_1):PAGE190_I86@PURE_QUANTA.ISL99390FRZTR5935(CHIPS)':
 'PHASE': CDS_PINID='PHASE';
NET_NAME
'SW_PVDDCR_SOC_P1_PH3'
 '@T6G_MB_LIB.T6G(SCH_1):SW_PVDDCR_SOC_P1_PH3':
 C_SIGNAL='@t6g_mb_lib.t6g(sch_1):sw_pvddcr_soc_p1_ph3';
NODE_NAME     PU32 32
 '@T6G_MB_LIB.T6G(SCH_1):PAGE191_I38@PURE_QUANTA.ISL99390FRZTR5935(CHIPS)':
 'PHASE': CDS_PINID='PHASE';
NODE_NAME     PC353 2
 '@T6G_MB_LIB.T6G(SCH_1):PAGE191_I33@PURE_QUANTA.Q_CAP(CHIPS)':
 'B': CDS_PINID='B';
NET_NAME
'SW_PVDDCR_SOC_P1_SW1'
 '@T6G_MB_LIB.T6G(SCH_1):SW_PVDDCR_SOC_P1_SW1':
 C_SIGNAL='@t6g_mb_lib.t6g(sch_1):sw_pvddcr_soc_p1_sw1';
NODE_NAME     PL35 1
 '@T6G_MB_LIB.T6G(SCH_1):PAGE190_I69@PURE_QUANTA.Q_INDUCTOR4P_14(CHIPS)':
 '1': CDS_PINID='\1\';
NODE_NAME     PU30 10_19
 '@T6G_MB_LIB.T6G(SCH_1):PAGE190_I17@PURE_QUANTA.ISL99390FRZTR5935(CHIPS)':
 'SW': CDS_PINID='SW';
NODE_NAME     PC141 1
 '@T6G_MB_LIB.T6G(SCH_1):PAGE190_I45@PURE_QUANTA.Q_CAP(CHIPS)':
 'A': CDS_PINID='A';
NET_NAME
'SW_PVDDCR_SOC_P1_SW1_RC'
 '@T6G_MB_LIB.T6G(SCH_1):SW_PVDDCR_SOC_P1_SW1_RC':
 C_SIGNAL='@t6g_mb_lib.t6g(sch_1):sw_pvddcr_soc_p1_sw1_rc';
NODE_NAME     PR525 1
 '@T6G_MB_LIB.T6G(SCH_1):PAGE190_I29@PURE_QUANTA.Q_RES(CHIPS)':
 'A': CDS_PINID='A';
NODE_NAME     PC141 2
 '@T6G_MB_LIB.T6G(SCH_1):PAGE190_I45@PURE_QUANTA.Q_CAP(CHIPS)':
 'B': CDS_PINID='B';
NET_NAME
'SW_PVDDCR_SOC_P1_SW2'
 '@T6G_MB_LIB.T6G(SCH_1):SW_PVDDCR_SOC_P1_SW2':
 C_SIGNAL='@t6g_mb_lib.t6g(sch_1):sw_pvddcr_soc_p1_sw2';
NODE_NAME     PL36 1
 '@T6G_MB_LIB.T6G(SCH_1):PAGE190_I52@PURE_QUANTA.Q_INDUCTOR4P_14(CHIPS)':
 '1': CDS_PINID='\1\';
NODE_NAME     PC149 1
 '@T6G_MB_LIB.T6G(SCH_1):PAGE190_I20@PURE_QUANTA.Q_CAP(CHIPS)':
 'A': CDS_PINID='A';
NODE_NAME     PU31 10_19
 '@T6G_MB_LIB.T6G(SCH_1):PAGE190_I86@PURE_QUANTA.ISL99390FRZTR5935(CHIPS)':
 'SW': CDS_PINID='SW';
NET_NAME
'SW_PVDDCR_SOC_P1_SW2_RC'
 '@T6G_MB_LIB.T6G(SCH_1):SW_PVDDCR_SOC_P1_SW2_RC':
 C_SIGNAL='@t6g_mb_lib.t6g(sch_1):sw_pvddcr_soc_p1_sw2_rc';
NODE_NAME     PC149 2
 '@T6G_MB_LIB.T6G(SCH_1):PAGE190_I20@PURE_QUANTA.Q_CAP(CHIPS)':
 'B': CDS_PINID='B';
NODE_NAME     PR526 1
 '@T6G_MB_LIB.T6G(SCH_1):PAGE190_I21@PURE_QUANTA.Q_RES(CHIPS)':
 'A': CDS_PINID='A';
NET_NAME
'SW_PVDDCR_SOC_P1_SW3'
 '@T6G_MB_LIB.T6G(SCH_1):SW_PVDDCR_SOC_P1_SW3':
 C_SIGNAL='@t6g_mb_lib.t6g(sch_1):sw_pvddcr_soc_p1_sw3';
NODE_NAME     PL38 1
 '@T6G_MB_LIB.T6G(SCH_1):PAGE191_I26@PURE_QUANTA.Q_INDUCTOR4P_14(CHIPS)':
 '1': CDS_PINID='\1\';
NODE_NAME     PU32 10_19
 '@T6G_MB_LIB.T6G(SCH_1):PAGE191_I38@PURE_QUANTA.ISL99390FRZTR5935(CHIPS)':
 'SW': CDS_PINID='SW';
NODE_NAME     PC195 1
 '@T6G_MB_LIB.T6G(SCH_1):PAGE191_I11@PURE_QUANTA.Q_CAP(CHIPS)':
 'A': CDS_PINID='A';
NET_NAME
'SW_PVDDCR_SOC_P1_SW3_RC'
 '@T6G_MB_LIB.T6G(SCH_1):SW_PVDDCR_SOC_P1_SW3_RC':
 C_SIGNAL='@t6g_mb_lib.t6g(sch_1):sw_pvddcr_soc_p1_sw3_rc';
NODE_NAME     PR511 1
 '@T6G_MB_LIB.T6G(SCH_1):PAGE191_I10@PURE_QUANTA.Q_RES(CHIPS)':
 'A': CDS_PINID='A';
NODE_NAME     PC195 2
 '@T6G_MB_LIB.T6G(SCH_1):PAGE191_I11@PURE_QUANTA.Q_CAP(CHIPS)':
 'B': CDS_PINID='B';
NET_NAME
'SW_PVDDIO_P0_BOOT1'
 '@T6G_MB_LIB.T6G(SCH_1):SW_PVDDIO_P0_BOOT1':
 C_SIGNAL='@t6g_mb_lib.t6g(sch_1):sw_pvddio_p0_boot1';
NODE_NAME     PR101 1
 '@T6G_MB_LIB.T6G(SCH_1):PAGE180_I34@PURE_QUANTA.Q_RES(CHIPS)':
 'A': CDS_PINID='A';
NODE_NAME     PU17 33
 '@T6G_MB_LIB.T6G(SCH_1):PAGE180_I84@PURE_QUANTA.ISL99390FRZTR5935(CHIPS)':
 'BOOT': CDS_PINID='BOOT';
NET_NAME
'SW_PVDDIO_P0_BOOT1_R'
 '@T6G_MB_LIB.T6G(SCH_1):SW_PVDDIO_P0_BOOT1_R':
 C_SIGNAL='@t6g_mb_lib.t6g(sch_1):sw_pvddio_p0_boot1_r';
NODE_NAME     PR101 2
 '@T6G_MB_LIB.T6G(SCH_1):PAGE180_I34@PURE_QUANTA.Q_RES(CHIPS)':
 'B': CDS_PINID='B';
NODE_NAME     PC155 1
 '@T6G_MB_LIB.T6G(SCH_1):PAGE180_I63@PURE_QUANTA.Q_CAP(CHIPS)':
 'A': CDS_PINID='A';
NET_NAME
'SW_PVDDIO_P0_BOOT2'
 '@T6G_MB_LIB.T6G(SCH_1):SW_PVDDIO_P0_BOOT2':
 C_SIGNAL='@t6g_mb_lib.t6g(sch_1):sw_pvddio_p0_boot2';
NODE_NAME     PU18 33
 '@T6G_MB_LIB.T6G(SCH_1):PAGE180_I15@PURE_QUANTA.ISL99390FRZTR5935(CHIPS)':
 'BOOT': CDS_PINID='BOOT';
NODE_NAME     PR102 1
 '@T6G_MB_LIB.T6G(SCH_1):PAGE180_I17@PURE_QUANTA.Q_RES(CHIPS)':
 'A': CDS_PINID='A';
NET_NAME
'SW_PVDDIO_P0_BOOT2_R'
 '@T6G_MB_LIB.T6G(SCH_1):SW_PVDDIO_P0_BOOT2_R':
 C_SIGNAL='@t6g_mb_lib.t6g(sch_1):sw_pvddio_p0_boot2_r';
NODE_NAME     PR102 2
 '@T6G_MB_LIB.T6G(SCH_1):PAGE180_I17@PURE_QUANTA.Q_RES(CHIPS)':
 'B': CDS_PINID='B';
NODE_NAME     PC156 1
 '@T6G_MB_LIB.T6G(SCH_1):PAGE180_I41@PURE_QUANTA.Q_CAP(CHIPS)':
 'A': CDS_PINID='A';
NET_NAME
'SW_PVDDIO_P0_BOOT3'
 '@T6G_MB_LIB.T6G(SCH_1):SW_PVDDIO_P0_BOOT3':
 C_SIGNAL='@t6g_mb_lib.t6g(sch_1):sw_pvddio_p0_boot3';
NODE_NAME     PU19 33
 '@T6G_MB_LIB.T6G(SCH_1):PAGE181_I32@PURE_QUANTA.ISL99390FRZTR5935(CHIPS)':
 'BOOT': CDS_PINID='BOOT';
NODE_NAME     PR110 1
 '@T6G_MB_LIB.T6G(SCH_1):PAGE181_I34@PURE_QUANTA.Q_RES(CHIPS)':
 'A': CDS_PINID='A';
NET_NAME
'SW_PVDDIO_P0_BOOT3_R'
 '@T6G_MB_LIB.T6G(SCH_1):SW_PVDDIO_P0_BOOT3_R':
 C_SIGNAL='@t6g_mb_lib.t6g(sch_1):sw_pvddio_p0_boot3_r';
NODE_NAME     PC186 1
 '@T6G_MB_LIB.T6G(SCH_1):PAGE181_I59@PURE_QUANTA.Q_CAP(CHIPS)':
 'A': CDS_PINID='A';
NODE_NAME     PR110 2
 '@T6G_MB_LIB.T6G(SCH_1):PAGE181_I34@PURE_QUANTA.Q_RES(CHIPS)':
 'B': CDS_PINID='B';
NET_NAME
'SW_PVDDIO_P0_BOOT4'
 '@T6G_MB_LIB.T6G(SCH_1):SW_PVDDIO_P0_BOOT4':
 C_SIGNAL='@t6g_mb_lib.t6g(sch_1):sw_pvddio_p0_boot4';
NODE_NAME     PR109 1
 '@T6G_MB_LIB.T6G(SCH_1):PAGE181_I16@PURE_QUANTA.Q_RES(CHIPS)':
 'A': CDS_PINID='A';
NODE_NAME     PU20 33
 '@T6G_MB_LIB.T6G(SCH_1):PAGE181_I73@PURE_QUANTA.ISL99390FRZTR5935(CHIPS)':
 'BOOT': CDS_PINID='BOOT';
NET_NAME
'SW_PVDDIO_P0_BOOT4_R'
 '@T6G_MB_LIB.T6G(SCH_1):SW_PVDDIO_P0_BOOT4_R':
 C_SIGNAL='@t6g_mb_lib.t6g(sch_1):sw_pvddio_p0_boot4_r';
NODE_NAME     PC183 1
 '@T6G_MB_LIB.T6G(SCH_1):PAGE181_I44@PURE_QUANTA.Q_CAP(CHIPS)':
 'A': CDS_PINID='A';
NODE_NAME     PR109 2
 '@T6G_MB_LIB.T6G(SCH_1):PAGE181_I16@PURE_QUANTA.Q_RES(CHIPS)':
 'B': CDS_PINID='B';
NET_NAME
'SW_PVDDIO_P0_BOOTR1'
 '@T6G_MB_LIB.T6G(SCH_1):SW_PVDDIO_P0_BOOTR1':
 C_SIGNAL='@t6g_mb_lib.t6g(sch_1):sw_pvddio_p0_bootr1';
NODE_NAME     PC155 2
 '@T6G_MB_LIB.T6G(SCH_1):PAGE180_I63@PURE_QUANTA.Q_CAP(CHIPS)':
 'B': CDS_PINID='B';
NODE_NAME     PU17 32
 '@T6G_MB_LIB.T6G(SCH_1):PAGE180_I84@PURE_QUANTA.ISL99390FRZTR5935(CHIPS)':
 'PHASE': CDS_PINID='PHASE';
NET_NAME
'SW_PVDDIO_P0_BOOTR2'
 '@T6G_MB_LIB.T6G(SCH_1):SW_PVDDIO_P0_BOOTR2':
 C_SIGNAL='@t6g_mb_lib.t6g(sch_1):sw_pvddio_p0_bootr2';
NODE_NAME     PU18 32
 '@T6G_MB_LIB.T6G(SCH_1):PAGE180_I15@PURE_QUANTA.ISL99390FRZTR5935(CHIPS)':
 'PHASE': CDS_PINID='PHASE';
NODE_NAME     PC156 2
 '@T6G_MB_LIB.T6G(SCH_1):PAGE180_I41@PURE_QUANTA.Q_CAP(CHIPS)':
 'B': CDS_PINID='B';
NET_NAME
'SW_PVDDIO_P0_BOOTR3'
 '@T6G_MB_LIB.T6G(SCH_1):SW_PVDDIO_P0_BOOTR3':
 C_SIGNAL='@t6g_mb_lib.t6g(sch_1):sw_pvddio_p0_bootr3';
NODE_NAME     PC186 2
 '@T6G_MB_LIB.T6G(SCH_1):PAGE181_I59@PURE_QUANTA.Q_CAP(CHIPS)':
 'B': CDS_PINID='B';
NODE_NAME     PU19 32
 '@T6G_MB_LIB.T6G(SCH_1):PAGE181_I32@PURE_QUANTA.ISL99390FRZTR5935(CHIPS)':
 'PHASE': CDS_PINID='PHASE';
NET_NAME
'SW_PVDDIO_P0_BOOTR4'
 '@T6G_MB_LIB.T6G(SCH_1):SW_PVDDIO_P0_BOOTR4':
 C_SIGNAL='@t6g_mb_lib.t6g(sch_1):sw_pvddio_p0_bootr4';
NODE_NAME     PC183 2
 '@T6G_MB_LIB.T6G(SCH_1):PAGE181_I44@PURE_QUANTA.Q_CAP(CHIPS)':
 'B': CDS_PINID='B';
NODE_NAME     PU20 32
 '@T6G_MB_LIB.T6G(SCH_1):PAGE181_I73@PURE_QUANTA.ISL99390FRZTR5935(CHIPS)':
 'PHASE': CDS_PINID='PHASE';
NET_NAME
'SW_PVDDIO_P0_SW1'
 '@T6G_MB_LIB.T6G(SCH_1):SW_PVDDIO_P0_SW1':
 C_SIGNAL='@t6g_mb_lib.t6g(sch_1):sw_pvddio_p0_sw1';
NODE_NAME     PC158 1
 '@T6G_MB_LIB.T6G(SCH_1):PAGE180_I61@PURE_QUANTA.Q_CAP(CHIPS)':
 'A': CDS_PINID='A';
NODE_NAME     PL17 1
 '@T6G_MB_LIB.T6G(SCH_1):PAGE180_I64@PURE_QUANTA.Q_INDUCTOR4P_14(CHIPS)':
 '1': CDS_PINID='\1\';
NODE_NAME     PU17 10_19
 '@T6G_MB_LIB.T6G(SCH_1):PAGE180_I84@PURE_QUANTA.ISL99390FRZTR5935(CHIPS)':
 'SW': CDS_PINID='SW';
NET_NAME
'SW_PVDDIO_P0_SW1_RC'
 '@T6G_MB_LIB.T6G(SCH_1):SW_PVDDIO_P0_SW1_RC':
 C_SIGNAL='@t6g_mb_lib.t6g(sch_1):sw_pvddio_p0_sw1_rc';
NODE_NAME     PR221 1
 '@T6G_MB_LIB.T6G(SCH_1):PAGE180_I60@PURE_QUANTA.Q_RES(CHIPS)':
 'A': CDS_PINID='A';
NODE_NAME     PC158 2
 '@T6G_MB_LIB.T6G(SCH_1):PAGE180_I61@PURE_QUANTA.Q_CAP(CHIPS)':
 'B': CDS_PINID='B';
NET_NAME
'SW_PVDDIO_P0_SW2'
 '@T6G_MB_LIB.T6G(SCH_1):SW_PVDDIO_P0_SW2':
 C_SIGNAL='@t6g_mb_lib.t6g(sch_1):sw_pvddio_p0_sw2';
NODE_NAME     PU18 10_19
 '@T6G_MB_LIB.T6G(SCH_1):PAGE180_I15@PURE_QUANTA.ISL99390FRZTR5935(CHIPS)':
 'SW': CDS_PINID='SW';
NODE_NAME     PC159 1
 '@T6G_MB_LIB.T6G(SCH_1):PAGE180_I37@PURE_QUANTA.Q_CAP(CHIPS)':
 'A': CDS_PINID='A';
NODE_NAME     PL18 1
 '@T6G_MB_LIB.T6G(SCH_1):PAGE180_I40@PURE_QUANTA.Q_INDUCTOR4P_14(CHIPS)':
 '1': CDS_PINID='\1\';
NET_NAME
'SW_PVDDIO_P0_SW2_RC'
 '@T6G_MB_LIB.T6G(SCH_1):SW_PVDDIO_P0_SW2_RC':
 C_SIGNAL='@t6g_mb_lib.t6g(sch_1):sw_pvddio_p0_sw2_rc';
NODE_NAME     PR223 1
 '@T6G_MB_LIB.T6G(SCH_1):PAGE180_I36@PURE_QUANTA.Q_RES(CHIPS)':
 'A': CDS_PINID='A';
NODE_NAME     PC159 2
 '@T6G_MB_LIB.T6G(SCH_1):PAGE180_I37@PURE_QUANTA.Q_CAP(CHIPS)':
 'B': CDS_PINID='B';
NET_NAME
'SW_PVDDIO_P0_SW3'
 '@T6G_MB_LIB.T6G(SCH_1):SW_PVDDIO_P0_SW3':
 C_SIGNAL='@t6g_mb_lib.t6g(sch_1):sw_pvddio_p0_sw3';
NODE_NAME     PU19 10_19
 '@T6G_MB_LIB.T6G(SCH_1):PAGE181_I32@PURE_QUANTA.ISL99390FRZTR5935(CHIPS)':
 'SW': CDS_PINID='SW';
NODE_NAME     PC166 1
 '@T6G_MB_LIB.T6G(SCH_1):PAGE181_I56@PURE_QUANTA.Q_CAP(CHIPS)':
 'A': CDS_PINID='A';
NODE_NAME     PL21 1
 '@T6G_MB_LIB.T6G(SCH_1):PAGE181_I61@PURE_QUANTA.Q_INDUCTOR4P_14(CHIPS)':
 '1': CDS_PINID='\1\';
NET_NAME
'SW_PVDDIO_P0_SW3_RC'
 '@T6G_MB_LIB.T6G(SCH_1):SW_PVDDIO_P0_SW3_RC':
 C_SIGNAL='@t6g_mb_lib.t6g(sch_1):sw_pvddio_p0_sw3_rc';
NODE_NAME     PR379 1
 '@T6G_MB_LIB.T6G(SCH_1):PAGE181_I55@PURE_QUANTA.Q_RES(CHIPS)':
 'A': CDS_PINID='A';
NODE_NAME     PC166 2
 '@T6G_MB_LIB.T6G(SCH_1):PAGE181_I56@PURE_QUANTA.Q_CAP(CHIPS)':
 'B': CDS_PINID='B';
NET_NAME
'SW_PVDDIO_P0_SW4'
 '@T6G_MB_LIB.T6G(SCH_1):SW_PVDDIO_P0_SW4':
 C_SIGNAL='@t6g_mb_lib.t6g(sch_1):sw_pvddio_p0_sw4';
NODE_NAME     PC163 1
 '@T6G_MB_LIB.T6G(SCH_1):PAGE181_I39@PURE_QUANTA.Q_CAP(CHIPS)':
 'A': CDS_PINID='A';
NODE_NAME     PL20 1
 '@T6G_MB_LIB.T6G(SCH_1):PAGE181_I42@PURE_QUANTA.Q_INDUCTOR4P_14(CHIPS)':
 '1': CDS_PINID='\1\';
NODE_NAME     PU20 10_19
 '@T6G_MB_LIB.T6G(SCH_1):PAGE181_I73@PURE_QUANTA.ISL99390FRZTR5935(CHIPS)':
 'SW': CDS_PINID='SW';
NET_NAME
'SW_PVDDIO_P0_SW4_RC'
 '@T6G_MB_LIB.T6G(SCH_1):SW_PVDDIO_P0_SW4_RC':
 C_SIGNAL='@t6g_mb_lib.t6g(sch_1):sw_pvddio_p0_sw4_rc';
NODE_NAME     PR291 1
 '@T6G_MB_LIB.T6G(SCH_1):PAGE181_I38@PURE_QUANTA.Q_RES(CHIPS)':
 'A': CDS_PINID='A';
NODE_NAME     PC163 2
 '@T6G_MB_LIB.T6G(SCH_1):PAGE181_I39@PURE_QUANTA.Q_CAP(CHIPS)':
 'B': CDS_PINID='B';
NET_NAME
'SW_PVDDIO_P1_BOOT1'
 '@T6G_MB_LIB.T6G(SCH_1):SW_PVDDIO_P1_BOOT1':
 C_SIGNAL='@t6g_mb_lib.t6g(sch_1):sw_pvddio_p1_boot1';
NODE_NAME     PU39 33
 '@T6G_MB_LIB.T6G(SCH_1):PAGE197_I39@PURE_QUANTA.ISL99390FRZTR5935(CHIPS)':
 'BOOT': CDS_PINID='BOOT';
NODE_NAME     PR279 1
 '@T6G_MB_LIB.T6G(SCH_1):PAGE197_I43@PURE_QUANTA.Q_RES(CHIPS)':
 'A': CDS_PINID='A';
NET_NAME
'SW_PVDDIO_P1_BOOT1_R'
 '@T6G_MB_LIB.T6G(SCH_1):SW_PVDDIO_P1_BOOT1_R':
 C_SIGNAL='@t6g_mb_lib.t6g(sch_1):sw_pvddio_p1_boot1_r';
NODE_NAME     PR279 2
 '@T6G_MB_LIB.T6G(SCH_1):PAGE197_I43@PURE_QUANTA.Q_RES(CHIPS)':
 'B': CDS_PINID='B';
NODE_NAME     PC447 1
 '@T6G_MB_LIB.T6G(SCH_1):PAGE197_I65@PURE_QUANTA.Q_CAP(CHIPS)':
 'A': CDS_PINID='A';
NET_NAME
'SW_PVDDIO_P1_BOOT2'
 '@T6G_MB_LIB.T6G(SCH_1):SW_PVDDIO_P1_BOOT2':
 C_SIGNAL='@t6g_mb_lib.t6g(sch_1):sw_pvddio_p1_boot2';
NODE_NAME     PR278 1
 '@T6G_MB_LIB.T6G(SCH_1):PAGE197_I22@PURE_QUANTA.Q_RES(CHIPS)':
 'A': CDS_PINID='A';
NODE_NAME     PU40 33
 '@T6G_MB_LIB.T6G(SCH_1):PAGE197_I84@PURE_QUANTA.ISL99390FRZTR5935(CHIPS)':
 'BOOT': CDS_PINID='BOOT';
NET_NAME
'SW_PVDDIO_P1_BOOT2_R'
 '@T6G_MB_LIB.T6G(SCH_1):SW_PVDDIO_P1_BOOT2_R':
 C_SIGNAL='@t6g_mb_lib.t6g(sch_1):sw_pvddio_p1_boot2_r';
NODE_NAME     PR278 2
 '@T6G_MB_LIB.T6G(SCH_1):PAGE197_I22@PURE_QUANTA.Q_RES(CHIPS)':
 'B': CDS_PINID='B';
NODE_NAME     PC445 1
 '@T6G_MB_LIB.T6G(SCH_1):PAGE197_I47@PURE_QUANTA.Q_CAP(CHIPS)':
 'A': CDS_PINID='A';
NET_NAME
'SW_PVDDIO_P1_BOOT3'
 '@T6G_MB_LIB.T6G(SCH_1):SW_PVDDIO_P1_BOOT3':
 C_SIGNAL='@t6g_mb_lib.t6g(sch_1):sw_pvddio_p1_boot3';
NODE_NAME     PR373 1
 '@T6G_MB_LIB.T6G(SCH_1):PAGE198_I34@PURE_QUANTA.Q_RES(CHIPS)':
 'A': CDS_PINID='A';
NODE_NAME     PU52 33
 '@T6G_MB_LIB.T6G(SCH_1):PAGE198_I73@PURE_QUANTA.ISL99390FRZTR5935(CHIPS)':
 'BOOT': CDS_PINID='BOOT';
NET_NAME
'SW_PVDDIO_P1_BOOT3_R'
 '@T6G_MB_LIB.T6G(SCH_1):SW_PVDDIO_P1_BOOT3_R':
 C_SIGNAL='@t6g_mb_lib.t6g(sch_1):sw_pvddio_p1_boot3_r';
NODE_NAME     PR373 2
 '@T6G_MB_LIB.T6G(SCH_1):PAGE198_I34@PURE_QUANTA.Q_RES(CHIPS)':
 'B': CDS_PINID='B';
NODE_NAME     PC631 1
 '@T6G_MB_LIB.T6G(SCH_1):PAGE198_I63@PURE_QUANTA.Q_CAP(CHIPS)':
 'A': CDS_PINID='A';
NET_NAME
'SW_PVDDIO_P1_BOOT4'
 '@T6G_MB_LIB.T6G(SCH_1):SW_PVDDIO_P1_BOOT4':
 C_SIGNAL='@t6g_mb_lib.t6g(sch_1):sw_pvddio_p1_boot4';
NODE_NAME     PU53 33
 '@T6G_MB_LIB.T6G(SCH_1):PAGE198_I15@PURE_QUANTA.ISL99390FRZTR5935(CHIPS)':
 'BOOT': CDS_PINID='BOOT';
NODE_NAME     PR372 1
 '@T6G_MB_LIB.T6G(SCH_1):PAGE198_I17@PURE_QUANTA.Q_RES(CHIPS)':
 'A': CDS_PINID='A';
NET_NAME
'SW_PVDDIO_P1_BOOT4_R'
 '@T6G_MB_LIB.T6G(SCH_1):SW_PVDDIO_P1_BOOT4_R':
 C_SIGNAL='@t6g_mb_lib.t6g(sch_1):sw_pvddio_p1_boot4_r';
NODE_NAME     PC630 1
 '@T6G_MB_LIB.T6G(SCH_1):PAGE198_I44@PURE_QUANTA.Q_CAP(CHIPS)':
 'A': CDS_PINID='A';
NODE_NAME     PR372 2
 '@T6G_MB_LIB.T6G(SCH_1):PAGE198_I17@PURE_QUANTA.Q_RES(CHIPS)':
 'B': CDS_PINID='B';
NET_NAME
'SW_PVDDIO_P1_BOOTR1'
 '@T6G_MB_LIB.T6G(SCH_1):SW_PVDDIO_P1_BOOTR1':
 C_SIGNAL='@t6g_mb_lib.t6g(sch_1):sw_pvddio_p1_bootr1';
NODE_NAME     PU39 32
 '@T6G_MB_LIB.T6G(SCH_1):PAGE197_I39@PURE_QUANTA.ISL99390FRZTR5935(CHIPS)':
 'PHASE': CDS_PINID='PHASE';
NODE_NAME     PC447 2
 '@T6G_MB_LIB.T6G(SCH_1):PAGE197_I65@PURE_QUANTA.Q_CAP(CHIPS)':
 'B': CDS_PINID='B';
NET_NAME
'SW_PVDDIO_P1_BOOTR2'
 '@T6G_MB_LIB.T6G(SCH_1):SW_PVDDIO_P1_BOOTR2':
 C_SIGNAL='@t6g_mb_lib.t6g(sch_1):sw_pvddio_p1_bootr2';
NODE_NAME     PC445 2
 '@T6G_MB_LIB.T6G(SCH_1):PAGE197_I47@PURE_QUANTA.Q_CAP(CHIPS)':
 'B': CDS_PINID='B';
NODE_NAME     PU40 32
 '@T6G_MB_LIB.T6G(SCH_1):PAGE197_I84@PURE_QUANTA.ISL99390FRZTR5935(CHIPS)':
 'PHASE': CDS_PINID='PHASE';
NET_NAME
'SW_PVDDIO_P1_BOOTR3'
 '@T6G_MB_LIB.T6G(SCH_1):SW_PVDDIO_P1_BOOTR3':
 C_SIGNAL='@t6g_mb_lib.t6g(sch_1):sw_pvddio_p1_bootr3';
NODE_NAME     PC631 2
 '@T6G_MB_LIB.T6G(SCH_1):PAGE198_I63@PURE_QUANTA.Q_CAP(CHIPS)':
 'B': CDS_PINID='B';
NODE_NAME     PU52 32
 '@T6G_MB_LIB.T6G(SCH_1):PAGE198_I73@PURE_QUANTA.ISL99390FRZTR5935(CHIPS)':
 'PHASE': CDS_PINID='PHASE';
NET_NAME
'SW_PVDDIO_P1_BOOTR4'
 '@T6G_MB_LIB.T6G(SCH_1):SW_PVDDIO_P1_BOOTR4':
 C_SIGNAL='@t6g_mb_lib.t6g(sch_1):sw_pvddio_p1_bootr4';
NODE_NAME     PU53 32
 '@T6G_MB_LIB.T6G(SCH_1):PAGE198_I15@PURE_QUANTA.ISL99390FRZTR5935(CHIPS)':
 'PHASE': CDS_PINID='PHASE';
NODE_NAME     PC630 2
 '@T6G_MB_LIB.T6G(SCH_1):PAGE198_I44@PURE_QUANTA.Q_CAP(CHIPS)':
 'B': CDS_PINID='B';
NET_NAME
'SW_PVDDIO_P1_SW1'
 '@T6G_MB_LIB.T6G(SCH_1):SW_PVDDIO_P1_SW1':
 C_SIGNAL='@t6g_mb_lib.t6g(sch_1):sw_pvddio_p1_sw1';
NODE_NAME     PU39 10_19
 '@T6G_MB_LIB.T6G(SCH_1):PAGE197_I39@PURE_QUANTA.ISL99390FRZTR5935(CHIPS)':
 'SW': CDS_PINID='SW';
NODE_NAME     PC174 1
 '@T6G_MB_LIB.T6G(SCH_1):PAGE197_I40@PURE_QUANTA.Q_CAP(CHIPS)':
 'A': CDS_PINID='A';
NODE_NAME     PL47 1
 '@T6G_MB_LIB.T6G(SCH_1):PAGE197_I71@PURE_QUANTA.Q_INDUCTOR4P_14(CHIPS)':
 '1': CDS_PINID='\1\';
NET_NAME
'SW_PVDDIO_P1_SW1_RC'
 '@T6G_MB_LIB.T6G(SCH_1):SW_PVDDIO_P1_SW1_RC':
 C_SIGNAL='@t6g_mb_lib.t6g(sch_1):sw_pvddio_p1_sw1_rc';
NODE_NAME     PR488 1
 '@T6G_MB_LIB.T6G(SCH_1):PAGE197_I26@PURE_QUANTA.Q_RES(CHIPS)':
 'A': CDS_PINID='A';
NODE_NAME     PC174 2
 '@T6G_MB_LIB.T6G(SCH_1):PAGE197_I40@PURE_QUANTA.Q_CAP(CHIPS)':
 'B': CDS_PINID='B';
NET_NAME
'SW_PVDDIO_P1_SW2'
 '@T6G_MB_LIB.T6G(SCH_1):SW_PVDDIO_P1_SW2':
 C_SIGNAL='@t6g_mb_lib.t6g(sch_1):sw_pvddio_p1_sw2';
NODE_NAME     PC175 1
 '@T6G_MB_LIB.T6G(SCH_1):PAGE197_I20@PURE_QUANTA.Q_CAP(CHIPS)':
 'A': CDS_PINID='A';
NODE_NAME     PL48 1
 '@T6G_MB_LIB.T6G(SCH_1):PAGE197_I83@PURE_QUANTA.Q_INDUCTOR4P_14(CHIPS)':
 '1': CDS_PINID='\1\';
NODE_NAME     PU40 10_19
 '@T6G_MB_LIB.T6G(SCH_1):PAGE197_I84@PURE_QUANTA.ISL99390FRZTR5935(CHIPS)':
 'SW': CDS_PINID='SW';
NET_NAME
'SW_PVDDIO_P1_SW2_RC'
 '@T6G_MB_LIB.T6G(SCH_1):SW_PVDDIO_P1_SW2_RC':
 C_SIGNAL='@t6g_mb_lib.t6g(sch_1):sw_pvddio_p1_sw2_rc';
NODE_NAME     PR489 1
 '@T6G_MB_LIB.T6G(SCH_1):PAGE197_I19@PURE_QUANTA.Q_RES(CHIPS)':
 'A': CDS_PINID='A';
NODE_NAME     PC175 2
 '@T6G_MB_LIB.T6G(SCH_1):PAGE197_I20@PURE_QUANTA.Q_CAP(CHIPS)':
 'B': CDS_PINID='B';
NET_NAME
'SW_PVDDIO_P1_SW3'
 '@T6G_MB_LIB.T6G(SCH_1):SW_PVDDIO_P1_SW3':
 C_SIGNAL='@t6g_mb_lib.t6g(sch_1):sw_pvddio_p1_sw3';
NODE_NAME     PC177 1
 '@T6G_MB_LIB.T6G(SCH_1):PAGE198_I58@PURE_QUANTA.Q_CAP(CHIPS)':
 'A': CDS_PINID='A';
NODE_NAME     PL68 1
 '@T6G_MB_LIB.T6G(SCH_1):PAGE198_I62@PURE_QUANTA.Q_INDUCTOR4P_14(CHIPS)':
 '1': CDS_PINID='\1\';
NODE_NAME     PU52 10_19
 '@T6G_MB_LIB.T6G(SCH_1):PAGE198_I73@PURE_QUANTA.ISL99390FRZTR5935(CHIPS)':
 'SW': CDS_PINID='SW';
NET_NAME
'SW_PVDDIO_P1_SW3_RC'
 '@T6G_MB_LIB.T6G(SCH_1):SW_PVDDIO_P1_SW3_RC':
 C_SIGNAL='@t6g_mb_lib.t6g(sch_1):sw_pvddio_p1_sw3_rc';
NODE_NAME     PR492 1
 '@T6G_MB_LIB.T6G(SCH_1):PAGE198_I57@PURE_QUANTA.Q_RES(CHIPS)':
 'A': CDS_PINID='A';
NODE_NAME     PC177 2
 '@T6G_MB_LIB.T6G(SCH_1):PAGE198_I58@PURE_QUANTA.Q_CAP(CHIPS)':
 'B': CDS_PINID='B';
NET_NAME
'SW_PVDDIO_P1_SW4'
 '@T6G_MB_LIB.T6G(SCH_1):SW_PVDDIO_P1_SW4':
 C_SIGNAL='@t6g_mb_lib.t6g(sch_1):sw_pvddio_p1_sw4';
NODE_NAME     PU53 10_19
 '@T6G_MB_LIB.T6G(SCH_1):PAGE198_I15@PURE_QUANTA.ISL99390FRZTR5935(CHIPS)':
 'SW': CDS_PINID='SW';
NODE_NAME     PC176 1
 '@T6G_MB_LIB.T6G(SCH_1):PAGE198_I37@PURE_QUANTA.Q_CAP(CHIPS)':
 'A': CDS_PINID='A';
NODE_NAME     PL67 1
 '@T6G_MB_LIB.T6G(SCH_1):PAGE198_I42@PURE_QUANTA.Q_INDUCTOR4P_14(CHIPS)':
 '1': CDS_PINID='\1\';
NET_NAME
'SW_PVDDIO_P1_SW4_RC'
 '@T6G_MB_LIB.T6G(SCH_1):SW_PVDDIO_P1_SW4_RC':
 C_SIGNAL='@t6g_mb_lib.t6g(sch_1):sw_pvddio_p1_sw4_rc';
NODE_NAME     PC176 2
 '@T6G_MB_LIB.T6G(SCH_1):PAGE198_I37@PURE_QUANTA.Q_CAP(CHIPS)':
 'B': CDS_PINID='B';
NODE_NAME     PR491 1
 '@T6G_MB_LIB.T6G(SCH_1):PAGE198_I39@PURE_QUANTA.Q_RES(CHIPS)':
 'A': CDS_PINID='A';
NET_NAME
'SW_PVDD_33_S5_BST'
 '@T6G_MB_LIB.T6G(SCH_1):SW_PVDD_33_S5_BST':
 C_SIGNAL='@t6g_mb_lib.t6g(sch_1):sw_pvdd_33_s5_bst';
NODE_NAME     PU55 1
 '@T6G_MB_LIB.T6G(SCH_1):PAGE167_I41@PURE_QUANTA.MPQ8633AGLEC807Z(CHIPS)':
 'BST': CDS_PINID='BST';
NODE_NAME     PR8000 1
 '@T6G_MB_LIB.T6G(SCH_1):PAGE167_I46@PURE_QUANTA.Q_RES(CHIPS)':
 'A': CDS_PINID='A';
NET_NAME
'SW_PVDD_33_S5_BST_R'
 '@T6G_MB_LIB.T6G(SCH_1):SW_PVDD_33_S5_BST_R':
 C_SIGNAL='@t6g_mb_lib.t6g(sch_1):sw_pvdd_33_s5_bst_r';
NODE_NAME     PC128 1
 '@T6G_MB_LIB.T6G(SCH_1):PAGE167_I40@PURE_QUANTA.Q_CAP(CHIPS)':
 'A': CDS_PINID='A';
NODE_NAME     PR8000 2
 '@T6G_MB_LIB.T6G(SCH_1):PAGE167_I46@PURE_QUANTA.Q_RES(CHIPS)':
 'B': CDS_PINID='B';
NET_NAME
'SW_PVDD_33_S5_SW'
 '@T6G_MB_LIB.T6G(SCH_1):SW_PVDD_33_S5_SW':
 C_SIGNAL='@t6g_mb_lib.t6g(sch_1):sw_pvdd_33_s5_sw';
NODE_NAME     PC128 2
 '@T6G_MB_LIB.T6G(SCH_1):PAGE167_I40@PURE_QUANTA.Q_CAP(CHIPS)':
 'B': CDS_PINID='B';
NODE_NAME     PU55 20
 '@T6G_MB_LIB.T6G(SCH_1):PAGE167_I41@PURE_QUANTA.MPQ8633AGLEC807Z(CHIPS)':
 'SW': CDS_PINID='SW';
NODE_NAME     PL72 1
 '@T6G_MB_LIB.T6G(SCH_1):PAGE167_I47@PURE_QUANTA.Q_INDUCTOR(CHIPS)':
 '1': CDS_PINID='\1\';
NET_NAME
'T1_GND'
 '@T6G_MB_LIB.T6G(SCH_1):T1_GND':
 C_SIGNAL='@t6g_mb_lib.t6g(sch_1):t1_gnd',
 CDS_GLOBAL_NET='TRUE';
NODE_NAME     DB6 1
 '@T6G_MB_LIB.T6G(SCH_1):PAGE265_I2@PURE_QUANTA.TDR_3P(CHIPS)':
 'GND': CDS_PINID='GND';
NODE_NAME     DB14 1
 '@T6G_MB_LIB.T6G(SCH_1):PAGE265_I5@PURE_QUANTA.TDR_3P(CHIPS)':
 'GND': CDS_PINID='GND';
NODE_NAME     DB13 1
 '@T6G_MB_LIB.T6G(SCH_1):PAGE265_I8@PURE_QUANTA.TDR_3P(CHIPS)':
 'GND': CDS_PINID='GND';
NODE_NAME     DB5 1
 '@T6G_MB_LIB.T6G(SCH_1):PAGE265_I9@PURE_QUANTA.TDR_3P(CHIPS)':
 'GND': CDS_PINID='GND';
NODE_NAME     DB4 1
 '@T6G_MB_LIB.T6G(SCH_1):PAGE265_I12@PURE_QUANTA.TDR_3P(CHIPS)':
 'GND': CDS_PINID='GND';
NODE_NAME     DB3 1
 '@T6G_MB_LIB.T6G(SCH_1):PAGE265_I13@PURE_QUANTA.TDR_3P(CHIPS)':
 'GND': CDS_PINID='GND';
NODE_NAME     DB2 1
 '@T6G_MB_LIB.T6G(SCH_1):PAGE265_I15@PURE_QUANTA.TDR_3P(CHIPS)':
 'GND': CDS_PINID='GND';
NODE_NAME     DB1 1
 '@T6G_MB_LIB.T6G(SCH_1):PAGE265_I16@PURE_QUANTA.TDR_3P(CHIPS)':
 'GND': CDS_PINID='GND';
NODE_NAME     DB12 1
 '@T6G_MB_LIB.T6G(SCH_1):PAGE265_I18@PURE_QUANTA.TDR_3P(CHIPS)':
 'GND': CDS_PINID='GND';
NODE_NAME     DB16 1
 '@T6G_MB_LIB.T6G(SCH_1):PAGE265_I20@PURE_QUANTA.TDR_3P(CHIPS)':
 'GND': CDS_PINID='GND';
NODE_NAME     DB15 1
 '@T6G_MB_LIB.T6G(SCH_1):PAGE265_I22@PURE_QUANTA.TDR_3P(CHIPS)':
 'GND': CDS_PINID='GND';
NODE_NAME     DB11 1
 '@T6G_MB_LIB.T6G(SCH_1):PAGE265_I25@PURE_QUANTA.TDR_3P(CHIPS)':
 'GND': CDS_PINID='GND';
NODE_NAME     X6 2
 '@T6G_MB_LIB.T6G(SCH_1):PAGE265_I29@PURE_QUANTA.TP_TDR_4P_FTS(CHIPS)':
 'P1': CDS_PINID='P1';
NODE_NAME     X6 3
 '@T6G_MB_LIB.T6G(SCH_1):PAGE265_I29@PURE_QUANTA.TP_TDR_4P_FTS(CHIPS)':
 'P2': CDS_PINID='P2';
NODE_NAME     X26 2
 '@T6G_MB_LIB.T6G(SCH_1):PAGE265_I30@PURE_QUANTA.TP_TDR_4P_FTS(CHIPS)':
 'P1': CDS_PINID='P1';
NODE_NAME     X26 3
 '@T6G_MB_LIB.T6G(SCH_1):PAGE265_I30@PURE_QUANTA.TP_TDR_4P_FTS(CHIPS)':
 'P2': CDS_PINID='P2';
NODE_NAME     X25 2
 '@T6G_MB_LIB.T6G(SCH_1):PAGE265_I31@PURE_QUANTA.TP_TDR_4P_FTS(CHIPS)':
 'P1': CDS_PINID='P1';
NODE_NAME     X25 3
 '@T6G_MB_LIB.T6G(SCH_1):PAGE265_I31@PURE_QUANTA.TP_TDR_4P_FTS(CHIPS)':
 'P2': CDS_PINID='P2';
NODE_NAME     X5 2
 '@T6G_MB_LIB.T6G(SCH_1):PAGE265_I35@PURE_QUANTA.TP_TDR_4P_FTS(CHIPS)':
 'P1': CDS_PINID='P1';
NODE_NAME     X5 3
 '@T6G_MB_LIB.T6G(SCH_1):PAGE265_I35@PURE_QUANTA.TP_TDR_4P_FTS(CHIPS)':
 'P2': CDS_PINID='P2';
NODE_NAME     X4 2
 '@T6G_MB_LIB.T6G(SCH_1):PAGE265_I36@PURE_QUANTA.TP_TDR_4P_FTS(CHIPS)':
 'P1': CDS_PINID='P1';
NODE_NAME     X4 3
 '@T6G_MB_LIB.T6G(SCH_1):PAGE265_I36@PURE_QUANTA.TP_TDR_4P_FTS(CHIPS)':
 'P2': CDS_PINID='P2';
NODE_NAME     X3 2
 '@T6G_MB_LIB.T6G(SCH_1):PAGE265_I37@PURE_QUANTA.TP_TDR_4P_FTS(CHIPS)':
 'P1': CDS_PINID='P1';
NODE_NAME     X3 3
 '@T6G_MB_LIB.T6G(SCH_1):PAGE265_I37@PURE_QUANTA.TP_TDR_4P_FTS(CHIPS)':
 'P2': CDS_PINID='P2';
NODE_NAME     DB10 1
 '@T6G_MB_LIB.T6G(SCH_1):PAGE265_I38@PURE_QUANTA.TDR_3P(CHIPS)':
 'GND': CDS_PINID='GND';
NODE_NAME     DB9 1
 '@T6G_MB_LIB.T6G(SCH_1):PAGE265_I40@PURE_QUANTA.TDR_3P(CHIPS)':
 'GND': CDS_PINID='GND';
NODE_NAME     DB8 1
 '@T6G_MB_LIB.T6G(SCH_1):PAGE265_I42@PURE_QUANTA.TDR_3P(CHIPS)':
 'GND': CDS_PINID='GND';
NODE_NAME     DB7 1
 '@T6G_MB_LIB.T6G(SCH_1):PAGE265_I44@PURE_QUANTA.TDR_3P(CHIPS)':
 'GND': CDS_PINID='GND';
NODE_NAME     X2 2
 '@T6G_MB_LIB.T6G(SCH_1):PAGE265_I47@PURE_QUANTA.TP_TDR_4P_FTS(CHIPS)':
 'P1': CDS_PINID='P1';
NODE_NAME     X2 3
 '@T6G_MB_LIB.T6G(SCH_1):PAGE265_I47@PURE_QUANTA.TP_TDR_4P_FTS(CHIPS)':
 'P2': CDS_PINID='P2';
NODE_NAME     X1 2
 '@T6G_MB_LIB.T6G(SCH_1):PAGE265_I48@PURE_QUANTA.TP_TDR_4P_FTS(CHIPS)':
 'P1': CDS_PINID='P1';
NODE_NAME     X1 3
 '@T6G_MB_LIB.T6G(SCH_1):PAGE265_I48@PURE_QUANTA.TP_TDR_4P_FTS(CHIPS)':
 'P2': CDS_PINID='P2';
NODE_NAME     X12 2
 '@T6G_MB_LIB.T6G(SCH_1):PAGE265_I49@PURE_QUANTA.TP_TDR_4P_FTS(CHIPS)':
 'P1': CDS_PINID='P1';
NODE_NAME     X12 3
 '@T6G_MB_LIB.T6G(SCH_1):PAGE265_I49@PURE_QUANTA.TP_TDR_4P_FTS(CHIPS)':
 'P2': CDS_PINID='P2';
NODE_NAME     X28 2
 '@T6G_MB_LIB.T6G(SCH_1):PAGE265_I52@PURE_QUANTA.TP_TDR_4P_FTS(CHIPS)':
 'P1': CDS_PINID='P1';
NODE_NAME     X28 3
 '@T6G_MB_LIB.T6G(SCH_1):PAGE265_I52@PURE_QUANTA.TP_TDR_4P_FTS(CHIPS)':
 'P2': CDS_PINID='P2';
NODE_NAME     X27 2
 '@T6G_MB_LIB.T6G(SCH_1):PAGE265_I53@PURE_QUANTA.TP_TDR_4P_FTS(CHIPS)':
 'P1': CDS_PINID='P1';
NODE_NAME     X27 3
 '@T6G_MB_LIB.T6G(SCH_1):PAGE265_I53@PURE_QUANTA.TP_TDR_4P_FTS(CHIPS)':
 'P2': CDS_PINID='P2';
NODE_NAME     X8006 2
 '@T6G_MB_LIB.T6G(SCH_1):PAGE265_I56@PURE_QUANTA.TP_TDR_4P_FTS(CHIPS)':
 'P1': CDS_PINID='P1';
NODE_NAME     X8006 3
 '@T6G_MB_LIB.T6G(SCH_1):PAGE265_I56@PURE_QUANTA.TP_TDR_4P_FTS(CHIPS)':
 'P2': CDS_PINID='P2';
NODE_NAME     X8026 2
 '@T6G_MB_LIB.T6G(SCH_1):PAGE265_I58@PURE_QUANTA.TP_TDR_4P_FTS(CHIPS)':
 'P1': CDS_PINID='P1';
NODE_NAME     X8026 3
 '@T6G_MB_LIB.T6G(SCH_1):PAGE265_I58@PURE_QUANTA.TP_TDR_4P_FTS(CHIPS)':
 'P2': CDS_PINID='P2';
NODE_NAME     X8025 2
 '@T6G_MB_LIB.T6G(SCH_1):PAGE265_I60@PURE_QUANTA.TP_TDR_4P_FTS(CHIPS)':
 'P1': CDS_PINID='P1';
NODE_NAME     X8025 3
 '@T6G_MB_LIB.T6G(SCH_1):PAGE265_I60@PURE_QUANTA.TP_TDR_4P_FTS(CHIPS)':
 'P2': CDS_PINID='P2';
NODE_NAME     X10 2
 '@T6G_MB_LIB.T6G(SCH_1):PAGE265_I61@PURE_QUANTA.TP_TDR_4P_FTS(CHIPS)':
 'P1': CDS_PINID='P1';
NODE_NAME     X10 3
 '@T6G_MB_LIB.T6G(SCH_1):PAGE265_I61@PURE_QUANTA.TP_TDR_4P_FTS(CHIPS)':
 'P2': CDS_PINID='P2';
NODE_NAME     X9 2
 '@T6G_MB_LIB.T6G(SCH_1):PAGE265_I62@PURE_QUANTA.TP_TDR_4P_FTS(CHIPS)':
 'P1': CDS_PINID='P1';
NODE_NAME     X9 3
 '@T6G_MB_LIB.T6G(SCH_1):PAGE265_I62@PURE_QUANTA.TP_TDR_4P_FTS(CHIPS)':
 'P2': CDS_PINID='P2';
NODE_NAME     X8005 2
 '@T6G_MB_LIB.T6G(SCH_1):PAGE265_I66@PURE_QUANTA.TP_TDR_4P_FTS(CHIPS)':
 'P1': CDS_PINID='P1';
NODE_NAME     X8005 3
 '@T6G_MB_LIB.T6G(SCH_1):PAGE265_I66@PURE_QUANTA.TP_TDR_4P_FTS(CHIPS)':
 'P2': CDS_PINID='P2';
NODE_NAME     X8004 2
 '@T6G_MB_LIB.T6G(SCH_1):PAGE265_I68@PURE_QUANTA.TP_TDR_4P_FTS(CHIPS)':
 'P1': CDS_PINID='P1';
NODE_NAME     X8004 3
 '@T6G_MB_LIB.T6G(SCH_1):PAGE265_I68@PURE_QUANTA.TP_TDR_4P_FTS(CHIPS)':
 'P2': CDS_PINID='P2';
NODE_NAME     X8003 2
 '@T6G_MB_LIB.T6G(SCH_1):PAGE265_I70@PURE_QUANTA.TP_TDR_4P_FTS(CHIPS)':
 'P1': CDS_PINID='P1';
NODE_NAME     X8003 3
 '@T6G_MB_LIB.T6G(SCH_1):PAGE265_I70@PURE_QUANTA.TP_TDR_4P_FTS(CHIPS)':
 'P2': CDS_PINID='P2';
NODE_NAME     X8028 2
 '@T6G_MB_LIB.T6G(SCH_1):PAGE265_I73@PURE_QUANTA.TP_TDR_4P_FTS(CHIPS)':
 'P1': CDS_PINID='P1';
NODE_NAME     X8028 3
 '@T6G_MB_LIB.T6G(SCH_1):PAGE265_I73@PURE_QUANTA.TP_TDR_4P_FTS(CHIPS)':
 'P2': CDS_PINID='P2';
NODE_NAME     X8027 2
 '@T6G_MB_LIB.T6G(SCH_1):PAGE265_I74@PURE_QUANTA.TP_TDR_4P_FTS(CHIPS)':
 'P1': CDS_PINID='P1';
NODE_NAME     X8027 3
 '@T6G_MB_LIB.T6G(SCH_1):PAGE265_I74@PURE_QUANTA.TP_TDR_4P_FTS(CHIPS)':
 'P2': CDS_PINID='P2';
NODE_NAME     X8011 2
 '@T6G_MB_LIB.T6G(SCH_1):PAGE265_I76@PURE_QUANTA.TP_TDR_4P_FTS(CHIPS)':
 'P1': CDS_PINID='P1';
NODE_NAME     X8011 3
 '@T6G_MB_LIB.T6G(SCH_1):PAGE265_I76@PURE_QUANTA.TP_TDR_4P_FTS(CHIPS)':
 'P2': CDS_PINID='P2';
NODE_NAME     X8010 2
 '@T6G_MB_LIB.T6G(SCH_1):PAGE265_I78@PURE_QUANTA.TP_TDR_4P_FTS(CHIPS)':
 'P1': CDS_PINID='P1';
NODE_NAME     X8010 3
 '@T6G_MB_LIB.T6G(SCH_1):PAGE265_I78@PURE_QUANTA.TP_TDR_4P_FTS(CHIPS)':
 'P2': CDS_PINID='P2';
NODE_NAME     X8009 2
 '@T6G_MB_LIB.T6G(SCH_1):PAGE265_I79@PURE_QUANTA.TP_TDR_4P_FTS(CHIPS)':
 'P1': CDS_PINID='P1';
NODE_NAME     X8009 3
 '@T6G_MB_LIB.T6G(SCH_1):PAGE265_I79@PURE_QUANTA.TP_TDR_4P_FTS(CHIPS)':
 'P2': CDS_PINID='P2';
NODE_NAME     X8 2
 '@T6G_MB_LIB.T6G(SCH_1):PAGE265_I82@PURE_QUANTA.TP_TDR_4P_FTS(CHIPS)':
 'P1': CDS_PINID='P1';
NODE_NAME     X8 3
 '@T6G_MB_LIB.T6G(SCH_1):PAGE265_I82@PURE_QUANTA.TP_TDR_4P_FTS(CHIPS)':
 'P2': CDS_PINID='P2';
NODE_NAME     X7 2
 '@T6G_MB_LIB.T6G(SCH_1):PAGE265_I84@PURE_QUANTA.TP_TDR_4P_FTS(CHIPS)':
 'P1': CDS_PINID='P1';
NODE_NAME     X7 3
 '@T6G_MB_LIB.T6G(SCH_1):PAGE265_I84@PURE_QUANTA.TP_TDR_4P_FTS(CHIPS)':
 'P2': CDS_PINID='P2';
NODE_NAME     X8002 2
 '@T6G_MB_LIB.T6G(SCH_1):PAGE265_I87@PURE_QUANTA.TP_TDR_4P_FTS(CHIPS)':
 'P1': CDS_PINID='P1';
NODE_NAME     X8002 3
 '@T6G_MB_LIB.T6G(SCH_1):PAGE265_I87@PURE_QUANTA.TP_TDR_4P_FTS(CHIPS)':
 'P2': CDS_PINID='P2';
NODE_NAME     X8001 2
 '@T6G_MB_LIB.T6G(SCH_1):PAGE265_I89@PURE_QUANTA.TP_TDR_4P_FTS(CHIPS)':
 'P1': CDS_PINID='P1';
NODE_NAME     X8001 3
 '@T6G_MB_LIB.T6G(SCH_1):PAGE265_I89@PURE_QUANTA.TP_TDR_4P_FTS(CHIPS)':
 'P2': CDS_PINID='P2';
NODE_NAME     X8008 2
 '@T6G_MB_LIB.T6G(SCH_1):PAGE265_I90@PURE_QUANTA.TP_TDR_4P_FTS(CHIPS)':
 'P1': CDS_PINID='P1';
NODE_NAME     X8008 3
 '@T6G_MB_LIB.T6G(SCH_1):PAGE265_I90@PURE_QUANTA.TP_TDR_4P_FTS(CHIPS)':
 'P2': CDS_PINID='P2';
NODE_NAME     X8007 2
 '@T6G_MB_LIB.T6G(SCH_1):PAGE265_I92@PURE_QUANTA.TP_TDR_4P_FTS(CHIPS)':
 'P1': CDS_PINID='P1';
NODE_NAME     X8007 3
 '@T6G_MB_LIB.T6G(SCH_1):PAGE265_I92@PURE_QUANTA.TP_TDR_4P_FTS(CHIPS)':
 'P2': CDS_PINID='P2';
NODE_NAME     X8012 2
 '@T6G_MB_LIB.T6G(SCH_1):PAGE265_I94@PURE_QUANTA.TP_TDR_4P_FTS(CHIPS)':
 'P1': CDS_PINID='P1';
NODE_NAME     X8012 3
 '@T6G_MB_LIB.T6G(SCH_1):PAGE265_I94@PURE_QUANTA.TP_TDR_4P_FTS(CHIPS)':
 'P2': CDS_PINID='P2';
NODE_NAME     X11 2
 '@T6G_MB_LIB.T6G(SCH_1):PAGE265_I96@PURE_QUANTA.TP_TDR_4P_FTS(CHIPS)':
 'P1': CDS_PINID='P1';
NODE_NAME     X11 3
 '@T6G_MB_LIB.T6G(SCH_1):PAGE265_I96@PURE_QUANTA.TP_TDR_4P_FTS(CHIPS)':
 'P2': CDS_PINID='P2';
NODE_NAME     X9026 2
 '@T6G_MB_LIB.T6G(SCH_1):PAGE266_I2@PURE_QUANTA.TP_TDR_4P_FTS(CHIPS)':
 'P1': CDS_PINID='P1';
NODE_NAME     X9026 3
 '@T6G_MB_LIB.T6G(SCH_1):PAGE266_I2@PURE_QUANTA.TP_TDR_4P_FTS(CHIPS)':
 'P2': CDS_PINID='P2';
NODE_NAME     X9025 2
 '@T6G_MB_LIB.T6G(SCH_1):PAGE266_I4@PURE_QUANTA.TP_TDR_4P_FTS(CHIPS)':
 'P1': CDS_PINID='P1';
NODE_NAME     X9025 3
 '@T6G_MB_LIB.T6G(SCH_1):PAGE266_I4@PURE_QUANTA.TP_TDR_4P_FTS(CHIPS)':
 'P2': CDS_PINID='P2';
NODE_NAME     X9005 2
 '@T6G_MB_LIB.T6G(SCH_1):PAGE266_I7@PURE_QUANTA.TP_TDR_4P_FTS(CHIPS)':
 'P1': CDS_PINID='P1';
NODE_NAME     X9005 3
 '@T6G_MB_LIB.T6G(SCH_1):PAGE266_I7@PURE_QUANTA.TP_TDR_4P_FTS(CHIPS)':
 'P2': CDS_PINID='P2';
NODE_NAME     X9004 2
 '@T6G_MB_LIB.T6G(SCH_1):PAGE266_I8@PURE_QUANTA.TP_TDR_4P_FTS(CHIPS)':
 'P1': CDS_PINID='P1';
NODE_NAME     X9004 3
 '@T6G_MB_LIB.T6G(SCH_1):PAGE266_I8@PURE_QUANTA.TP_TDR_4P_FTS(CHIPS)':
 'P2': CDS_PINID='P2';
NODE_NAME     X9003 2
 '@T6G_MB_LIB.T6G(SCH_1):PAGE266_I10@PURE_QUANTA.TP_TDR_4P_FTS(CHIPS)':
 'P1': CDS_PINID='P1';
NODE_NAME     X9003 3
 '@T6G_MB_LIB.T6G(SCH_1):PAGE266_I10@PURE_QUANTA.TP_TDR_4P_FTS(CHIPS)':
 'P2': CDS_PINID='P2';
NODE_NAME     X9002 2
 '@T6G_MB_LIB.T6G(SCH_1):PAGE266_I12@PURE_QUANTA.TP_TDR_4P_FTS(CHIPS)':
 'P1': CDS_PINID='P1';
NODE_NAME     X9002 3
 '@T6G_MB_LIB.T6G(SCH_1):PAGE266_I12@PURE_QUANTA.TP_TDR_4P_FTS(CHIPS)':
 'P2': CDS_PINID='P2';
NODE_NAME     X9028 2
 '@T6G_MB_LIB.T6G(SCH_1):PAGE266_I13@PURE_QUANTA.TP_TDR_4P_FTS(CHIPS)':
 'P1': CDS_PINID='P1';
NODE_NAME     X9028 3
 '@T6G_MB_LIB.T6G(SCH_1):PAGE266_I13@PURE_QUANTA.TP_TDR_4P_FTS(CHIPS)':
 'P2': CDS_PINID='P2';
NODE_NAME     X9027 2
 '@T6G_MB_LIB.T6G(SCH_1):PAGE266_I15@PURE_QUANTA.TP_TDR_4P_FTS(CHIPS)':
 'P1': CDS_PINID='P1';
NODE_NAME     X9027 3
 '@T6G_MB_LIB.T6G(SCH_1):PAGE266_I15@PURE_QUANTA.TP_TDR_4P_FTS(CHIPS)':
 'P2': CDS_PINID='P2';
NODE_NAME     X9010 2
 '@T6G_MB_LIB.T6G(SCH_1):PAGE266_I16@PURE_QUANTA.TP_TDR_4P_FTS(CHIPS)':
 'P1': CDS_PINID='P1';
NODE_NAME     X9010 3
 '@T6G_MB_LIB.T6G(SCH_1):PAGE266_I16@PURE_QUANTA.TP_TDR_4P_FTS(CHIPS)':
 'P2': CDS_PINID='P2';
NODE_NAME     X9011 2
 '@T6G_MB_LIB.T6G(SCH_1):PAGE266_I17@PURE_QUANTA.TP_TDR_4P_FTS(CHIPS)':
 'P1': CDS_PINID='P1';
NODE_NAME     X9011 3
 '@T6G_MB_LIB.T6G(SCH_1):PAGE266_I17@PURE_QUANTA.TP_TDR_4P_FTS(CHIPS)':
 'P2': CDS_PINID='P2';
NODE_NAME     X9009 2
 '@T6G_MB_LIB.T6G(SCH_1):PAGE266_I37@PURE_QUANTA.TP_TDR_4P_FTS(CHIPS)':
 'P1': CDS_PINID='P1';
NODE_NAME     X9009 3
 '@T6G_MB_LIB.T6G(SCH_1):PAGE266_I37@PURE_QUANTA.TP_TDR_4P_FTS(CHIPS)':
 'P2': CDS_PINID='P2';
NODE_NAME     X9008 2
 '@T6G_MB_LIB.T6G(SCH_1):PAGE266_I38@PURE_QUANTA.TP_TDR_4P_FTS(CHIPS)':
 'P1': CDS_PINID='P1';
NODE_NAME     X9008 3
 '@T6G_MB_LIB.T6G(SCH_1):PAGE266_I38@PURE_QUANTA.TP_TDR_4P_FTS(CHIPS)':
 'P2': CDS_PINID='P2';
NET_NAME
'TCA9539_0_ADD0'
 '@T6G_MB_LIB.T6G(SCH_1):TCA9539_0_ADD0':
 C_SIGNAL='@t6g_mb_lib.t6g(sch_1):tca9539_0_add0';
NODE_NAME     R2696 1
 '@T6G_MB_LIB.T6G(SCH_1):PAGE246_I6@PURE_QUANTA.Q_RES(CHIPS)':
 'A': CDS_PINID='A';
NODE_NAME     R2695 2
 '@T6G_MB_LIB.T6G(SCH_1):PAGE246_I7@PURE_QUANTA.Q_RES(CHIPS)':
 'B': CDS_PINID='B';
NODE_NAME     U181 21
 '@T6G_MB_LIB.T6G(SCH_1):PAGE246_I83@PURE_QUANTA.PCA9539RPW(CHIPS)':
 'A0': CDS_PINID='A0';
NET_NAME
'TCA9539_0_ADD1'
 '@T6G_MB_LIB.T6G(SCH_1):TCA9539_0_ADD1':
 C_SIGNAL='@t6g_mb_lib.t6g(sch_1):tca9539_0_add1';
NODE_NAME     R2694 1
 '@T6G_MB_LIB.T6G(SCH_1):PAGE246_I2@PURE_QUANTA.Q_RES(CHIPS)':
 'A': CDS_PINID='A';
NODE_NAME     R2693 2
 '@T6G_MB_LIB.T6G(SCH_1):PAGE246_I3@PURE_QUANTA.Q_RES(CHIPS)':
 'B': CDS_PINID='B';
NODE_NAME     U181 2
 '@T6G_MB_LIB.T6G(SCH_1):PAGE246_I83@PURE_QUANTA.PCA9539RPW(CHIPS)':
 'A1': CDS_PINID='A1';
NET_NAME
'TDR_DIFF_80_BOT_DN'
 '@T6G_MB_LIB.T6G(SCH_1):TDR_DIFF_80_BOT_DN':
 C_SIGNAL='@t6g_mb_lib.t6g(sch_1):tdr_diff_80_bot_dn';
NODE_NAME     X6 4
 '@T6G_MB_LIB.T6G(SCH_1):PAGE265_I29@PURE_QUANTA.TP_TDR_4P_FTS(CHIPS)':
 'S2': CDS_PINID='S2';
NODE_NAME     X12 1
 '@T6G_MB_LIB.T6G(SCH_1):PAGE265_I49@PURE_QUANTA.TP_TDR_4P_FTS(CHIPS)':
 'S1': CDS_PINID='S1';
NET_NAME
'TDR_DIFF_80_BOT_DP'
 '@T6G_MB_LIB.T6G(SCH_1):TDR_DIFF_80_BOT_DP':
 C_SIGNAL='@t6g_mb_lib.t6g(sch_1):tdr_diff_80_bot_dp';
NODE_NAME     X6 1
 '@T6G_MB_LIB.T6G(SCH_1):PAGE265_I29@PURE_QUANTA.TP_TDR_4P_FTS(CHIPS)':
 'S1': CDS_PINID='S1';
NODE_NAME     X12 4
 '@T6G_MB_LIB.T6G(SCH_1):PAGE265_I49@PURE_QUANTA.TP_TDR_4P_FTS(CHIPS)':
 'S2': CDS_PINID='S2';
NET_NAME
'TDR_DIFF_80_IN1_DN'
 '@T6G_MB_LIB.T6G(SCH_1):TDR_DIFF_80_IN1_DN':
 C_SIGNAL='@t6g_mb_lib.t6g(sch_1):tdr_diff_80_in1_dn';
NODE_NAME     X2 4
 '@T6G_MB_LIB.T6G(SCH_1):PAGE265_I47@PURE_QUANTA.TP_TDR_4P_FTS(CHIPS)':
 'S2': CDS_PINID='S2';
NODE_NAME     X8 1
 '@T6G_MB_LIB.T6G(SCH_1):PAGE265_I82@PURE_QUANTA.TP_TDR_4P_FTS(CHIPS)':
 'S1': CDS_PINID='S1';
NET_NAME
'TDR_DIFF_80_IN1_DP'
 '@T6G_MB_LIB.T6G(SCH_1):TDR_DIFF_80_IN1_DP':
 C_SIGNAL='@t6g_mb_lib.t6g(sch_1):tdr_diff_80_in1_dp';
NODE_NAME     X2 1
 '@T6G_MB_LIB.T6G(SCH_1):PAGE265_I47@PURE_QUANTA.TP_TDR_4P_FTS(CHIPS)':
 'S1': CDS_PINID='S1';
NODE_NAME     X8 4
 '@T6G_MB_LIB.T6G(SCH_1):PAGE265_I82@PURE_QUANTA.TP_TDR_4P_FTS(CHIPS)':
 'S2': CDS_PINID='S2';
NET_NAME
'TDR_DIFF_80_IN2_DN'
 '@T6G_MB_LIB.T6G(SCH_1):TDR_DIFF_80_IN2_DN':
 C_SIGNAL='@t6g_mb_lib.t6g(sch_1):tdr_diff_80_in2_dn';
NODE_NAME     X3 4
 '@T6G_MB_LIB.T6G(SCH_1):PAGE265_I37@PURE_QUANTA.TP_TDR_4P_FTS(CHIPS)':
 'S2': CDS_PINID='S2';
NODE_NAME     X9 1
 '@T6G_MB_LIB.T6G(SCH_1):PAGE265_I62@PURE_QUANTA.TP_TDR_4P_FTS(CHIPS)':
 'S1': CDS_PINID='S1';
NET_NAME
'TDR_DIFF_80_IN2_DP'
 '@T6G_MB_LIB.T6G(SCH_1):TDR_DIFF_80_IN2_DP':
 C_SIGNAL='@t6g_mb_lib.t6g(sch_1):tdr_diff_80_in2_dp';
NODE_NAME     X3 1
 '@T6G_MB_LIB.T6G(SCH_1):PAGE265_I37@PURE_QUANTA.TP_TDR_4P_FTS(CHIPS)':
 'S1': CDS_PINID='S1';
NODE_NAME     X9 4
 '@T6G_MB_LIB.T6G(SCH_1):PAGE265_I62@PURE_QUANTA.TP_TDR_4P_FTS(CHIPS)':
 'S2': CDS_PINID='S2';
NET_NAME
'TDR_DIFF_80_IN3_DN'
 '@T6G_MB_LIB.T6G(SCH_1):TDR_DIFF_80_IN3_DN':
 C_SIGNAL='@t6g_mb_lib.t6g(sch_1):tdr_diff_80_in3_dn';
NODE_NAME     X4 4
 '@T6G_MB_LIB.T6G(SCH_1):PAGE265_I36@PURE_QUANTA.TP_TDR_4P_FTS(CHIPS)':
 'S2': CDS_PINID='S2';
NODE_NAME     X10 1
 '@T6G_MB_LIB.T6G(SCH_1):PAGE265_I61@PURE_QUANTA.TP_TDR_4P_FTS(CHIPS)':
 'S1': CDS_PINID='S1';
NET_NAME
'TDR_DIFF_80_IN3_DP'
 '@T6G_MB_LIB.T6G(SCH_1):TDR_DIFF_80_IN3_DP':
 C_SIGNAL='@t6g_mb_lib.t6g(sch_1):tdr_diff_80_in3_dp';
NODE_NAME     X4 1
 '@T6G_MB_LIB.T6G(SCH_1):PAGE265_I36@PURE_QUANTA.TP_TDR_4P_FTS(CHIPS)':
 'S1': CDS_PINID='S1';
NODE_NAME     X10 4
 '@T6G_MB_LIB.T6G(SCH_1):PAGE265_I61@PURE_QUANTA.TP_TDR_4P_FTS(CHIPS)':
 'S2': CDS_PINID='S2';
NET_NAME
'TDR_DIFF_80_IN4_DN'
 '@T6G_MB_LIB.T6G(SCH_1):TDR_DIFF_80_IN4_DN':
 C_SIGNAL='@t6g_mb_lib.t6g(sch_1):tdr_diff_80_in4_dn';
NODE_NAME     X5 4
 '@T6G_MB_LIB.T6G(SCH_1):PAGE265_I35@PURE_QUANTA.TP_TDR_4P_FTS(CHIPS)':
 'S2': CDS_PINID='S2';
NODE_NAME     X11 1
 '@T6G_MB_LIB.T6G(SCH_1):PAGE265_I96@PURE_QUANTA.TP_TDR_4P_FTS(CHIPS)':
 'S1': CDS_PINID='S1';
NET_NAME
'TDR_DIFF_80_IN4_DP'
 '@T6G_MB_LIB.T6G(SCH_1):TDR_DIFF_80_IN4_DP':
 C_SIGNAL='@t6g_mb_lib.t6g(sch_1):tdr_diff_80_in4_dp';
NODE_NAME     X5 1
 '@T6G_MB_LIB.T6G(SCH_1):PAGE265_I35@PURE_QUANTA.TP_TDR_4P_FTS(CHIPS)':
 'S1': CDS_PINID='S1';
NODE_NAME     X11 4
 '@T6G_MB_LIB.T6G(SCH_1):PAGE265_I96@PURE_QUANTA.TP_TDR_4P_FTS(CHIPS)':
 'S2': CDS_PINID='S2';
NET_NAME
'TDR_DIFF_80_IN5_DN'
 '@T6G_MB_LIB.T6G(SCH_1):TDR_DIFF_80_IN5_DN':
 C_SIGNAL='@t6g_mb_lib.t6g(sch_1):tdr_diff_80_in5_dn';
NODE_NAME     X25 4
 '@T6G_MB_LIB.T6G(SCH_1):PAGE265_I31@PURE_QUANTA.TP_TDR_4P_FTS(CHIPS)':
 'S2': CDS_PINID='S2';
NODE_NAME     X27 1
 '@T6G_MB_LIB.T6G(SCH_1):PAGE265_I53@PURE_QUANTA.TP_TDR_4P_FTS(CHIPS)':
 'S1': CDS_PINID='S1';
NET_NAME
'TDR_DIFF_80_IN5_DP'
 '@T6G_MB_LIB.T6G(SCH_1):TDR_DIFF_80_IN5_DP':
 C_SIGNAL='@t6g_mb_lib.t6g(sch_1):tdr_diff_80_in5_dp';
NODE_NAME     X25 1
 '@T6G_MB_LIB.T6G(SCH_1):PAGE265_I31@PURE_QUANTA.TP_TDR_4P_FTS(CHIPS)':
 'S1': CDS_PINID='S1';
NODE_NAME     X27 4
 '@T6G_MB_LIB.T6G(SCH_1):PAGE265_I53@PURE_QUANTA.TP_TDR_4P_FTS(CHIPS)':
 'S2': CDS_PINID='S2';
NET_NAME
'TDR_DIFF_80_IN6_DN'
 '@T6G_MB_LIB.T6G(SCH_1):TDR_DIFF_80_IN6_DN':
 C_SIGNAL='@t6g_mb_lib.t6g(sch_1):tdr_diff_80_in6_dn';
NODE_NAME     X26 4
 '@T6G_MB_LIB.T6G(SCH_1):PAGE265_I30@PURE_QUANTA.TP_TDR_4P_FTS(CHIPS)':
 'S2': CDS_PINID='S2';
NODE_NAME     X28 1
 '@T6G_MB_LIB.T6G(SCH_1):PAGE265_I52@PURE_QUANTA.TP_TDR_4P_FTS(CHIPS)':
 'S1': CDS_PINID='S1';
NET_NAME
'TDR_DIFF_80_IN6_DP'
 '@T6G_MB_LIB.T6G(SCH_1):TDR_DIFF_80_IN6_DP':
 C_SIGNAL='@t6g_mb_lib.t6g(sch_1):tdr_diff_80_in6_dp';
NODE_NAME     X26 1
 '@T6G_MB_LIB.T6G(SCH_1):PAGE265_I30@PURE_QUANTA.TP_TDR_4P_FTS(CHIPS)':
 'S1': CDS_PINID='S1';
NODE_NAME     X28 4
 '@T6G_MB_LIB.T6G(SCH_1):PAGE265_I52@PURE_QUANTA.TP_TDR_4P_FTS(CHIPS)':
 'S2': CDS_PINID='S2';
NET_NAME
'TDR_DIFF_80_TOP_DN'
 '@T6G_MB_LIB.T6G(SCH_1):TDR_DIFF_80_TOP_DN':
 C_SIGNAL='@t6g_mb_lib.t6g(sch_1):tdr_diff_80_top_dn';
NODE_NAME     X1 4
 '@T6G_MB_LIB.T6G(SCH_1):PAGE265_I48@PURE_QUANTA.TP_TDR_4P_FTS(CHIPS)':
 'S2': CDS_PINID='S2';
NODE_NAME     X7 1
 '@T6G_MB_LIB.T6G(SCH_1):PAGE265_I84@PURE_QUANTA.TP_TDR_4P_FTS(CHIPS)':
 'S1': CDS_PINID='S1';
NET_NAME
'TDR_DIFF_80_TOP_DP'
 '@T6G_MB_LIB.T6G(SCH_1):TDR_DIFF_80_TOP_DP':
 C_SIGNAL='@t6g_mb_lib.t6g(sch_1):tdr_diff_80_top_dp';
NODE_NAME     X1 1
 '@T6G_MB_LIB.T6G(SCH_1):PAGE265_I48@PURE_QUANTA.TP_TDR_4P_FTS(CHIPS)':
 'S1': CDS_PINID='S1';
NODE_NAME     X7 4
 '@T6G_MB_LIB.T6G(SCH_1):PAGE265_I84@PURE_QUANTA.TP_TDR_4P_FTS(CHIPS)':
 'S2': CDS_PINID='S2';
NET_NAME
'TDR_DIFF_85_BOT_DN'
 '@T6G_MB_LIB.T6G(SCH_1):TDR_DIFF_85_BOT_DN':
 C_SIGNAL='@t6g_mb_lib.t6g(sch_1):tdr_diff_85_bot_dn';
NODE_NAME     X8006 4
 '@T6G_MB_LIB.T6G(SCH_1):PAGE265_I56@PURE_QUANTA.TP_TDR_4P_FTS(CHIPS)':
 'S2': CDS_PINID='S2';
NODE_NAME     X8012 1
 '@T6G_MB_LIB.T6G(SCH_1):PAGE265_I94@PURE_QUANTA.TP_TDR_4P_FTS(CHIPS)':
 'S1': CDS_PINID='S1';
NET_NAME
'TDR_DIFF_85_BOT_DP'
 '@T6G_MB_LIB.T6G(SCH_1):TDR_DIFF_85_BOT_DP':
 C_SIGNAL='@t6g_mb_lib.t6g(sch_1):tdr_diff_85_bot_dp';
NODE_NAME     X8006 1
 '@T6G_MB_LIB.T6G(SCH_1):PAGE265_I56@PURE_QUANTA.TP_TDR_4P_FTS(CHIPS)':
 'S1': CDS_PINID='S1';
NODE_NAME     X8012 4
 '@T6G_MB_LIB.T6G(SCH_1):PAGE265_I94@PURE_QUANTA.TP_TDR_4P_FTS(CHIPS)':
 'S2': CDS_PINID='S2';
NET_NAME
'TDR_DIFF_85_IN1_DN'
 '@T6G_MB_LIB.T6G(SCH_1):TDR_DIFF_85_IN1_DN':
 C_SIGNAL='@t6g_mb_lib.t6g(sch_1):tdr_diff_85_in1_dn';
NODE_NAME     X8002 4
 '@T6G_MB_LIB.T6G(SCH_1):PAGE265_I87@PURE_QUANTA.TP_TDR_4P_FTS(CHIPS)':
 'S2': CDS_PINID='S2';
NODE_NAME     X8008 1
 '@T6G_MB_LIB.T6G(SCH_1):PAGE265_I90@PURE_QUANTA.TP_TDR_4P_FTS(CHIPS)':
 'S1': CDS_PINID='S1';
NET_NAME
'TDR_DIFF_85_IN1_DP'
 '@T6G_MB_LIB.T6G(SCH_1):TDR_DIFF_85_IN1_DP':
 C_SIGNAL='@t6g_mb_lib.t6g(sch_1):tdr_diff_85_in1_dp';
NODE_NAME     X8002 1
 '@T6G_MB_LIB.T6G(SCH_1):PAGE265_I87@PURE_QUANTA.TP_TDR_4P_FTS(CHIPS)':
 'S1': CDS_PINID='S1';
NODE_NAME     X8008 4
 '@T6G_MB_LIB.T6G(SCH_1):PAGE265_I90@PURE_QUANTA.TP_TDR_4P_FTS(CHIPS)':
 'S2': CDS_PINID='S2';
NET_NAME
'TDR_DIFF_85_IN2_DN'
 '@T6G_MB_LIB.T6G(SCH_1):TDR_DIFF_85_IN2_DN':
 C_SIGNAL='@t6g_mb_lib.t6g(sch_1):tdr_diff_85_in2_dn';
NODE_NAME     X8003 4
 '@T6G_MB_LIB.T6G(SCH_1):PAGE265_I70@PURE_QUANTA.TP_TDR_4P_FTS(CHIPS)':
 'S2': CDS_PINID='S2';
NODE_NAME     X8009 1
 '@T6G_MB_LIB.T6G(SCH_1):PAGE265_I79@PURE_QUANTA.TP_TDR_4P_FTS(CHIPS)':
 'S1': CDS_PINID='S1';
NET_NAME
'TDR_DIFF_85_IN2_DP'
 '@T6G_MB_LIB.T6G(SCH_1):TDR_DIFF_85_IN2_DP':
 C_SIGNAL='@t6g_mb_lib.t6g(sch_1):tdr_diff_85_in2_dp';
NODE_NAME     X8003 1
 '@T6G_MB_LIB.T6G(SCH_1):PAGE265_I70@PURE_QUANTA.TP_TDR_4P_FTS(CHIPS)':
 'S1': CDS_PINID='S1';
NODE_NAME     X8009 4
 '@T6G_MB_LIB.T6G(SCH_1):PAGE265_I79@PURE_QUANTA.TP_TDR_4P_FTS(CHIPS)':
 'S2': CDS_PINID='S2';
NET_NAME
'TDR_DIFF_85_IN3_DN'
 '@T6G_MB_LIB.T6G(SCH_1):TDR_DIFF_85_IN3_DN':
 C_SIGNAL='@t6g_mb_lib.t6g(sch_1):tdr_diff_85_in3_dn';
NODE_NAME     X8004 4
 '@T6G_MB_LIB.T6G(SCH_1):PAGE265_I68@PURE_QUANTA.TP_TDR_4P_FTS(CHIPS)':
 'S2': CDS_PINID='S2';
NODE_NAME     X8010 1
 '@T6G_MB_LIB.T6G(SCH_1):PAGE265_I78@PURE_QUANTA.TP_TDR_4P_FTS(CHIPS)':
 'S1': CDS_PINID='S1';
NET_NAME
'TDR_DIFF_85_IN3_DP'
 '@T6G_MB_LIB.T6G(SCH_1):TDR_DIFF_85_IN3_DP':
 C_SIGNAL='@t6g_mb_lib.t6g(sch_1):tdr_diff_85_in3_dp';
NODE_NAME     X8004 1
 '@T6G_MB_LIB.T6G(SCH_1):PAGE265_I68@PURE_QUANTA.TP_TDR_4P_FTS(CHIPS)':
 'S1': CDS_PINID='S1';
NODE_NAME     X8010 4
 '@T6G_MB_LIB.T6G(SCH_1):PAGE265_I78@PURE_QUANTA.TP_TDR_4P_FTS(CHIPS)':
 'S2': CDS_PINID='S2';
NET_NAME
'TDR_DIFF_85_IN4_DN'
 '@T6G_MB_LIB.T6G(SCH_1):TDR_DIFF_85_IN4_DN':
 C_SIGNAL='@t6g_mb_lib.t6g(sch_1):tdr_diff_85_in4_dn';
NODE_NAME     X8005 4
 '@T6G_MB_LIB.T6G(SCH_1):PAGE265_I66@PURE_QUANTA.TP_TDR_4P_FTS(CHIPS)':
 'S2': CDS_PINID='S2';
NODE_NAME     X8011 1
 '@T6G_MB_LIB.T6G(SCH_1):PAGE265_I76@PURE_QUANTA.TP_TDR_4P_FTS(CHIPS)':
 'S1': CDS_PINID='S1';
NET_NAME
'TDR_DIFF_85_IN4_DP'
 '@T6G_MB_LIB.T6G(SCH_1):TDR_DIFF_85_IN4_DP':
 C_SIGNAL='@t6g_mb_lib.t6g(sch_1):tdr_diff_85_in4_dp';
NODE_NAME     X8005 1
 '@T6G_MB_LIB.T6G(SCH_1):PAGE265_I66@PURE_QUANTA.TP_TDR_4P_FTS(CHIPS)':
 'S1': CDS_PINID='S1';
NODE_NAME     X8011 4
 '@T6G_MB_LIB.T6G(SCH_1):PAGE265_I76@PURE_QUANTA.TP_TDR_4P_FTS(CHIPS)':
 'S2': CDS_PINID='S2';
NET_NAME
'TDR_DIFF_85_IN5_DN'
 '@T6G_MB_LIB.T6G(SCH_1):TDR_DIFF_85_IN5_DN':
 C_SIGNAL='@t6g_mb_lib.t6g(sch_1):tdr_diff_85_in5_dn';
NODE_NAME     X8025 4
 '@T6G_MB_LIB.T6G(SCH_1):PAGE265_I60@PURE_QUANTA.TP_TDR_4P_FTS(CHIPS)':
 'S2': CDS_PINID='S2';
NODE_NAME     X8027 1
 '@T6G_MB_LIB.T6G(SCH_1):PAGE265_I74@PURE_QUANTA.TP_TDR_4P_FTS(CHIPS)':
 'S1': CDS_PINID='S1';
NET_NAME
'TDR_DIFF_85_IN5_DP'
 '@T6G_MB_LIB.T6G(SCH_1):TDR_DIFF_85_IN5_DP':
 C_SIGNAL='@t6g_mb_lib.t6g(sch_1):tdr_diff_85_in5_dp';
NODE_NAME     X8025 1
 '@T6G_MB_LIB.T6G(SCH_1):PAGE265_I60@PURE_QUANTA.TP_TDR_4P_FTS(CHIPS)':
 'S1': CDS_PINID='S1';
NODE_NAME     X8027 4
 '@T6G_MB_LIB.T6G(SCH_1):PAGE265_I74@PURE_QUANTA.TP_TDR_4P_FTS(CHIPS)':
 'S2': CDS_PINID='S2';
NET_NAME
'TDR_DIFF_85_IN6_DN'
 '@T6G_MB_LIB.T6G(SCH_1):TDR_DIFF_85_IN6_DN':
 C_SIGNAL='@t6g_mb_lib.t6g(sch_1):tdr_diff_85_in6_dn';
NODE_NAME     X8026 4
 '@T6G_MB_LIB.T6G(SCH_1):PAGE265_I58@PURE_QUANTA.TP_TDR_4P_FTS(CHIPS)':
 'S2': CDS_PINID='S2';
NODE_NAME     X8028 1
 '@T6G_MB_LIB.T6G(SCH_1):PAGE265_I73@PURE_QUANTA.TP_TDR_4P_FTS(CHIPS)':
 'S1': CDS_PINID='S1';
NET_NAME
'TDR_DIFF_85_IN6_DP'
 '@T6G_MB_LIB.T6G(SCH_1):TDR_DIFF_85_IN6_DP':
 C_SIGNAL='@t6g_mb_lib.t6g(sch_1):tdr_diff_85_in6_dp';
NODE_NAME     X8026 1
 '@T6G_MB_LIB.T6G(SCH_1):PAGE265_I58@PURE_QUANTA.TP_TDR_4P_FTS(CHIPS)':
 'S1': CDS_PINID='S1';
NODE_NAME     X8028 4
 '@T6G_MB_LIB.T6G(SCH_1):PAGE265_I73@PURE_QUANTA.TP_TDR_4P_FTS(CHIPS)':
 'S2': CDS_PINID='S2';
NET_NAME
'TDR_DIFF_85_NECK_IN1_DN'
 '@T6G_MB_LIB.T6G(SCH_1):TDR_DIFF_85_NECK_IN1_DN':
 C_SIGNAL='@t6g_mb_lib.t6g(sch_1):tdr_diff_85_neck_in1_dn';
NODE_NAME     X9002 4
 '@T6G_MB_LIB.T6G(SCH_1):PAGE266_I12@PURE_QUANTA.TP_TDR_4P_FTS(CHIPS)':
 'S2': CDS_PINID='S2';
NODE_NAME     X9008 1
 '@T6G_MB_LIB.T6G(SCH_1):PAGE266_I38@PURE_QUANTA.TP_TDR_4P_FTS(CHIPS)':
 'S1': CDS_PINID='S1';
NET_NAME
'TDR_DIFF_85_NECK_IN1_DP'
 '@T6G_MB_LIB.T6G(SCH_1):TDR_DIFF_85_NECK_IN1_DP':
 C_SIGNAL='@t6g_mb_lib.t6g(sch_1):tdr_diff_85_neck_in1_dp';
NODE_NAME     X9002 1
 '@T6G_MB_LIB.T6G(SCH_1):PAGE266_I12@PURE_QUANTA.TP_TDR_4P_FTS(CHIPS)':
 'S1': CDS_PINID='S1';
NODE_NAME     X9008 4
 '@T6G_MB_LIB.T6G(SCH_1):PAGE266_I38@PURE_QUANTA.TP_TDR_4P_FTS(CHIPS)':
 'S2': CDS_PINID='S2';
NET_NAME
'TDR_DIFF_85_NECK_IN2_DN'
 '@T6G_MB_LIB.T6G(SCH_1):TDR_DIFF_85_NECK_IN2_DN':
 C_SIGNAL='@t6g_mb_lib.t6g(sch_1):tdr_diff_85_neck_in2_dn';
NODE_NAME     X9003 4
 '@T6G_MB_LIB.T6G(SCH_1):PAGE266_I10@PURE_QUANTA.TP_TDR_4P_FTS(CHIPS)':
 'S2': CDS_PINID='S2';
NODE_NAME     X9009 1
 '@T6G_MB_LIB.T6G(SCH_1):PAGE266_I37@PURE_QUANTA.TP_TDR_4P_FTS(CHIPS)':
 'S1': CDS_PINID='S1';
NET_NAME
'TDR_DIFF_85_NECK_IN2_DP'
 '@T6G_MB_LIB.T6G(SCH_1):TDR_DIFF_85_NECK_IN2_DP':
 C_SIGNAL='@t6g_mb_lib.t6g(sch_1):tdr_diff_85_neck_in2_dp';
NODE_NAME     X9003 1
 '@T6G_MB_LIB.T6G(SCH_1):PAGE266_I10@PURE_QUANTA.TP_TDR_4P_FTS(CHIPS)':
 'S1': CDS_PINID='S1';
NODE_NAME     X9009 4
 '@T6G_MB_LIB.T6G(SCH_1):PAGE266_I37@PURE_QUANTA.TP_TDR_4P_FTS(CHIPS)':
 'S2': CDS_PINID='S2';
NET_NAME
'TDR_DIFF_85_NECK_IN3_DN'
 '@T6G_MB_LIB.T6G(SCH_1):TDR_DIFF_85_NECK_IN3_DN':
 C_SIGNAL='@t6g_mb_lib.t6g(sch_1):tdr_diff_85_neck_in3_dn';
NODE_NAME     X9004 4
 '@T6G_MB_LIB.T6G(SCH_1):PAGE266_I8@PURE_QUANTA.TP_TDR_4P_FTS(CHIPS)':
 'S2': CDS_PINID='S2';
NODE_NAME     X9010 1
 '@T6G_MB_LIB.T6G(SCH_1):PAGE266_I16@PURE_QUANTA.TP_TDR_4P_FTS(CHIPS)':
 'S1': CDS_PINID='S1';
NET_NAME
'TDR_DIFF_85_NECK_IN3_DP'
 '@T6G_MB_LIB.T6G(SCH_1):TDR_DIFF_85_NECK_IN3_DP':
 C_SIGNAL='@t6g_mb_lib.t6g(sch_1):tdr_diff_85_neck_in3_dp';
NODE_NAME     X9004 1
 '@T6G_MB_LIB.T6G(SCH_1):PAGE266_I8@PURE_QUANTA.TP_TDR_4P_FTS(CHIPS)':
 'S1': CDS_PINID='S1';
NODE_NAME     X9010 4
 '@T6G_MB_LIB.T6G(SCH_1):PAGE266_I16@PURE_QUANTA.TP_TDR_4P_FTS(CHIPS)':
 'S2': CDS_PINID='S2';
NET_NAME
'TDR_DIFF_85_NECK_IN4_DN'
 '@T6G_MB_LIB.T6G(SCH_1):TDR_DIFF_85_NECK_IN4_DN':
 C_SIGNAL='@t6g_mb_lib.t6g(sch_1):tdr_diff_85_neck_in4_dn';
NODE_NAME     X9005 4
 '@T6G_MB_LIB.T6G(SCH_1):PAGE266_I7@PURE_QUANTA.TP_TDR_4P_FTS(CHIPS)':
 'S2': CDS_PINID='S2';
NODE_NAME     X9011 1
 '@T6G_MB_LIB.T6G(SCH_1):PAGE266_I17@PURE_QUANTA.TP_TDR_4P_FTS(CHIPS)':
 'S1': CDS_PINID='S1';
NET_NAME
'TDR_DIFF_85_NECK_IN4_DP'
 '@T6G_MB_LIB.T6G(SCH_1):TDR_DIFF_85_NECK_IN4_DP':
 C_SIGNAL='@t6g_mb_lib.t6g(sch_1):tdr_diff_85_neck_in4_dp';
NODE_NAME     X9005 1
 '@T6G_MB_LIB.T6G(SCH_1):PAGE266_I7@PURE_QUANTA.TP_TDR_4P_FTS(CHIPS)':
 'S1': CDS_PINID='S1';
NODE_NAME     X9011 4
 '@T6G_MB_LIB.T6G(SCH_1):PAGE266_I17@PURE_QUANTA.TP_TDR_4P_FTS(CHIPS)':
 'S2': CDS_PINID='S2';
NET_NAME
'TDR_DIFF_85_NECK_IN5_DN'
 '@T6G_MB_LIB.T6G(SCH_1):TDR_DIFF_85_NECK_IN5_DN':
 C_SIGNAL='@t6g_mb_lib.t6g(sch_1):tdr_diff_85_neck_in5_dn';
NODE_NAME     X9025 4
 '@T6G_MB_LIB.T6G(SCH_1):PAGE266_I4@PURE_QUANTA.TP_TDR_4P_FTS(CHIPS)':
 'S2': CDS_PINID='S2';
NODE_NAME     X9027 1
 '@T6G_MB_LIB.T6G(SCH_1):PAGE266_I15@PURE_QUANTA.TP_TDR_4P_FTS(CHIPS)':
 'S1': CDS_PINID='S1';
NET_NAME
'TDR_DIFF_85_NECK_IN5_DP'
 '@T6G_MB_LIB.T6G(SCH_1):TDR_DIFF_85_NECK_IN5_DP':
 C_SIGNAL='@t6g_mb_lib.t6g(sch_1):tdr_diff_85_neck_in5_dp';
NODE_NAME     X9025 1
 '@T6G_MB_LIB.T6G(SCH_1):PAGE266_I4@PURE_QUANTA.TP_TDR_4P_FTS(CHIPS)':
 'S1': CDS_PINID='S1';
NODE_NAME     X9027 4
 '@T6G_MB_LIB.T6G(SCH_1):PAGE266_I15@PURE_QUANTA.TP_TDR_4P_FTS(CHIPS)':
 'S2': CDS_PINID='S2';
NET_NAME
'TDR_DIFF_85_NECK_IN6_DN'
 '@T6G_MB_LIB.T6G(SCH_1):TDR_DIFF_85_NECK_IN6_DN':
 C_SIGNAL='@t6g_mb_lib.t6g(sch_1):tdr_diff_85_neck_in6_dn';
NODE_NAME     X9026 4
 '@T6G_MB_LIB.T6G(SCH_1):PAGE266_I2@PURE_QUANTA.TP_TDR_4P_FTS(CHIPS)':
 'S2': CDS_PINID='S2';
NODE_NAME     X9028 1
 '@T6G_MB_LIB.T6G(SCH_1):PAGE266_I13@PURE_QUANTA.TP_TDR_4P_FTS(CHIPS)':
 'S1': CDS_PINID='S1';
NET_NAME
'TDR_DIFF_85_NECK_IN6_DP'
 '@T6G_MB_LIB.T6G(SCH_1):TDR_DIFF_85_NECK_IN6_DP':
 C_SIGNAL='@t6g_mb_lib.t6g(sch_1):tdr_diff_85_neck_in6_dp';
NODE_NAME     X9026 1
 '@T6G_MB_LIB.T6G(SCH_1):PAGE266_I2@PURE_QUANTA.TP_TDR_4P_FTS(CHIPS)':
 'S1': CDS_PINID='S1';
NODE_NAME     X9028 4
 '@T6G_MB_LIB.T6G(SCH_1):PAGE266_I13@PURE_QUANTA.TP_TDR_4P_FTS(CHIPS)':
 'S2': CDS_PINID='S2';
NET_NAME
'TDR_DIFF_85_TOP_DN'
 '@T6G_MB_LIB.T6G(SCH_1):TDR_DIFF_85_TOP_DN':
 C_SIGNAL='@t6g_mb_lib.t6g(sch_1):tdr_diff_85_top_dn';
NODE_NAME     X8001 4
 '@T6G_MB_LIB.T6G(SCH_1):PAGE265_I89@PURE_QUANTA.TP_TDR_4P_FTS(CHIPS)':
 'S2': CDS_PINID='S2';
NODE_NAME     X8007 1
 '@T6G_MB_LIB.T6G(SCH_1):PAGE265_I92@PURE_QUANTA.TP_TDR_4P_FTS(CHIPS)':
 'S1': CDS_PINID='S1';
NET_NAME
'TDR_DIFF_85_TOP_DP'
 '@T6G_MB_LIB.T6G(SCH_1):TDR_DIFF_85_TOP_DP':
 C_SIGNAL='@t6g_mb_lib.t6g(sch_1):tdr_diff_85_top_dp';
NODE_NAME     X8001 1
 '@T6G_MB_LIB.T6G(SCH_1):PAGE265_I89@PURE_QUANTA.TP_TDR_4P_FTS(CHIPS)':
 'S1': CDS_PINID='S1';
NODE_NAME     X8007 4
 '@T6G_MB_LIB.T6G(SCH_1):PAGE265_I92@PURE_QUANTA.TP_TDR_4P_FTS(CHIPS)':
 'S2': CDS_PINID='S2';
NET_NAME
'TDR_SE_45_OHM_BOT'
 '@T6G_MB_LIB.T6G(SCH_1):TDR_SE_45_OHM_BOT':
 C_SIGNAL='@t6g_mb_lib.t6g(sch_1):tdr_se_45_ohm_bot';
NODE_NAME     DB6 2
 '@T6G_MB_LIB.T6G(SCH_1):PAGE265_I2@PURE_QUANTA.TDR_3P(CHIPS)':
 'IO1': CDS_PINID='IO1';
NODE_NAME     DB6 3
 '@T6G_MB_LIB.T6G(SCH_1):PAGE265_I2@PURE_QUANTA.TDR_3P(CHIPS)':
 'IO2': CDS_PINID='IO2';
NET_NAME
'TDR_SE_45_OHM_IN1'
 '@T6G_MB_LIB.T6G(SCH_1):TDR_SE_45_OHM_IN1':
 C_SIGNAL='@t6g_mb_lib.t6g(sch_1):tdr_se_45_ohm_in1';
NODE_NAME     DB2 2
 '@T6G_MB_LIB.T6G(SCH_1):PAGE265_I15@PURE_QUANTA.TDR_3P(CHIPS)':
 'IO1': CDS_PINID='IO1';
NODE_NAME     DB2 3
 '@T6G_MB_LIB.T6G(SCH_1):PAGE265_I15@PURE_QUANTA.TDR_3P(CHIPS)':
 'IO2': CDS_PINID='IO2';
NET_NAME
'TDR_SE_45_OHM_IN2'
 '@T6G_MB_LIB.T6G(SCH_1):TDR_SE_45_OHM_IN2':
 C_SIGNAL='@t6g_mb_lib.t6g(sch_1):tdr_se_45_ohm_in2';
NODE_NAME     DB3 2
 '@T6G_MB_LIB.T6G(SCH_1):PAGE265_I13@PURE_QUANTA.TDR_3P(CHIPS)':
 'IO1': CDS_PINID='IO1';
NODE_NAME     DB3 3
 '@T6G_MB_LIB.T6G(SCH_1):PAGE265_I13@PURE_QUANTA.TDR_3P(CHIPS)':
 'IO2': CDS_PINID='IO2';
NET_NAME
'TDR_SE_45_OHM_IN3'
 '@T6G_MB_LIB.T6G(SCH_1):TDR_SE_45_OHM_IN3':
 C_SIGNAL='@t6g_mb_lib.t6g(sch_1):tdr_se_45_ohm_in3';
NODE_NAME     DB4 2
 '@T6G_MB_LIB.T6G(SCH_1):PAGE265_I12@PURE_QUANTA.TDR_3P(CHIPS)':
 'IO1': CDS_PINID='IO1';
NODE_NAME     DB4 3
 '@T6G_MB_LIB.T6G(SCH_1):PAGE265_I12@PURE_QUANTA.TDR_3P(CHIPS)':
 'IO2': CDS_PINID='IO2';
NET_NAME
'TDR_SE_45_OHM_IN4'
 '@T6G_MB_LIB.T6G(SCH_1):TDR_SE_45_OHM_IN4':
 C_SIGNAL='@t6g_mb_lib.t6g(sch_1):tdr_se_45_ohm_in4';
NODE_NAME     DB5 2
 '@T6G_MB_LIB.T6G(SCH_1):PAGE265_I9@PURE_QUANTA.TDR_3P(CHIPS)':
 'IO1': CDS_PINID='IO1';
NODE_NAME     DB5 3
 '@T6G_MB_LIB.T6G(SCH_1):PAGE265_I9@PURE_QUANTA.TDR_3P(CHIPS)':
 'IO2': CDS_PINID='IO2';
NET_NAME
'TDR_SE_45_OHM_IN5'
 '@T6G_MB_LIB.T6G(SCH_1):TDR_SE_45_OHM_IN5':
 C_SIGNAL='@t6g_mb_lib.t6g(sch_1):tdr_se_45_ohm_in5';
NODE_NAME     DB13 2
 '@T6G_MB_LIB.T6G(SCH_1):PAGE265_I8@PURE_QUANTA.TDR_3P(CHIPS)':
 'IO1': CDS_PINID='IO1';
NODE_NAME     DB13 3
 '@T6G_MB_LIB.T6G(SCH_1):PAGE265_I8@PURE_QUANTA.TDR_3P(CHIPS)':
 'IO2': CDS_PINID='IO2';
NET_NAME
'TDR_SE_45_OHM_IN6'
 '@T6G_MB_LIB.T6G(SCH_1):TDR_SE_45_OHM_IN6':
 C_SIGNAL='@t6g_mb_lib.t6g(sch_1):tdr_se_45_ohm_in6';
NODE_NAME     DB14 2
 '@T6G_MB_LIB.T6G(SCH_1):PAGE265_I5@PURE_QUANTA.TDR_3P(CHIPS)':
 'IO1': CDS_PINID='IO1';
NODE_NAME     DB14 3
 '@T6G_MB_LIB.T6G(SCH_1):PAGE265_I5@PURE_QUANTA.TDR_3P(CHIPS)':
 'IO2': CDS_PINID='IO2';
NET_NAME
'TDR_SE_45_OHM_TOP'
 '@T6G_MB_LIB.T6G(SCH_1):TDR_SE_45_OHM_TOP':
 C_SIGNAL='@t6g_mb_lib.t6g(sch_1):tdr_se_45_ohm_top';
NODE_NAME     DB1 2
 '@T6G_MB_LIB.T6G(SCH_1):PAGE265_I16@PURE_QUANTA.TDR_3P(CHIPS)':
 'IO1': CDS_PINID='IO1';
NODE_NAME     DB1 3
 '@T6G_MB_LIB.T6G(SCH_1):PAGE265_I16@PURE_QUANTA.TDR_3P(CHIPS)':
 'IO2': CDS_PINID='IO2';
NET_NAME
'TDR_SE_50_OHM_BOT'
 '@T6G_MB_LIB.T6G(SCH_1):TDR_SE_50_OHM_BOT':
 C_SIGNAL='@t6g_mb_lib.t6g(sch_1):tdr_se_50_ohm_bot';
NODE_NAME     DB12 2
 '@T6G_MB_LIB.T6G(SCH_1):PAGE265_I18@PURE_QUANTA.TDR_3P(CHIPS)':
 'IO1': CDS_PINID='IO1';
NODE_NAME     DB12 3
 '@T6G_MB_LIB.T6G(SCH_1):PAGE265_I18@PURE_QUANTA.TDR_3P(CHIPS)':
 'IO2': CDS_PINID='IO2';
NET_NAME
'TDR_SE_50_OHM_IN1'
 '@T6G_MB_LIB.T6G(SCH_1):TDR_SE_50_OHM_IN1':
 C_SIGNAL='@t6g_mb_lib.t6g(sch_1):tdr_se_50_ohm_in1';
NODE_NAME     DB8 2
 '@T6G_MB_LIB.T6G(SCH_1):PAGE265_I42@PURE_QUANTA.TDR_3P(CHIPS)':
 'IO1': CDS_PINID='IO1';
NODE_NAME     DB8 3
 '@T6G_MB_LIB.T6G(SCH_1):PAGE265_I42@PURE_QUANTA.TDR_3P(CHIPS)':
 'IO2': CDS_PINID='IO2';
NET_NAME
'TDR_SE_50_OHM_IN2'
 '@T6G_MB_LIB.T6G(SCH_1):TDR_SE_50_OHM_IN2':
 C_SIGNAL='@t6g_mb_lib.t6g(sch_1):tdr_se_50_ohm_in2';
NODE_NAME     DB9 2
 '@T6G_MB_LIB.T6G(SCH_1):PAGE265_I40@PURE_QUANTA.TDR_3P(CHIPS)':
 'IO1': CDS_PINID='IO1';
NODE_NAME     DB9 3
 '@T6G_MB_LIB.T6G(SCH_1):PAGE265_I40@PURE_QUANTA.TDR_3P(CHIPS)':
 'IO2': CDS_PINID='IO2';
NET_NAME
'TDR_SE_50_OHM_IN3'
 '@T6G_MB_LIB.T6G(SCH_1):TDR_SE_50_OHM_IN3':
 C_SIGNAL='@t6g_mb_lib.t6g(sch_1):tdr_se_50_ohm_in3';
NODE_NAME     DB10 2
 '@T6G_MB_LIB.T6G(SCH_1):PAGE265_I38@PURE_QUANTA.TDR_3P(CHIPS)':
 'IO1': CDS_PINID='IO1';
NODE_NAME     DB10 3
 '@T6G_MB_LIB.T6G(SCH_1):PAGE265_I38@PURE_QUANTA.TDR_3P(CHIPS)':
 'IO2': CDS_PINID='IO2';
NET_NAME
'TDR_SE_50_OHM_IN4'
 '@T6G_MB_LIB.T6G(SCH_1):TDR_SE_50_OHM_IN4':
 C_SIGNAL='@t6g_mb_lib.t6g(sch_1):tdr_se_50_ohm_in4';
NODE_NAME     DB11 2
 '@T6G_MB_LIB.T6G(SCH_1):PAGE265_I25@PURE_QUANTA.TDR_3P(CHIPS)':
 'IO1': CDS_PINID='IO1';
NODE_NAME     DB11 3
 '@T6G_MB_LIB.T6G(SCH_1):PAGE265_I25@PURE_QUANTA.TDR_3P(CHIPS)':
 'IO2': CDS_PINID='IO2';
NET_NAME
'TDR_SE_50_OHM_IN5'
 '@T6G_MB_LIB.T6G(SCH_1):TDR_SE_50_OHM_IN5':
 C_SIGNAL='@t6g_mb_lib.t6g(sch_1):tdr_se_50_ohm_in5';
NODE_NAME     DB15 2
 '@T6G_MB_LIB.T6G(SCH_1):PAGE265_I22@PURE_QUANTA.TDR_3P(CHIPS)':
 'IO1': CDS_PINID='IO1';
NODE_NAME     DB15 3
 '@T6G_MB_LIB.T6G(SCH_1):PAGE265_I22@PURE_QUANTA.TDR_3P(CHIPS)':
 'IO2': CDS_PINID='IO2';
NET_NAME
'TDR_SE_50_OHM_IN6'
 '@T6G_MB_LIB.T6G(SCH_1):TDR_SE_50_OHM_IN6':
 C_SIGNAL='@t6g_mb_lib.t6g(sch_1):tdr_se_50_ohm_in6';
NODE_NAME     DB16 2
 '@T6G_MB_LIB.T6G(SCH_1):PAGE265_I20@PURE_QUANTA.TDR_3P(CHIPS)':
 'IO1': CDS_PINID='IO1';
NODE_NAME     DB16 3
 '@T6G_MB_LIB.T6G(SCH_1):PAGE265_I20@PURE_QUANTA.TDR_3P(CHIPS)':
 'IO2': CDS_PINID='IO2';
NET_NAME
'TDR_SE_50_OHM_TOP'
 '@T6G_MB_LIB.T6G(SCH_1):TDR_SE_50_OHM_TOP':
 C_SIGNAL='@t6g_mb_lib.t6g(sch_1):tdr_se_50_ohm_top';
NODE_NAME     DB7 2
 '@T6G_MB_LIB.T6G(SCH_1):PAGE265_I44@PURE_QUANTA.TDR_3P(CHIPS)':
 'IO1': CDS_PINID='IO1';
NODE_NAME     DB7 3
 '@T6G_MB_LIB.T6G(SCH_1):PAGE265_I44@PURE_QUANTA.TDR_3P(CHIPS)':
 'IO2': CDS_PINID='IO2';
NET_NAME
'TEST0_RT_CPU0_P0'
 '@T6G_MB_LIB.T6G(SCH_1):TEST0_RT_CPU0_P0':
 C_SIGNAL='@t6g_mb_lib.t6g(sch_1):test0_rt_cpu0_p0';
NODE_NAME     R982 1
 '@T6G_MB_LIB.T6G(SCH_1):PAGE385_I29@PURE_QUANTA.Q_RES(CHIPS)':
 'A': CDS_PINID='A';
NODE_NAME     R981 2
 '@T6G_MB_LIB.T6G(SCH_1):PAGE385_I31@PURE_QUANTA.Q_RES(CHIPS)':
 'B': CDS_PINID='B';
NODE_NAME     U6010 FF24
 '@T6G_MB_LIB.T6G(SCH_1):PAGE385_I53@PURE_QUANTA.PT5161LRS(CHIPS)':
 'TEST0': CDS_PINID='TEST0';
NET_NAME
'TEST0_RT_CPU0_P1'
 '@T6G_MB_LIB.T6G(SCH_1):TEST0_RT_CPU0_P1':
 C_SIGNAL='@t6g_mb_lib.t6g(sch_1):test0_rt_cpu0_p1';
NODE_NAME     R1031 1
 '@T6G_MB_LIB.T6G(SCH_1):PAGE408_I9@PURE_QUANTA.Q_RES(CHIPS)':
 'A': CDS_PINID='A';
NODE_NAME     R1030 2
 '@T6G_MB_LIB.T6G(SCH_1):PAGE408_I11@PURE_QUANTA.Q_RES(CHIPS)':
 'B': CDS_PINID='B';
NODE_NAME     U6011 FF24
 '@T6G_MB_LIB.T6G(SCH_1):PAGE408_I83@PURE_QUANTA.PT5161LRS(CHIPS)':
 'TEST0': CDS_PINID='TEST0';
NET_NAME
'TEST0_RT_CPU0_P2'
 '@T6G_MB_LIB.T6G(SCH_1):TEST0_RT_CPU0_P2':
 C_SIGNAL='@t6g_mb_lib.t6g(sch_1):test0_rt_cpu0_p2';
NODE_NAME     R1074 1
 '@T6G_MB_LIB.T6G(SCH_1):PAGE419_I9@PURE_QUANTA.Q_RES(CHIPS)':
 'A': CDS_PINID='A';
NODE_NAME     R1073 2
 '@T6G_MB_LIB.T6G(SCH_1):PAGE419_I11@PURE_QUANTA.Q_RES(CHIPS)':
 'B': CDS_PINID='B';
NODE_NAME     U6012 FF24
 '@T6G_MB_LIB.T6G(SCH_1):PAGE419_I83@PURE_QUANTA.PT5161LRS(CHIPS)':
 'TEST0': CDS_PINID='TEST0';
NET_NAME
'TEST0_RT_CPU0_P3'
 '@T6G_MB_LIB.T6G(SCH_1):TEST0_RT_CPU0_P3':
 C_SIGNAL='@t6g_mb_lib.t6g(sch_1):test0_rt_cpu0_p3';
NODE_NAME     R1115 1
 '@T6G_MB_LIB.T6G(SCH_1):PAGE430_I9@PURE_QUANTA.Q_RES(CHIPS)':
 'A': CDS_PINID='A';
NODE_NAME     R1114 2
 '@T6G_MB_LIB.T6G(SCH_1):PAGE430_I11@PURE_QUANTA.Q_RES(CHIPS)':
 'B': CDS_PINID='B';
NODE_NAME     U6013 FF24
 '@T6G_MB_LIB.T6G(SCH_1):PAGE430_I83@PURE_QUANTA.PT5161LRS(CHIPS)':
 'TEST0': CDS_PINID='TEST0';
NET_NAME
'TEST0_RT_CPU1_P0'
 '@T6G_MB_LIB.T6G(SCH_1):TEST0_RT_CPU1_P0':
 C_SIGNAL='@t6g_mb_lib.t6g(sch_1):test0_rt_cpu1_p0';
NODE_NAME     U6014 FF24
 '@T6G_MB_LIB.T6G(SCH_1):PAGE401_I1@PURE_QUANTA.PT5161LRS(CHIPS)':
 'TEST0': CDS_PINID='TEST0';
NODE_NAME     R716 2
 '@T6G_MB_LIB.T6G(SCH_1):PAGE401_I27@PURE_QUANTA.Q_RES(CHIPS)':
 'B': CDS_PINID='B';
NODE_NAME     R719 1
 '@T6G_MB_LIB.T6G(SCH_1):PAGE401_I34@PURE_QUANTA.Q_RES(CHIPS)':
 'A': CDS_PINID='A';
NET_NAME
'TEST0_RT_CPU1_P1'
 '@T6G_MB_LIB.T6G(SCH_1):TEST0_RT_CPU1_P1':
 C_SIGNAL='@t6g_mb_lib.t6g(sch_1):test0_rt_cpu1_p1';
NODE_NAME     R785 1
 '@T6G_MB_LIB.T6G(SCH_1):PAGE392_I23@PURE_QUANTA.Q_RES(CHIPS)':
 'A': CDS_PINID='A';
NODE_NAME     R784 2
 '@T6G_MB_LIB.T6G(SCH_1):PAGE392_I25@PURE_QUANTA.Q_RES(CHIPS)':
 'B': CDS_PINID='B';
NODE_NAME     U6015 FF24
 '@T6G_MB_LIB.T6G(SCH_1):PAGE392_I47@PURE_QUANTA.PT5161LRS(CHIPS)':
 'TEST0': CDS_PINID='TEST0';
NET_NAME
'TEST0_RT_CPU1_P2'
 '@T6G_MB_LIB.T6G(SCH_1):TEST0_RT_CPU1_P2':
 C_SIGNAL='@t6g_mb_lib.t6g(sch_1):test0_rt_cpu1_p2';
NODE_NAME     R879 1
 '@T6G_MB_LIB.T6G(SCH_1):PAGE451_I42@PURE_QUANTA.Q_RES(CHIPS)':
 'A': CDS_PINID='A';
NODE_NAME     R878 2
 '@T6G_MB_LIB.T6G(SCH_1):PAGE451_I47@PURE_QUANTA.Q_RES(CHIPS)':
 'B': CDS_PINID='B';
NODE_NAME     U6016 FF24
 '@T6G_MB_LIB.T6G(SCH_1):PAGE451_I97@PURE_QUANTA.PT5161LRS(CHIPS)':
 'TEST0': CDS_PINID='TEST0';
NET_NAME
'TEST0_RT_CPU1_P3'
 '@T6G_MB_LIB.T6G(SCH_1):TEST0_RT_CPU1_P3':
 C_SIGNAL='@t6g_mb_lib.t6g(sch_1):test0_rt_cpu1_p3';
NODE_NAME     R919 1
 '@T6G_MB_LIB.T6G(SCH_1):PAGE462_I21@PURE_QUANTA.Q_RES(CHIPS)':
 'A': CDS_PINID='A';
NODE_NAME     R918 2
 '@T6G_MB_LIB.T6G(SCH_1):PAGE462_I23@PURE_QUANTA.Q_RES(CHIPS)':
 'B': CDS_PINID='B';
NODE_NAME     U6017 FF24
 '@T6G_MB_LIB.T6G(SCH_1):PAGE462_I97@PURE_QUANTA.PT5161LRS(CHIPS)':
 'TEST0': CDS_PINID='TEST0';
NET_NAME
'TEST1_RT_CPU0_P0'
 '@T6G_MB_LIB.T6G(SCH_1):TEST1_RT_CPU0_P0':
 C_SIGNAL='@t6g_mb_lib.t6g(sch_1):test1_rt_cpu0_p0';
NODE_NAME     U6010 FF27
 '@T6G_MB_LIB.T6G(SCH_1):PAGE385_I53@PURE_QUANTA.PT5161LRS(CHIPS)':
 'TEST1': CDS_PINID='TEST1';
NODE_NAME     R984 1
 '@T6G_MB_LIB.T6G(SCH_1):PAGE385_I57@PURE_QUANTA.Q_RES(CHIPS)':
 'A': CDS_PINID='A';
NODE_NAME     R983 2
 '@T6G_MB_LIB.T6G(SCH_1):PAGE385_I61@PURE_QUANTA.Q_RES(CHIPS)':
 'B': CDS_PINID='B';
NET_NAME
'TEST1_RT_CPU0_P1'
 '@T6G_MB_LIB.T6G(SCH_1):TEST1_RT_CPU0_P1':
 C_SIGNAL='@t6g_mb_lib.t6g(sch_1):test1_rt_cpu0_p1';
NODE_NAME     R1033 1
 '@T6G_MB_LIB.T6G(SCH_1):PAGE408_I36@PURE_QUANTA.Q_RES(CHIPS)':
 'A': CDS_PINID='A';
NODE_NAME     R1032 2
 '@T6G_MB_LIB.T6G(SCH_1):PAGE408_I40@PURE_QUANTA.Q_RES(CHIPS)':
 'B': CDS_PINID='B';
NODE_NAME     U6011 FF27
 '@T6G_MB_LIB.T6G(SCH_1):PAGE408_I83@PURE_QUANTA.PT5161LRS(CHIPS)':
 'TEST1': CDS_PINID='TEST1';
NET_NAME
'TEST1_RT_CPU0_P2'
 '@T6G_MB_LIB.T6G(SCH_1):TEST1_RT_CPU0_P2':
 C_SIGNAL='@t6g_mb_lib.t6g(sch_1):test1_rt_cpu0_p2';
NODE_NAME     R1076 1
 '@T6G_MB_LIB.T6G(SCH_1):PAGE419_I36@PURE_QUANTA.Q_RES(CHIPS)':
 'A': CDS_PINID='A';
NODE_NAME     R1075 2
 '@T6G_MB_LIB.T6G(SCH_1):PAGE419_I40@PURE_QUANTA.Q_RES(CHIPS)':
 'B': CDS_PINID='B';
NODE_NAME     U6012 FF27
 '@T6G_MB_LIB.T6G(SCH_1):PAGE419_I83@PURE_QUANTA.PT5161LRS(CHIPS)':
 'TEST1': CDS_PINID='TEST1';
NET_NAME
'TEST1_RT_CPU0_P3'
 '@T6G_MB_LIB.T6G(SCH_1):TEST1_RT_CPU0_P3':
 C_SIGNAL='@t6g_mb_lib.t6g(sch_1):test1_rt_cpu0_p3';
NODE_NAME     R1118 1
 '@T6G_MB_LIB.T6G(SCH_1):PAGE430_I36@PURE_QUANTA.Q_RES(CHIPS)':
 'A': CDS_PINID='A';
NODE_NAME     R1116 2
 '@T6G_MB_LIB.T6G(SCH_1):PAGE430_I40@PURE_QUANTA.Q_RES(CHIPS)':
 'B': CDS_PINID='B';
NODE_NAME     U6013 FF27
 '@T6G_MB_LIB.T6G(SCH_1):PAGE430_I83@PURE_QUANTA.PT5161LRS(CHIPS)':
 'TEST1': CDS_PINID='TEST1';
NET_NAME
'TEST1_RT_CPU1_P0'
 '@T6G_MB_LIB.T6G(SCH_1):TEST1_RT_CPU1_P0':
 C_SIGNAL='@t6g_mb_lib.t6g(sch_1):test1_rt_cpu1_p0';
NODE_NAME     U6014 FF27
 '@T6G_MB_LIB.T6G(SCH_1):PAGE401_I1@PURE_QUANTA.PT5161LRS(CHIPS)':
 'TEST1': CDS_PINID='TEST1';
NODE_NAME     R720 2
 '@T6G_MB_LIB.T6G(SCH_1):PAGE401_I26@PURE_QUANTA.Q_RES(CHIPS)':
 'B': CDS_PINID='B';
NODE_NAME     R723 1
 '@T6G_MB_LIB.T6G(SCH_1):PAGE401_I33@PURE_QUANTA.Q_RES(CHIPS)':
 'A': CDS_PINID='A';
NET_NAME
'TEST1_RT_CPU1_P1'
 '@T6G_MB_LIB.T6G(SCH_1):TEST1_RT_CPU1_P1':
 C_SIGNAL='@t6g_mb_lib.t6g(sch_1):test1_rt_cpu1_p1';
NODE_NAME     U6015 FF27
 '@T6G_MB_LIB.T6G(SCH_1):PAGE392_I47@PURE_QUANTA.PT5161LRS(CHIPS)':
 'TEST1': CDS_PINID='TEST1';
NODE_NAME     R787 1
 '@T6G_MB_LIB.T6G(SCH_1):PAGE392_I51@PURE_QUANTA.Q_RES(CHIPS)':
 'A': CDS_PINID='A';
NODE_NAME     R786 2
 '@T6G_MB_LIB.T6G(SCH_1):PAGE392_I55@PURE_QUANTA.Q_RES(CHIPS)':
 'B': CDS_PINID='B';
NET_NAME
'TEST1_RT_CPU1_P2'
 '@T6G_MB_LIB.T6G(SCH_1):TEST1_RT_CPU1_P2':
 C_SIGNAL='@t6g_mb_lib.t6g(sch_1):test1_rt_cpu1_p2';
NODE_NAME     R881 1
 '@T6G_MB_LIB.T6G(SCH_1):PAGE451_I43@PURE_QUANTA.Q_RES(CHIPS)':
 'A': CDS_PINID='A';
NODE_NAME     R880 2
 '@T6G_MB_LIB.T6G(SCH_1):PAGE451_I48@PURE_QUANTA.Q_RES(CHIPS)':
 'B': CDS_PINID='B';
NODE_NAME     U6016 FF27
 '@T6G_MB_LIB.T6G(SCH_1):PAGE451_I97@PURE_QUANTA.PT5161LRS(CHIPS)':
 'TEST1': CDS_PINID='TEST1';
NET_NAME
'TEST1_RT_CPU1_P3'
 '@T6G_MB_LIB.T6G(SCH_1):TEST1_RT_CPU1_P3':
 C_SIGNAL='@t6g_mb_lib.t6g(sch_1):test1_rt_cpu1_p3';
NODE_NAME     R921 1
 '@T6G_MB_LIB.T6G(SCH_1):PAGE462_I50@PURE_QUANTA.Q_RES(CHIPS)':
 'A': CDS_PINID='A';
NODE_NAME     R920 2
 '@T6G_MB_LIB.T6G(SCH_1):PAGE462_I54@PURE_QUANTA.Q_RES(CHIPS)':
 'B': CDS_PINID='B';
NODE_NAME     U6017 FF27
 '@T6G_MB_LIB.T6G(SCH_1):PAGE462_I97@PURE_QUANTA.PT5161LRS(CHIPS)':
 'TEST1': CDS_PINID='TEST1';
NET_NAME
'TEST2_RT_CPU0_P0'
 '@T6G_MB_LIB.T6G(SCH_1):TEST2_RT_CPU0_P0':
 C_SIGNAL='@t6g_mb_lib.t6g(sch_1):test2_rt_cpu0_p0';
NODE_NAME     U6010 FF30
 '@T6G_MB_LIB.T6G(SCH_1):PAGE385_I53@PURE_QUANTA.PT5161LRS(CHIPS)':
 'TEST2': CDS_PINID='TEST2';
NODE_NAME     R995 1
 '@T6G_MB_LIB.T6G(SCH_1):PAGE385_I58@PURE_QUANTA.Q_RES(CHIPS)':
 'A': CDS_PINID='A';
NODE_NAME     R985 2
 '@T6G_MB_LIB.T6G(SCH_1):PAGE385_I62@PURE_QUANTA.Q_RES(CHIPS)':
 'B': CDS_PINID='B';
NET_NAME
'TEST2_RT_CPU0_P1'
 '@T6G_MB_LIB.T6G(SCH_1):TEST2_RT_CPU0_P1':
 C_SIGNAL='@t6g_mb_lib.t6g(sch_1):test2_rt_cpu0_p1';
NODE_NAME     R1035 1
 '@T6G_MB_LIB.T6G(SCH_1):PAGE408_I37@PURE_QUANTA.Q_RES(CHIPS)':
 'A': CDS_PINID='A';
NODE_NAME     R1034 2
 '@T6G_MB_LIB.T6G(SCH_1):PAGE408_I41@PURE_QUANTA.Q_RES(CHIPS)':
 'B': CDS_PINID='B';
NODE_NAME     U6011 FF30
 '@T6G_MB_LIB.T6G(SCH_1):PAGE408_I83@PURE_QUANTA.PT5161LRS(CHIPS)':
 'TEST2': CDS_PINID='TEST2';
NET_NAME
'TEST2_RT_CPU0_P2'
 '@T6G_MB_LIB.T6G(SCH_1):TEST2_RT_CPU0_P2':
 C_SIGNAL='@t6g_mb_lib.t6g(sch_1):test2_rt_cpu0_p2';
NODE_NAME     R1078 1
 '@T6G_MB_LIB.T6G(SCH_1):PAGE419_I37@PURE_QUANTA.Q_RES(CHIPS)':
 'A': CDS_PINID='A';
NODE_NAME     R1077 2
 '@T6G_MB_LIB.T6G(SCH_1):PAGE419_I41@PURE_QUANTA.Q_RES(CHIPS)':
 'B': CDS_PINID='B';
NODE_NAME     U6012 FF30
 '@T6G_MB_LIB.T6G(SCH_1):PAGE419_I83@PURE_QUANTA.PT5161LRS(CHIPS)':
 'TEST2': CDS_PINID='TEST2';
NET_NAME
'TEST2_RT_CPU0_P3'
 '@T6G_MB_LIB.T6G(SCH_1):TEST2_RT_CPU0_P3':
 C_SIGNAL='@t6g_mb_lib.t6g(sch_1):test2_rt_cpu0_p3';
NODE_NAME     R1120 1
 '@T6G_MB_LIB.T6G(SCH_1):PAGE430_I37@PURE_QUANTA.Q_RES(CHIPS)':
 'A': CDS_PINID='A';
NODE_NAME     R1119 2
 '@T6G_MB_LIB.T6G(SCH_1):PAGE430_I41@PURE_QUANTA.Q_RES(CHIPS)':
 'B': CDS_PINID='B';
NODE_NAME     U6013 FF30
 '@T6G_MB_LIB.T6G(SCH_1):PAGE430_I83@PURE_QUANTA.PT5161LRS(CHIPS)':
 'TEST2': CDS_PINID='TEST2';
NET_NAME
'TEST2_RT_CPU1_P0'
 '@T6G_MB_LIB.T6G(SCH_1):TEST2_RT_CPU1_P0':
 C_SIGNAL='@t6g_mb_lib.t6g(sch_1):test2_rt_cpu1_p0';
NODE_NAME     U6014 FF30
 '@T6G_MB_LIB.T6G(SCH_1):PAGE401_I1@PURE_QUANTA.PT5161LRS(CHIPS)':
 'TEST2': CDS_PINID='TEST2';
NODE_NAME     R724 2
 '@T6G_MB_LIB.T6G(SCH_1):PAGE401_I25@PURE_QUANTA.Q_RES(CHIPS)':
 'B': CDS_PINID='B';
NODE_NAME     R725 1
 '@T6G_MB_LIB.T6G(SCH_1):PAGE401_I32@PURE_QUANTA.Q_RES(CHIPS)':
 'A': CDS_PINID='A';
NET_NAME
'TEST2_RT_CPU1_P1'
 '@T6G_MB_LIB.T6G(SCH_1):TEST2_RT_CPU1_P1':
 C_SIGNAL='@t6g_mb_lib.t6g(sch_1):test2_rt_cpu1_p1';
NODE_NAME     U6015 FF30
 '@T6G_MB_LIB.T6G(SCH_1):PAGE392_I47@PURE_QUANTA.PT5161LRS(CHIPS)':
 'TEST2': CDS_PINID='TEST2';
NODE_NAME     R791 1
 '@T6G_MB_LIB.T6G(SCH_1):PAGE392_I52@PURE_QUANTA.Q_RES(CHIPS)':
 'A': CDS_PINID='A';
NODE_NAME     R788 2
 '@T6G_MB_LIB.T6G(SCH_1):PAGE392_I56@PURE_QUANTA.Q_RES(CHIPS)':
 'B': CDS_PINID='B';
NET_NAME
'TEST2_RT_CPU1_P2'
 '@T6G_MB_LIB.T6G(SCH_1):TEST2_RT_CPU1_P2':
 C_SIGNAL='@t6g_mb_lib.t6g(sch_1):test2_rt_cpu1_p2';
NODE_NAME     R883 1
 '@T6G_MB_LIB.T6G(SCH_1):PAGE451_I45@PURE_QUANTA.Q_RES(CHIPS)':
 'A': CDS_PINID='A';
NODE_NAME     R882 2
 '@T6G_MB_LIB.T6G(SCH_1):PAGE451_I49@PURE_QUANTA.Q_RES(CHIPS)':
 'B': CDS_PINID='B';
NODE_NAME     U6016 FF30
 '@T6G_MB_LIB.T6G(SCH_1):PAGE451_I97@PURE_QUANTA.PT5161LRS(CHIPS)':
 'TEST2': CDS_PINID='TEST2';
NET_NAME
'TEST2_RT_CPU1_P3'
 '@T6G_MB_LIB.T6G(SCH_1):TEST2_RT_CPU1_P3':
 C_SIGNAL='@t6g_mb_lib.t6g(sch_1):test2_rt_cpu1_p3';
NODE_NAME     R923 1
 '@T6G_MB_LIB.T6G(SCH_1):PAGE462_I51@PURE_QUANTA.Q_RES(CHIPS)':
 'A': CDS_PINID='A';
NODE_NAME     R922 2
 '@T6G_MB_LIB.T6G(SCH_1):PAGE462_I55@PURE_QUANTA.Q_RES(CHIPS)':
 'B': CDS_PINID='B';
NODE_NAME     U6017 FF30
 '@T6G_MB_LIB.T6G(SCH_1):PAGE462_I97@PURE_QUANTA.PT5161LRS(CHIPS)':
 'TEST2': CDS_PINID='TEST2';
NET_NAME
'TP_ADC128_2_INT'
 '@T6G_MB_LIB.T6G(SCH_1):TP_ADC128_2_INT':
 C_SIGNAL='@t6g_mb_lib.t6g(sch_1):tp_adc128_2_int';
NODE_NAME     U51 6
 '@T6G_MB_LIB.T6G(SCH_1):PAGE263_I142@PURE_QUANTA.ADC128D818CIMTXNOPB(CHIPS)':
 'INT#': CDS_PINID='\int#\';
NET_NAME
'TP_ADC128_INT'
 '@T6G_MB_LIB.T6G(SCH_1):TP_ADC128_INT':
 C_SIGNAL='@t6g_mb_lib.t6g(sch_1):tp_adc128_int';
NODE_NAME     U269 6
 '@T6G_MB_LIB.T6G(SCH_1):PAGE369_I142@PURE_QUANTA.ADC128D818CIMTXNOPB(CHIPS)':
 'INT#': CDS_PINID='\int#\';
NET_NAME
'TP_BEEP_LED'
 '@T6G_MB_LIB.T6G(SCH_1):TP_BEEP_LED':
 C_SIGNAL='@t6g_mb_lib.t6g(sch_1):tp_beep_led';
NODE_NAME     J41 B69
 '@T6G_MB_LIB.T6G(SCH_1):PAGE348_I176@PURE_QUANTA.SCONN168_ME1016810202011(CHIPS)':
 'RFU1_NC_B69': CDS_PINID='RFU1_NC_B69';
NET_NAME
'TP_CHASI'
 '@T6G_MB_LIB.T6G(SCH_1):TP_CHASI':
 C_SIGNAL='@t6g_mb_lib.t6g(sch_1):tp_chasi';
NODE_NAME     J41 A54
 '@T6G_MB_LIB.T6G(SCH_1):PAGE348_I176@PURE_QUANTA.SCONN168_ME1016810202011(CHIPS)':
 'PERP11': CDS_PINID='PERP11';
NODE_NAME     R4809 1
 '@T6G_MB_LIB.T6G(SCH_1):PAGE348_I220@PURE_QUANTA.Q_RES(CHIPS)':
 'A': CDS_PINID='A';
NET_NAME
'TP_CLK_100M_E1S_0_DN'
 '@T6G_MB_LIB.T6G(SCH_1):TP_CLK_100M_E1S_0_DN':
 C_SIGNAL='@t6g_mb_lib.t6g(sch_1):tp_clk_100m_e1s_0_dn';
NODE_NAME     J90 A14
 '@T6G_MB_LIB.T6G(SCH_1):PAGE297_I90@PURE_QUANTA.SCONN56_123276793(CHIPS)':
 'REFCLK_N1': CDS_PINID='REFCLK_N1';
NET_NAME
'TP_CLK_100M_E1S_0_DP'
 '@T6G_MB_LIB.T6G(SCH_1):TP_CLK_100M_E1S_0_DP':
 C_SIGNAL='@t6g_mb_lib.t6g(sch_1):tp_clk_100m_e1s_0_dp';
NODE_NAME     J90 A15
 '@T6G_MB_LIB.T6G(SCH_1):PAGE297_I90@PURE_QUANTA.SCONN56_123276793(CHIPS)':
 'REFCLK_P1': CDS_PINID='REFCLK_P1';
NET_NAME
'TP_CLK_50M_Y3'
 '@T6G_MB_LIB.T6G(SCH_1):TP_CLK_50M_Y3':
 C_SIGNAL='@t6g_mb_lib.t6g(sch_1):tp_clk_50m_y3';
NODE_NAME     U90 8
 '@T6G_MB_LIB.T6G(SCH_1):PAGE337_I16@PURE_QUANTA.PI6CV304LE(CHIPS)':
 'Y3': CDS_PINID='Y3';
NET_NAME
'TP_CPU0_TEST41_IDO'
 '@T6G_MB_LIB.T6G(SCH_1):TP_CPU0_TEST41_IDO':
 C_SIGNAL='@t6g_mb_lib.t6g(sch_1):tp_cpu0_test41_ido';
NODE_NAME     U25 W31
 '@T6G_MB_LIB.T6G(SCH_1):PAGE27_I227@PURE_QUANTA.GENOA_SP5(CHIPS)':
 'TEST41_IOD': CDS_PINID='TEST41_IOD';
NET_NAME
'TP_CPU0_TEST47_CCD0'
 '@T6G_MB_LIB.T6G(SCH_1):TP_CPU0_TEST47_CCD0':
 C_SIGNAL='@t6g_mb_lib.t6g(sch_1):tp_cpu0_test47_ccd0';
NODE_NAME     U25 B60
 '@T6G_MB_LIB.T6G(SCH_1):PAGE27_I227@PURE_QUANTA.GENOA_SP5(CHIPS)':
 'TEST47_CCD0': CDS_PINID='TEST47_CCD0';
NET_NAME
'TP_CPU0_TEST47_CCD1'
 '@T6G_MB_LIB.T6G(SCH_1):TP_CPU0_TEST47_CCD1':
 C_SIGNAL='@t6g_mb_lib.t6g(sch_1):tp_cpu0_test47_ccd1';
NODE_NAME     U25 CJ24
 '@T6G_MB_LIB.T6G(SCH_1):PAGE27_I227@PURE_QUANTA.GENOA_SP5(CHIPS)':
 'TEST47_CCD1': CDS_PINID='TEST47_CCD1';
NET_NAME
'TP_CPU0_TEST47_CCD2'
 '@T6G_MB_LIB.T6G(SCH_1):TP_CPU0_TEST47_CCD2':
 C_SIGNAL='@t6g_mb_lib.t6g(sch_1):tp_cpu0_test47_ccd2';
NODE_NAME     U25 CK46
 '@T6G_MB_LIB.T6G(SCH_1):PAGE27_I227@PURE_QUANTA.GENOA_SP5(CHIPS)':
 'TEST47_CCD2': CDS_PINID='TEST47_CCD2';
NET_NAME
'TP_CPU0_TEST47_CCD3'
 '@T6G_MB_LIB.T6G(SCH_1):TP_CPU0_TEST47_CCD3':
 C_SIGNAL='@t6g_mb_lib.t6g(sch_1):tp_cpu0_test47_ccd3';
NODE_NAME     U25 E32
 '@T6G_MB_LIB.T6G(SCH_1):PAGE27_I227@PURE_QUANTA.GENOA_SP5(CHIPS)':
 'TEST47_CCD3': CDS_PINID='TEST47_CCD3';
NET_NAME
'TP_CPU0_TEST47_IOD0'
 '@T6G_MB_LIB.T6G(SCH_1):TP_CPU0_TEST47_IOD0':
 C_SIGNAL='@t6g_mb_lib.t6g(sch_1):tp_cpu0_test47_iod0';
NODE_NAME     U25 B58
 '@T6G_MB_LIB.T6G(SCH_1):PAGE27_I227@PURE_QUANTA.GENOA_SP5(CHIPS)':
 'TEST47_IOD0': CDS_PINID='TEST47_IOD0';
NET_NAME
'TP_CPU0_TEST47_IOD1'
 '@T6G_MB_LIB.T6G(SCH_1):TP_CPU0_TEST47_IOD1':
 C_SIGNAL='@t6g_mb_lib.t6g(sch_1):tp_cpu0_test47_iod1';
NODE_NAME     U25 D7
 '@T6G_MB_LIB.T6G(SCH_1):PAGE27_I227@PURE_QUANTA.GENOA_SP5(CHIPS)':
 'TEST47_IOD1': CDS_PINID='TEST47_IOD1';
NET_NAME
'TP_CPU0_TEST4_CCD0'
 '@T6G_MB_LIB.T6G(SCH_1):TP_CPU0_TEST4_CCD0':
 C_SIGNAL='@t6g_mb_lib.t6g(sch_1):tp_cpu0_test4_ccd0';
NODE_NAME     U25 AA50
 '@T6G_MB_LIB.T6G(SCH_1):PAGE27_I227@PURE_QUANTA.GENOA_SP5(CHIPS)':
 'TEST4_CCD0': CDS_PINID='TEST4_CCD0';
NET_NAME
'TP_CPU0_TEST4_CCD1'
 '@T6G_MB_LIB.T6G(SCH_1):TP_CPU0_TEST4_CCD1':
 C_SIGNAL='@t6g_mb_lib.t6g(sch_1):tp_cpu0_test4_ccd1';
NODE_NAME     U25 CJ28
 '@T6G_MB_LIB.T6G(SCH_1):PAGE27_I227@PURE_QUANTA.GENOA_SP5(CHIPS)':
 'TEST4_CCD1': CDS_PINID='TEST4_CCD1';
NET_NAME
'TP_CPU0_TEST4_CCD10'
 '@T6G_MB_LIB.T6G(SCH_1):TP_CPU0_TEST4_CCD10':
 C_SIGNAL='@t6g_mb_lib.t6g(sch_1):tp_cpu0_test4_ccd10';
NODE_NAME     U25 CJ47
 '@T6G_MB_LIB.T6G(SCH_1):PAGE27_I227@PURE_QUANTA.GENOA_SP5(CHIPS)':
 'TEST4_CCD10': CDS_PINID='TEST4_CCD10';
NET_NAME
'TP_CPU0_TEST4_CCD11'
 '@T6G_MB_LIB.T6G(SCH_1):TP_CPU0_TEST4_CCD11':
 C_SIGNAL='@t6g_mb_lib.t6g(sch_1):tp_cpu0_test4_ccd11';
NODE_NAME     U25 AA28
 '@T6G_MB_LIB.T6G(SCH_1):PAGE27_I227@PURE_QUANTA.GENOA_SP5(CHIPS)':
 'TEST4_CCD11': CDS_PINID='TEST4_CCD11';
NET_NAME
'TP_CPU0_TEST4_CCD2'
 '@T6G_MB_LIB.T6G(SCH_1):TP_CPU0_TEST4_CCD2':
 C_SIGNAL='@t6g_mb_lib.t6g(sch_1):tp_cpu0_test4_ccd2';
NODE_NAME     U25 CJ48
 '@T6G_MB_LIB.T6G(SCH_1):PAGE27_I227@PURE_QUANTA.GENOA_SP5(CHIPS)':
 'TEST4_CCD2': CDS_PINID='TEST4_CCD2';
NET_NAME
'TP_CPU0_TEST4_CCD3'
 '@T6G_MB_LIB.T6G(SCH_1):TP_CPU0_TEST4_CCD3':
 C_SIGNAL='@t6g_mb_lib.t6g(sch_1):tp_cpu0_test4_ccd3';
NODE_NAME     U25 AA30
 '@T6G_MB_LIB.T6G(SCH_1):PAGE27_I227@PURE_QUANTA.GENOA_SP5(CHIPS)':
 'TEST4_CCD3': CDS_PINID='TEST4_CCD3';
NET_NAME
'TP_CPU0_TEST4_CCD4'
 '@T6G_MB_LIB.T6G(SCH_1):TP_CPU0_TEST4_CCD4':
 C_SIGNAL='@t6g_mb_lib.t6g(sch_1):tp_cpu0_test4_ccd4';
NODE_NAME     U25 AA52
 '@T6G_MB_LIB.T6G(SCH_1):PAGE27_I227@PURE_QUANTA.GENOA_SP5(CHIPS)':
 'TEST4_CCD4': CDS_PINID='TEST4_CCD4';
NET_NAME
'TP_CPU0_TEST4_CCD5'
 '@T6G_MB_LIB.T6G(SCH_1):TP_CPU0_TEST4_CCD5':
 C_SIGNAL='@t6g_mb_lib.t6g(sch_1):tp_cpu0_test4_ccd5';
NODE_NAME     U25 CJ26
 '@T6G_MB_LIB.T6G(SCH_1):PAGE27_I227@PURE_QUANTA.GENOA_SP5(CHIPS)':
 'TEST4_CCD5': CDS_PINID='TEST4_CCD5';
NET_NAME
'TP_CPU0_TEST4_CCD6'
 '@T6G_MB_LIB.T6G(SCH_1):TP_CPU0_TEST4_CCD6':
 C_SIGNAL='@t6g_mb_lib.t6g(sch_1):tp_cpu0_test4_ccd6';
NODE_NAME     U25 CJ50
 '@T6G_MB_LIB.T6G(SCH_1):PAGE27_I227@PURE_QUANTA.GENOA_SP5(CHIPS)':
 'TEST4_CCD6': CDS_PINID='TEST4_CCD6';
NET_NAME
'TP_CPU0_TEST4_CCD7'
 '@T6G_MB_LIB.T6G(SCH_1):TP_CPU0_TEST4_CCD7':
 C_SIGNAL='@t6g_mb_lib.t6g(sch_1):tp_cpu0_test4_ccd7';
NODE_NAME     U25 AA27
 '@T6G_MB_LIB.T6G(SCH_1):PAGE27_I227@PURE_QUANTA.GENOA_SP5(CHIPS)':
 'TEST4_CCD7': CDS_PINID='TEST4_CCD7';
NET_NAME
'TP_CPU0_TEST4_CCD8'
 '@T6G_MB_LIB.T6G(SCH_1):TP_CPU0_TEST4_CCD8':
 C_SIGNAL='@t6g_mb_lib.t6g(sch_1):tp_cpu0_test4_ccd8';
NODE_NAME     U25 AA48
 '@T6G_MB_LIB.T6G(SCH_1):PAGE27_I227@PURE_QUANTA.GENOA_SP5(CHIPS)':
 'TEST4_CCD8': CDS_PINID='TEST4_CCD8';
NET_NAME
'TP_CPU0_TEST4_CCD9'
 '@T6G_MB_LIB.T6G(SCH_1):TP_CPU0_TEST4_CCD9':
 C_SIGNAL='@t6g_mb_lib.t6g(sch_1):tp_cpu0_test4_ccd9';
NODE_NAME     U25 CK30
 '@T6G_MB_LIB.T6G(SCH_1):PAGE27_I227@PURE_QUANTA.GENOA_SP5(CHIPS)':
 'TEST4_CCD9': CDS_PINID='TEST4_CCD9';
NET_NAME
'TP_CPU0_TEST4_IOD'
 '@T6G_MB_LIB.T6G(SCH_1):TP_CPU0_TEST4_IOD':
 C_SIGNAL='@t6g_mb_lib.t6g(sch_1):tp_cpu0_test4_iod';
NODE_NAME     U25 AA25
 '@T6G_MB_LIB.T6G(SCH_1):PAGE27_I227@PURE_QUANTA.GENOA_SP5(CHIPS)':
 'TEST4_IOD': CDS_PINID='TEST4_IOD';
NET_NAME
'TP_CPU0_TEST50_IOD'
 '@T6G_MB_LIB.T6G(SCH_1):TP_CPU0_TEST50_IOD':
 C_SIGNAL='@t6g_mb_lib.t6g(sch_1):tp_cpu0_test50_iod';
NODE_NAME     U25 B61
 '@T6G_MB_LIB.T6G(SCH_1):PAGE27_I227@PURE_QUANTA.GENOA_SP5(CHIPS)':
 'TEST50_IOD': CDS_PINID='TEST50_IOD';
NET_NAME
'TP_CPU0_TEST5_CCD0'
 '@T6G_MB_LIB.T6G(SCH_1):TP_CPU0_TEST5_CCD0':
 C_SIGNAL='@t6g_mb_lib.t6g(sch_1):tp_cpu0_test5_ccd0';
NODE_NAME     U25 AA51
 '@T6G_MB_LIB.T6G(SCH_1):PAGE27_I227@PURE_QUANTA.GENOA_SP5(CHIPS)':
 'TEST5_CCD0': CDS_PINID='TEST5_CCD0';
NET_NAME
'TP_CPU0_TEST5_CCD1'
 '@T6G_MB_LIB.T6G(SCH_1):TP_CPU0_TEST5_CCD1':
 C_SIGNAL='@t6g_mb_lib.t6g(sch_1):tp_cpu0_test5_ccd1';
NODE_NAME     U25 CJ27
 '@T6G_MB_LIB.T6G(SCH_1):PAGE27_I227@PURE_QUANTA.GENOA_SP5(CHIPS)':
 'TEST5_CCD1': CDS_PINID='TEST5_CCD1';
NET_NAME
'TP_CPU0_TEST5_CCD10'
 '@T6G_MB_LIB.T6G(SCH_1):TP_CPU0_TEST5_CCD10':
 C_SIGNAL='@t6g_mb_lib.t6g(sch_1):tp_cpu0_test5_ccd10';
NODE_NAME     U25 CK47
 '@T6G_MB_LIB.T6G(SCH_1):PAGE27_I227@PURE_QUANTA.GENOA_SP5(CHIPS)':
 'TEST5_CCD10': CDS_PINID='TEST5_CCD10';
NET_NAME
'TP_CPU0_TEST5_CCD11'
 '@T6G_MB_LIB.T6G(SCH_1):TP_CPU0_TEST5_CCD11':
 C_SIGNAL='@t6g_mb_lib.t6g(sch_1):tp_cpu0_test5_ccd11';
NODE_NAME     U25 Y29
 '@T6G_MB_LIB.T6G(SCH_1):PAGE27_I227@PURE_QUANTA.GENOA_SP5(CHIPS)':
 'TEST5_CCD11': CDS_PINID='TEST5_CCD11';
NET_NAME
'TP_CPU0_TEST5_CCD2'
 '@T6G_MB_LIB.T6G(SCH_1):TP_CPU0_TEST5_CCD2':
 C_SIGNAL='@t6g_mb_lib.t6g(sch_1):tp_cpu0_test5_ccd2';
NODE_NAME     U25 CJ49
 '@T6G_MB_LIB.T6G(SCH_1):PAGE27_I227@PURE_QUANTA.GENOA_SP5(CHIPS)':
 'TEST5_CCD2': CDS_PINID='TEST5_CCD2';
NET_NAME
'TP_CPU0_TEST5_CCD3'
 '@T6G_MB_LIB.T6G(SCH_1):TP_CPU0_TEST5_CCD3':
 C_SIGNAL='@t6g_mb_lib.t6g(sch_1):tp_cpu0_test5_ccd3';
NODE_NAME     U25 Y30
 '@T6G_MB_LIB.T6G(SCH_1):PAGE27_I227@PURE_QUANTA.GENOA_SP5(CHIPS)':
 'TEST5_CCD3': CDS_PINID='TEST5_CCD3';
NET_NAME
'TP_CPU0_TEST5_CCD4'
 '@T6G_MB_LIB.T6G(SCH_1):TP_CPU0_TEST5_CCD4':
 C_SIGNAL='@t6g_mb_lib.t6g(sch_1):tp_cpu0_test5_ccd4';
NODE_NAME     U25 AA53
 '@T6G_MB_LIB.T6G(SCH_1):PAGE27_I227@PURE_QUANTA.GENOA_SP5(CHIPS)':
 'TEST5_CCD4': CDS_PINID='TEST5_CCD4';
NET_NAME
'TP_CPU0_TEST5_CCD5'
 '@T6G_MB_LIB.T6G(SCH_1):TP_CPU0_TEST5_CCD5':
 C_SIGNAL='@t6g_mb_lib.t6g(sch_1):tp_cpu0_test5_ccd5';
NODE_NAME     U25 CJ25
 '@T6G_MB_LIB.T6G(SCH_1):PAGE27_I227@PURE_QUANTA.GENOA_SP5(CHIPS)':
 'TEST5_CCD5': CDS_PINID='TEST5_CCD5';
NET_NAME
'TP_CPU0_TEST5_CCD6'
 '@T6G_MB_LIB.T6G(SCH_1):TP_CPU0_TEST5_CCD6':
 C_SIGNAL='@t6g_mb_lib.t6g(sch_1):tp_cpu0_test5_ccd6';
NODE_NAME     U25 CJ51
 '@T6G_MB_LIB.T6G(SCH_1):PAGE27_I227@PURE_QUANTA.GENOA_SP5(CHIPS)':
 'TEST5_CCD6': CDS_PINID='TEST5_CCD6';
NET_NAME
'TP_CPU0_TEST5_CCD7'
 '@T6G_MB_LIB.T6G(SCH_1):TP_CPU0_TEST5_CCD7':
 C_SIGNAL='@t6g_mb_lib.t6g(sch_1):tp_cpu0_test5_ccd7';
NODE_NAME     U25 AA26
 '@T6G_MB_LIB.T6G(SCH_1):PAGE27_I227@PURE_QUANTA.GENOA_SP5(CHIPS)':
 'TEST5_CCD7': CDS_PINID='TEST5_CCD7';
NET_NAME
'TP_CPU0_TEST5_CCD8'
 '@T6G_MB_LIB.T6G(SCH_1):TP_CPU0_TEST5_CCD8':
 C_SIGNAL='@t6g_mb_lib.t6g(sch_1):tp_cpu0_test5_ccd8';
NODE_NAME     U25 Y47
 '@T6G_MB_LIB.T6G(SCH_1):PAGE27_I227@PURE_QUANTA.GENOA_SP5(CHIPS)':
 'TEST5_CCD8': CDS_PINID='TEST5_CCD8';
NET_NAME
'TP_CPU0_TEST5_CCD9'
 '@T6G_MB_LIB.T6G(SCH_1):TP_CPU0_TEST5_CCD9':
 C_SIGNAL='@t6g_mb_lib.t6g(sch_1):tp_cpu0_test5_ccd9';
NODE_NAME     U25 CK29
 '@T6G_MB_LIB.T6G(SCH_1):PAGE27_I227@PURE_QUANTA.GENOA_SP5(CHIPS)':
 'TEST5_CCD9': CDS_PINID='TEST5_CCD9';
NET_NAME
'TP_CPU0_TEST5_IOD'
 '@T6G_MB_LIB.T6G(SCH_1):TP_CPU0_TEST5_IOD':
 C_SIGNAL='@t6g_mb_lib.t6g(sch_1):tp_cpu0_test5_iod';
NODE_NAME     U25 AA24
 '@T6G_MB_LIB.T6G(SCH_1):PAGE27_I227@PURE_QUANTA.GENOA_SP5(CHIPS)':
 'TEST5_IOD': CDS_PINID='TEST5_IOD';
NET_NAME
'TP_CPU0_TEST6_CCD0'
 '@T6G_MB_LIB.T6G(SCH_1):TP_CPU0_TEST6_CCD0':
 C_SIGNAL='@t6g_mb_lib.t6g(sch_1):tp_cpu0_test6_ccd0';
NODE_NAME     U25 AA46
 '@T6G_MB_LIB.T6G(SCH_1):PAGE27_I227@PURE_QUANTA.GENOA_SP5(CHIPS)':
 'TEST6_CCD0': CDS_PINID='TEST6_CCD0';
NET_NAME
'TP_CPU0_TEST6_CCD1'
 '@T6G_MB_LIB.T6G(SCH_1):TP_CPU0_TEST6_CCD1':
 C_SIGNAL='@t6g_mb_lib.t6g(sch_1):tp_cpu0_test6_ccd1';
NODE_NAME     U25 CJ30
 '@T6G_MB_LIB.T6G(SCH_1):PAGE27_I227@PURE_QUANTA.GENOA_SP5(CHIPS)':
 'TEST6_CCD1': CDS_PINID='TEST6_CCD1';
NET_NAME
'TP_CPU0_TEST6_CCD2'
 '@T6G_MB_LIB.T6G(SCH_1):TP_CPU0_TEST6_CCD2':
 C_SIGNAL='@t6g_mb_lib.t6g(sch_1):tp_cpu0_test6_ccd2';
NODE_NAME     U25 CJ46
 '@T6G_MB_LIB.T6G(SCH_1):PAGE27_I227@PURE_QUANTA.GENOA_SP5(CHIPS)':
 'TEST6_CCD2': CDS_PINID='TEST6_CCD2';
NET_NAME
'TP_CPU0_TEST6_CCD3'
 '@T6G_MB_LIB.T6G(SCH_1):TP_CPU0_TEST6_CCD3':
 C_SIGNAL='@t6g_mb_lib.t6g(sch_1):tp_cpu0_test6_ccd3';
NODE_NAME     U25 Y46
 '@T6G_MB_LIB.T6G(SCH_1):PAGE27_I227@PURE_QUANTA.GENOA_SP5(CHIPS)':
 'TEST6_CCD3': CDS_PINID='TEST6_CCD3';
NET_NAME
'TP_CPU0_TEST6_IOD'
 '@T6G_MB_LIB.T6G(SCH_1):TP_CPU0_TEST6_IOD':
 C_SIGNAL='@t6g_mb_lib.t6g(sch_1):tp_cpu0_test6_iod';
NODE_NAME     U25 AA49
 '@T6G_MB_LIB.T6G(SCH_1):PAGE27_I227@PURE_QUANTA.GENOA_SP5(CHIPS)':
 'TEST6_IOD': CDS_PINID='TEST6_IOD';
NET_NAME
'TP_CPU0_TEST6_X3D0'
 '@T6G_MB_LIB.T6G(SCH_1):TP_CPU0_TEST6_X3D0':
 C_SIGNAL='@t6g_mb_lib.t6g(sch_1):tp_cpu0_test6_x3d0';
NODE_NAME     U25 AA47
 '@T6G_MB_LIB.T6G(SCH_1):PAGE27_I227@PURE_QUANTA.GENOA_SP5(CHIPS)':
 'TEST6_X3D0': CDS_PINID='TEST6_X3D0';
NET_NAME
'TP_CPU0_TEST6_X3D1'
 '@T6G_MB_LIB.T6G(SCH_1):TP_CPU0_TEST6_X3D1':
 C_SIGNAL='@t6g_mb_lib.t6g(sch_1):tp_cpu0_test6_x3d1';
NODE_NAME     U25 CJ29
 '@T6G_MB_LIB.T6G(SCH_1):PAGE27_I227@PURE_QUANTA.GENOA_SP5(CHIPS)':
 'TEST6_X3D1': CDS_PINID='TEST6_X3D1';
NET_NAME
'TP_CPU0_TEST6_X3D2'
 '@T6G_MB_LIB.T6G(SCH_1):TP_CPU0_TEST6_X3D2':
 C_SIGNAL='@t6g_mb_lib.t6g(sch_1):tp_cpu0_test6_x3d2';
NODE_NAME     U25 AA29
 '@T6G_MB_LIB.T6G(SCH_1):PAGE27_I227@PURE_QUANTA.GENOA_SP5(CHIPS)':
 'TEST6_X3D2': CDS_PINID='TEST6_X3D2';
NET_NAME
'TP_CPU0_TEST6_X3D3'
 '@T6G_MB_LIB.T6G(SCH_1):TP_CPU0_TEST6_X3D3':
 C_SIGNAL='@t6g_mb_lib.t6g(sch_1):tp_cpu0_test6_x3d3';
NODE_NAME     U25 CJ52
 '@T6G_MB_LIB.T6G(SCH_1):PAGE27_I227@PURE_QUANTA.GENOA_SP5(CHIPS)':
 'TEST6_X3D3': CDS_PINID='TEST6_X3D3';
NET_NAME
'TP_CPU0_TEST6_X3D4'
 '@T6G_MB_LIB.T6G(SCH_1):TP_CPU0_TEST6_X3D4':
 C_SIGNAL='@t6g_mb_lib.t6g(sch_1):tp_cpu0_test6_x3d4';
NODE_NAME     U25 AA23
 '@T6G_MB_LIB.T6G(SCH_1):PAGE27_I227@PURE_QUANTA.GENOA_SP5(CHIPS)':
 'TEST6_X3D4': CDS_PINID='TEST6_X3D4';
NET_NAME
'TP_CPU0_TEST6_X3D5'
 '@T6G_MB_LIB.T6G(SCH_1):TP_CPU0_TEST6_X3D5':
 C_SIGNAL='@t6g_mb_lib.t6g(sch_1):tp_cpu0_test6_x3d5';
NODE_NAME     U25 CJ53
 '@T6G_MB_LIB.T6G(SCH_1):PAGE27_I227@PURE_QUANTA.GENOA_SP5(CHIPS)':
 'TEST6_X3D5': CDS_PINID='TEST6_X3D5';
NET_NAME
'TP_CPU0_UART0_INTR'
 '@T6G_MB_LIB.T6G(SCH_1):TP_CPU0_UART0_INTR':
 C_SIGNAL='@t6g_mb_lib.t6g(sch_1):tp_cpu0_uart0_intr';
NODE_NAME     U25 DG34
 '@T6G_MB_LIB.T6G(SCH_1):PAGE27_I227@PURE_QUANTA.GENOA_SP5(CHIPS)':
 'UART0_INTR||AGPIO139': CDS_PINID='\uart0_intr||agpio139\';
NET_NAME
'TP_CPU0_USB_HUB1_SUSPEND'
 '@T6G_MB_LIB.T6G(SCH_1):TP_CPU0_USB_HUB1_SUSPEND':
 C_SIGNAL='@t6g_mb_lib.t6g(sch_1):tp_cpu0_usb_hub1_suspend';
NODE_NAME     U6001 20
 '@T6G_MB_LIB.T6G(SCH_1):PAGE153_I1@PURE_QUANTA.CYUSB330468LTXI(CHIPS)':
 'SUSPEND': CDS_PINID='SUSPEND';
NET_NAME
'TP_CPU1_TEST41_IOD'
 '@T6G_MB_LIB.T6G(SCH_1):TP_CPU1_TEST41_IOD':
 C_SIGNAL='@t6g_mb_lib.t6g(sch_1):tp_cpu1_test41_iod';
NODE_NAME     U26 W31
 '@T6G_MB_LIB.T6G(SCH_1):PAGE54_I190@PURE_QUANTA.GENOA_SP5(CHIPS)':
 'TEST41_IOD': CDS_PINID='TEST41_IOD';
NET_NAME
'TP_CPU1_TEST47_CCD0'
 '@T6G_MB_LIB.T6G(SCH_1):TP_CPU1_TEST47_CCD0':
 C_SIGNAL='@t6g_mb_lib.t6g(sch_1):tp_cpu1_test47_ccd0';
NODE_NAME     U26 B60
 '@T6G_MB_LIB.T6G(SCH_1):PAGE54_I190@PURE_QUANTA.GENOA_SP5(CHIPS)':
 'TEST47_CCD0': CDS_PINID='TEST47_CCD0';
NET_NAME
'TP_CPU1_TEST47_CCD1'
 '@T6G_MB_LIB.T6G(SCH_1):TP_CPU1_TEST47_CCD1':
 C_SIGNAL='@t6g_mb_lib.t6g(sch_1):tp_cpu1_test47_ccd1';
NODE_NAME     U26 CJ24
 '@T6G_MB_LIB.T6G(SCH_1):PAGE54_I190@PURE_QUANTA.GENOA_SP5(CHIPS)':
 'TEST47_CCD1': CDS_PINID='TEST47_CCD1';
NET_NAME
'TP_CPU1_TEST47_CCD2'
 '@T6G_MB_LIB.T6G(SCH_1):TP_CPU1_TEST47_CCD2':
 C_SIGNAL='@t6g_mb_lib.t6g(sch_1):tp_cpu1_test47_ccd2';
NODE_NAME     U26 CK46
 '@T6G_MB_LIB.T6G(SCH_1):PAGE54_I190@PURE_QUANTA.GENOA_SP5(CHIPS)':
 'TEST47_CCD2': CDS_PINID='TEST47_CCD2';
NET_NAME
'TP_CPU1_TEST47_CCD3'
 '@T6G_MB_LIB.T6G(SCH_1):TP_CPU1_TEST47_CCD3':
 C_SIGNAL='@t6g_mb_lib.t6g(sch_1):tp_cpu1_test47_ccd3';
NODE_NAME     U26 E32
 '@T6G_MB_LIB.T6G(SCH_1):PAGE54_I190@PURE_QUANTA.GENOA_SP5(CHIPS)':
 'TEST47_CCD3': CDS_PINID='TEST47_CCD3';
NET_NAME
'TP_CPU1_TEST47_IOD0'
 '@T6G_MB_LIB.T6G(SCH_1):TP_CPU1_TEST47_IOD0':
 C_SIGNAL='@t6g_mb_lib.t6g(sch_1):tp_cpu1_test47_iod0';
NODE_NAME     U26 B58
 '@T6G_MB_LIB.T6G(SCH_1):PAGE54_I190@PURE_QUANTA.GENOA_SP5(CHIPS)':
 'TEST47_IOD0': CDS_PINID='TEST47_IOD0';
NET_NAME
'TP_CPU1_TEST47_IOD1'
 '@T6G_MB_LIB.T6G(SCH_1):TP_CPU1_TEST47_IOD1':
 C_SIGNAL='@t6g_mb_lib.t6g(sch_1):tp_cpu1_test47_iod1';
NODE_NAME     U26 D7
 '@T6G_MB_LIB.T6G(SCH_1):PAGE54_I190@PURE_QUANTA.GENOA_SP5(CHIPS)':
 'TEST47_IOD1': CDS_PINID='TEST47_IOD1';
NET_NAME
'TP_CPU1_TEST4_CCD0'
 '@T6G_MB_LIB.T6G(SCH_1):TP_CPU1_TEST4_CCD0':
 C_SIGNAL='@t6g_mb_lib.t6g(sch_1):tp_cpu1_test4_ccd0';
NODE_NAME     U26 AA50
 '@T6G_MB_LIB.T6G(SCH_1):PAGE54_I190@PURE_QUANTA.GENOA_SP5(CHIPS)':
 'TEST4_CCD0': CDS_PINID='TEST4_CCD0';
NET_NAME
'TP_CPU1_TEST4_CCD1'
 '@T6G_MB_LIB.T6G(SCH_1):TP_CPU1_TEST4_CCD1':
 C_SIGNAL='@t6g_mb_lib.t6g(sch_1):tp_cpu1_test4_ccd1';
NODE_NAME     U26 CJ28
 '@T6G_MB_LIB.T6G(SCH_1):PAGE54_I190@PURE_QUANTA.GENOA_SP5(CHIPS)':
 'TEST4_CCD1': CDS_PINID='TEST4_CCD1';
NET_NAME
'TP_CPU1_TEST4_CCD10'
 '@T6G_MB_LIB.T6G(SCH_1):TP_CPU1_TEST4_CCD10':
 C_SIGNAL='@t6g_mb_lib.t6g(sch_1):tp_cpu1_test4_ccd10';
NODE_NAME     U26 CJ47
 '@T6G_MB_LIB.T6G(SCH_1):PAGE54_I190@PURE_QUANTA.GENOA_SP5(CHIPS)':
 'TEST4_CCD10': CDS_PINID='TEST4_CCD10';
NET_NAME
'TP_CPU1_TEST4_CCD11'
 '@T6G_MB_LIB.T6G(SCH_1):TP_CPU1_TEST4_CCD11':
 C_SIGNAL='@t6g_mb_lib.t6g(sch_1):tp_cpu1_test4_ccd11';
NODE_NAME     U26 AA28
 '@T6G_MB_LIB.T6G(SCH_1):PAGE54_I190@PURE_QUANTA.GENOA_SP5(CHIPS)':
 'TEST4_CCD11': CDS_PINID='TEST4_CCD11';
NET_NAME
'TP_CPU1_TEST4_CCD2'
 '@T6G_MB_LIB.T6G(SCH_1):TP_CPU1_TEST4_CCD2':
 C_SIGNAL='@t6g_mb_lib.t6g(sch_1):tp_cpu1_test4_ccd2';
NODE_NAME     U26 CJ48
 '@T6G_MB_LIB.T6G(SCH_1):PAGE54_I190@PURE_QUANTA.GENOA_SP5(CHIPS)':
 'TEST4_CCD2': CDS_PINID='TEST4_CCD2';
NET_NAME
'TP_CPU1_TEST4_CCD3'
 '@T6G_MB_LIB.T6G(SCH_1):TP_CPU1_TEST4_CCD3':
 C_SIGNAL='@t6g_mb_lib.t6g(sch_1):tp_cpu1_test4_ccd3';
NODE_NAME     U26 AA30
 '@T6G_MB_LIB.T6G(SCH_1):PAGE54_I190@PURE_QUANTA.GENOA_SP5(CHIPS)':
 'TEST4_CCD3': CDS_PINID='TEST4_CCD3';
NET_NAME
'TP_CPU1_TEST4_CCD4'
 '@T6G_MB_LIB.T6G(SCH_1):TP_CPU1_TEST4_CCD4':
 C_SIGNAL='@t6g_mb_lib.t6g(sch_1):tp_cpu1_test4_ccd4';
NODE_NAME     U26 AA52
 '@T6G_MB_LIB.T6G(SCH_1):PAGE54_I190@PURE_QUANTA.GENOA_SP5(CHIPS)':
 'TEST4_CCD4': CDS_PINID='TEST4_CCD4';
NET_NAME
'TP_CPU1_TEST4_CCD5'
 '@T6G_MB_LIB.T6G(SCH_1):TP_CPU1_TEST4_CCD5':
 C_SIGNAL='@t6g_mb_lib.t6g(sch_1):tp_cpu1_test4_ccd5';
NODE_NAME     U26 CJ26
 '@T6G_MB_LIB.T6G(SCH_1):PAGE54_I190@PURE_QUANTA.GENOA_SP5(CHIPS)':
 'TEST4_CCD5': CDS_PINID='TEST4_CCD5';
NET_NAME
'TP_CPU1_TEST4_CCD6'
 '@T6G_MB_LIB.T6G(SCH_1):TP_CPU1_TEST4_CCD6':
 C_SIGNAL='@t6g_mb_lib.t6g(sch_1):tp_cpu1_test4_ccd6';
NODE_NAME     U26 CJ50
 '@T6G_MB_LIB.T6G(SCH_1):PAGE54_I190@PURE_QUANTA.GENOA_SP5(CHIPS)':
 'TEST4_CCD6': CDS_PINID='TEST4_CCD6';
NET_NAME
'TP_CPU1_TEST4_CCD7'
 '@T6G_MB_LIB.T6G(SCH_1):TP_CPU1_TEST4_CCD7':
 C_SIGNAL='@t6g_mb_lib.t6g(sch_1):tp_cpu1_test4_ccd7';
NODE_NAME     U26 AA27
 '@T6G_MB_LIB.T6G(SCH_1):PAGE54_I190@PURE_QUANTA.GENOA_SP5(CHIPS)':
 'TEST4_CCD7': CDS_PINID='TEST4_CCD7';
NET_NAME
'TP_CPU1_TEST4_CCD8'
 '@T6G_MB_LIB.T6G(SCH_1):TP_CPU1_TEST4_CCD8':
 C_SIGNAL='@t6g_mb_lib.t6g(sch_1):tp_cpu1_test4_ccd8';
NODE_NAME     U26 AA48
 '@T6G_MB_LIB.T6G(SCH_1):PAGE54_I190@PURE_QUANTA.GENOA_SP5(CHIPS)':
 'TEST4_CCD8': CDS_PINID='TEST4_CCD8';
NET_NAME
'TP_CPU1_TEST4_CCD9'
 '@T6G_MB_LIB.T6G(SCH_1):TP_CPU1_TEST4_CCD9':
 C_SIGNAL='@t6g_mb_lib.t6g(sch_1):tp_cpu1_test4_ccd9';
NODE_NAME     U26 CK30
 '@T6G_MB_LIB.T6G(SCH_1):PAGE54_I190@PURE_QUANTA.GENOA_SP5(CHIPS)':
 'TEST4_CCD9': CDS_PINID='TEST4_CCD9';
NET_NAME
'TP_CPU1_TEST4_IOD'
 '@T6G_MB_LIB.T6G(SCH_1):TP_CPU1_TEST4_IOD':
 C_SIGNAL='@t6g_mb_lib.t6g(sch_1):tp_cpu1_test4_iod';
NODE_NAME     U26 AA25
 '@T6G_MB_LIB.T6G(SCH_1):PAGE54_I190@PURE_QUANTA.GENOA_SP5(CHIPS)':
 'TEST4_IOD': CDS_PINID='TEST4_IOD';
NET_NAME
'TP_CPU1_TEST50_IOD'
 '@T6G_MB_LIB.T6G(SCH_1):TP_CPU1_TEST50_IOD':
 C_SIGNAL='@t6g_mb_lib.t6g(sch_1):tp_cpu1_test50_iod';
NODE_NAME     U26 B61
 '@T6G_MB_LIB.T6G(SCH_1):PAGE54_I190@PURE_QUANTA.GENOA_SP5(CHIPS)':
 'TEST50_IOD': CDS_PINID='TEST50_IOD';
NET_NAME
'TP_CPU1_TEST5_CCD0'
 '@T6G_MB_LIB.T6G(SCH_1):TP_CPU1_TEST5_CCD0':
 C_SIGNAL='@t6g_mb_lib.t6g(sch_1):tp_cpu1_test5_ccd0';
NODE_NAME     U26 AA51
 '@T6G_MB_LIB.T6G(SCH_1):PAGE54_I190@PURE_QUANTA.GENOA_SP5(CHIPS)':
 'TEST5_CCD0': CDS_PINID='TEST5_CCD0';
NET_NAME
'TP_CPU1_TEST5_CCD1'
 '@T6G_MB_LIB.T6G(SCH_1):TP_CPU1_TEST5_CCD1':
 C_SIGNAL='@t6g_mb_lib.t6g(sch_1):tp_cpu1_test5_ccd1';
NODE_NAME     U26 CJ27
 '@T6G_MB_LIB.T6G(SCH_1):PAGE54_I190@PURE_QUANTA.GENOA_SP5(CHIPS)':
 'TEST5_CCD1': CDS_PINID='TEST5_CCD1';
NET_NAME
'TP_CPU1_TEST5_CCD10'
 '@T6G_MB_LIB.T6G(SCH_1):TP_CPU1_TEST5_CCD10':
 C_SIGNAL='@t6g_mb_lib.t6g(sch_1):tp_cpu1_test5_ccd10';
NODE_NAME     U26 CK47
 '@T6G_MB_LIB.T6G(SCH_1):PAGE54_I190@PURE_QUANTA.GENOA_SP5(CHIPS)':
 'TEST5_CCD10': CDS_PINID='TEST5_CCD10';
NET_NAME
'TP_CPU1_TEST5_CCD11'
 '@T6G_MB_LIB.T6G(SCH_1):TP_CPU1_TEST5_CCD11':
 C_SIGNAL='@t6g_mb_lib.t6g(sch_1):tp_cpu1_test5_ccd11';
NODE_NAME     U26 Y29
 '@T6G_MB_LIB.T6G(SCH_1):PAGE54_I190@PURE_QUANTA.GENOA_SP5(CHIPS)':
 'TEST5_CCD11': CDS_PINID='TEST5_CCD11';
NET_NAME
'TP_CPU1_TEST5_CCD2'
 '@T6G_MB_LIB.T6G(SCH_1):TP_CPU1_TEST5_CCD2':
 C_SIGNAL='@t6g_mb_lib.t6g(sch_1):tp_cpu1_test5_ccd2';
NODE_NAME     U26 CJ49
 '@T6G_MB_LIB.T6G(SCH_1):PAGE54_I190@PURE_QUANTA.GENOA_SP5(CHIPS)':
 'TEST5_CCD2': CDS_PINID='TEST5_CCD2';
NET_NAME
'TP_CPU1_TEST5_CCD3'
 '@T6G_MB_LIB.T6G(SCH_1):TP_CPU1_TEST5_CCD3':
 C_SIGNAL='@t6g_mb_lib.t6g(sch_1):tp_cpu1_test5_ccd3';
NODE_NAME     U26 Y30
 '@T6G_MB_LIB.T6G(SCH_1):PAGE54_I190@PURE_QUANTA.GENOA_SP5(CHIPS)':
 'TEST5_CCD3': CDS_PINID='TEST5_CCD3';
NET_NAME
'TP_CPU1_TEST5_CCD4'
 '@T6G_MB_LIB.T6G(SCH_1):TP_CPU1_TEST5_CCD4':
 C_SIGNAL='@t6g_mb_lib.t6g(sch_1):tp_cpu1_test5_ccd4';
NODE_NAME     U26 AA53
 '@T6G_MB_LIB.T6G(SCH_1):PAGE54_I190@PURE_QUANTA.GENOA_SP5(CHIPS)':
 'TEST5_CCD4': CDS_PINID='TEST5_CCD4';
NET_NAME
'TP_CPU1_TEST5_CCD5'
 '@T6G_MB_LIB.T6G(SCH_1):TP_CPU1_TEST5_CCD5':
 C_SIGNAL='@t6g_mb_lib.t6g(sch_1):tp_cpu1_test5_ccd5';
NODE_NAME     U26 CJ25
 '@T6G_MB_LIB.T6G(SCH_1):PAGE54_I190@PURE_QUANTA.GENOA_SP5(CHIPS)':
 'TEST5_CCD5': CDS_PINID='TEST5_CCD5';
NET_NAME
'TP_CPU1_TEST5_CCD6'
 '@T6G_MB_LIB.T6G(SCH_1):TP_CPU1_TEST5_CCD6':
 C_SIGNAL='@t6g_mb_lib.t6g(sch_1):tp_cpu1_test5_ccd6';
NODE_NAME     U26 CJ51
 '@T6G_MB_LIB.T6G(SCH_1):PAGE54_I190@PURE_QUANTA.GENOA_SP5(CHIPS)':
 'TEST5_CCD6': CDS_PINID='TEST5_CCD6';
NET_NAME
'TP_CPU1_TEST5_CCD7'
 '@T6G_MB_LIB.T6G(SCH_1):TP_CPU1_TEST5_CCD7':
 C_SIGNAL='@t6g_mb_lib.t6g(sch_1):tp_cpu1_test5_ccd7';
NODE_NAME     U26 AA26
 '@T6G_MB_LIB.T6G(SCH_1):PAGE54_I190@PURE_QUANTA.GENOA_SP5(CHIPS)':
 'TEST5_CCD7': CDS_PINID='TEST5_CCD7';
NET_NAME
'TP_CPU1_TEST5_CCD8'
 '@T6G_MB_LIB.T6G(SCH_1):TP_CPU1_TEST5_CCD8':
 C_SIGNAL='@t6g_mb_lib.t6g(sch_1):tp_cpu1_test5_ccd8';
NODE_NAME     U26 Y47
 '@T6G_MB_LIB.T6G(SCH_1):PAGE54_I190@PURE_QUANTA.GENOA_SP5(CHIPS)':
 'TEST5_CCD8': CDS_PINID='TEST5_CCD8';
NET_NAME
'TP_CPU1_TEST5_CCD9'
 '@T6G_MB_LIB.T6G(SCH_1):TP_CPU1_TEST5_CCD9':
 C_SIGNAL='@t6g_mb_lib.t6g(sch_1):tp_cpu1_test5_ccd9';
NODE_NAME     U26 CK29
 '@T6G_MB_LIB.T6G(SCH_1):PAGE54_I190@PURE_QUANTA.GENOA_SP5(CHIPS)':
 'TEST5_CCD9': CDS_PINID='TEST5_CCD9';
NET_NAME
'TP_CPU1_TEST5_IOD'
 '@T6G_MB_LIB.T6G(SCH_1):TP_CPU1_TEST5_IOD':
 C_SIGNAL='@t6g_mb_lib.t6g(sch_1):tp_cpu1_test5_iod';
NODE_NAME     U26 AA24
 '@T6G_MB_LIB.T6G(SCH_1):PAGE54_I190@PURE_QUANTA.GENOA_SP5(CHIPS)':
 'TEST5_IOD': CDS_PINID='TEST5_IOD';
NET_NAME
'TP_CPU1_TEST6_CCD0'
 '@T6G_MB_LIB.T6G(SCH_1):TP_CPU1_TEST6_CCD0':
 C_SIGNAL='@t6g_mb_lib.t6g(sch_1):tp_cpu1_test6_ccd0';
NODE_NAME     U26 AA46
 '@T6G_MB_LIB.T6G(SCH_1):PAGE54_I190@PURE_QUANTA.GENOA_SP5(CHIPS)':
 'TEST6_CCD0': CDS_PINID='TEST6_CCD0';
NET_NAME
'TP_CPU1_TEST6_CCD1'
 '@T6G_MB_LIB.T6G(SCH_1):TP_CPU1_TEST6_CCD1':
 C_SIGNAL='@t6g_mb_lib.t6g(sch_1):tp_cpu1_test6_ccd1';
NODE_NAME     U26 CJ30
 '@T6G_MB_LIB.T6G(SCH_1):PAGE54_I190@PURE_QUANTA.GENOA_SP5(CHIPS)':
 'TEST6_CCD1': CDS_PINID='TEST6_CCD1';
NET_NAME
'TP_CPU1_TEST6_CCD2'
 '@T6G_MB_LIB.T6G(SCH_1):TP_CPU1_TEST6_CCD2':
 C_SIGNAL='@t6g_mb_lib.t6g(sch_1):tp_cpu1_test6_ccd2';
NODE_NAME     U26 CJ46
 '@T6G_MB_LIB.T6G(SCH_1):PAGE54_I190@PURE_QUANTA.GENOA_SP5(CHIPS)':
 'TEST6_CCD2': CDS_PINID='TEST6_CCD2';
NET_NAME
'TP_CPU1_TEST6_CCD3'
 '@T6G_MB_LIB.T6G(SCH_1):TP_CPU1_TEST6_CCD3':
 C_SIGNAL='@t6g_mb_lib.t6g(sch_1):tp_cpu1_test6_ccd3';
NODE_NAME     U26 Y46
 '@T6G_MB_LIB.T6G(SCH_1):PAGE54_I190@PURE_QUANTA.GENOA_SP5(CHIPS)':
 'TEST6_CCD3': CDS_PINID='TEST6_CCD3';
NET_NAME
'TP_CPU1_TEST6_IOD'
 '@T6G_MB_LIB.T6G(SCH_1):TP_CPU1_TEST6_IOD':
 C_SIGNAL='@t6g_mb_lib.t6g(sch_1):tp_cpu1_test6_iod';
NODE_NAME     U26 AA49
 '@T6G_MB_LIB.T6G(SCH_1):PAGE54_I190@PURE_QUANTA.GENOA_SP5(CHIPS)':
 'TEST6_IOD': CDS_PINID='TEST6_IOD';
NET_NAME
'TP_CPU1_TEST6_X3D0'
 '@T6G_MB_LIB.T6G(SCH_1):TP_CPU1_TEST6_X3D0':
 C_SIGNAL='@t6g_mb_lib.t6g(sch_1):tp_cpu1_test6_x3d0';
NODE_NAME     U26 AA47
 '@T6G_MB_LIB.T6G(SCH_1):PAGE54_I190@PURE_QUANTA.GENOA_SP5(CHIPS)':
 'TEST6_X3D0': CDS_PINID='TEST6_X3D0';
NET_NAME
'TP_CPU1_TEST6_X3D1'
 '@T6G_MB_LIB.T6G(SCH_1):TP_CPU1_TEST6_X3D1':
 C_SIGNAL='@t6g_mb_lib.t6g(sch_1):tp_cpu1_test6_x3d1';
NODE_NAME     U26 CJ29
 '@T6G_MB_LIB.T6G(SCH_1):PAGE54_I190@PURE_QUANTA.GENOA_SP5(CHIPS)':
 'TEST6_X3D1': CDS_PINID='TEST6_X3D1';
NET_NAME
'TP_CPU1_TEST6_X3D2'
 '@T6G_MB_LIB.T6G(SCH_1):TP_CPU1_TEST6_X3D2':
 C_SIGNAL='@t6g_mb_lib.t6g(sch_1):tp_cpu1_test6_x3d2';
NODE_NAME     U26 AA29
 '@T6G_MB_LIB.T6G(SCH_1):PAGE54_I190@PURE_QUANTA.GENOA_SP5(CHIPS)':
 'TEST6_X3D2': CDS_PINID='TEST6_X3D2';
NET_NAME
'TP_CPU1_TEST6_X3D3'
 '@T6G_MB_LIB.T6G(SCH_1):TP_CPU1_TEST6_X3D3':
 C_SIGNAL='@t6g_mb_lib.t6g(sch_1):tp_cpu1_test6_x3d3';
NODE_NAME     U26 CJ52
 '@T6G_MB_LIB.T6G(SCH_1):PAGE54_I190@PURE_QUANTA.GENOA_SP5(CHIPS)':
 'TEST6_X3D3': CDS_PINID='TEST6_X3D3';
NET_NAME
'TP_CPU1_TEST6_X3D4'
 '@T6G_MB_LIB.T6G(SCH_1):TP_CPU1_TEST6_X3D4':
 C_SIGNAL='@t6g_mb_lib.t6g(sch_1):tp_cpu1_test6_x3d4';
NODE_NAME     U26 AA23
 '@T6G_MB_LIB.T6G(SCH_1):PAGE54_I190@PURE_QUANTA.GENOA_SP5(CHIPS)':
 'TEST6_X3D4': CDS_PINID='TEST6_X3D4';
NET_NAME
'TP_CPU1_TEST6_X3D5'
 '@T6G_MB_LIB.T6G(SCH_1):TP_CPU1_TEST6_X3D5':
 C_SIGNAL='@t6g_mb_lib.t6g(sch_1):tp_cpu1_test6_x3d5';
NODE_NAME     U26 CJ53
 '@T6G_MB_LIB.T6G(SCH_1):PAGE54_I190@PURE_QUANTA.GENOA_SP5(CHIPS)':
 'TEST6_X3D5': CDS_PINID='TEST6_X3D5';
NET_NAME
'TP_CPU1_UART0_CTS_N'
 '@T6G_MB_LIB.T6G(SCH_1):TP_CPU1_UART0_CTS_N':
 C_SIGNAL='@t6g_mb_lib.t6g(sch_1):tp_cpu1_uart0_cts_n';
NODE_NAME     U26 DJ33
 '@T6G_MB_LIB.T6G(SCH_1):PAGE54_I190@PURE_QUANTA.GENOA_SP5(CHIPS)':
 'UART0_CTS_L||UART2_TXD||AGPIO135': CDS_PINID='\uart0_cts_l||uart2_txd||agpio135\';
NET_NAME
'TP_CPU1_UART0_INTR'
 '@T6G_MB_LIB.T6G(SCH_1):TP_CPU1_UART0_INTR':
 C_SIGNAL='@t6g_mb_lib.t6g(sch_1):tp_cpu1_uart0_intr';
NODE_NAME     U26 DG34
 '@T6G_MB_LIB.T6G(SCH_1):PAGE54_I190@PURE_QUANTA.GENOA_SP5(CHIPS)':
 'UART0_INTR||AGPIO139': CDS_PINID='\uart0_intr||agpio139\';
NET_NAME
'TP_CPU1_UART0_RTS_N'
 '@T6G_MB_LIB.T6G(SCH_1):TP_CPU1_UART0_RTS_N':
 C_SIGNAL='@t6g_mb_lib.t6g(sch_1):tp_cpu1_uart0_rts_n';
NODE_NAME     U26 DF34
 '@T6G_MB_LIB.T6G(SCH_1):PAGE54_I190@PURE_QUANTA.GENOA_SP5(CHIPS)':
 'UART0_RTS_L||UART2_RXD||AGPIO137': CDS_PINID='\uart0_rts_l||uart2_rxd||agpio137\';
NET_NAME
'TP_CPU1_UART0_RX'
 '@T6G_MB_LIB.T6G(SCH_1):TP_CPU1_UART0_RX':
 C_SIGNAL='@t6g_mb_lib.t6g(sch_1):tp_cpu1_uart0_rx';
NODE_NAME     U26 DG35
 '@T6G_MB_LIB.T6G(SCH_1):PAGE54_I190@PURE_QUANTA.GENOA_SP5(CHIPS)':
 'UART0_RXD||AGPIO136': CDS_PINID='\uart0_rxd||agpio136\';
NET_NAME
'TP_CPU1_UART0_TX'
 '@T6G_MB_LIB.T6G(SCH_1):TP_CPU1_UART0_TX':
 C_SIGNAL='@t6g_mb_lib.t6g(sch_1):tp_cpu1_uart0_tx';
NODE_NAME     U26 DJ34
 '@T6G_MB_LIB.T6G(SCH_1):PAGE54_I190@PURE_QUANTA.GENOA_SP5(CHIPS)':
 'UART0_TXD||AGPIO138': CDS_PINID='\uart0_txd||agpio138\';
NET_NAME
'TP_CPU1_UART1_RX'
 '@T6G_MB_LIB.T6G(SCH_1):TP_CPU1_UART1_RX':
 C_SIGNAL='@t6g_mb_lib.t6g(sch_1):tp_cpu1_uart1_rx';
NODE_NAME     U26 DH33
 '@T6G_MB_LIB.T6G(SCH_1):PAGE54_I190@PURE_QUANTA.GENOA_SP5(CHIPS)':
 'UART1_RXD||AGPIO141': CDS_PINID='\uart1_rxd||agpio141\';
NET_NAME
'TP_E1S_0_MFG'
 '@T6G_MB_LIB.T6G(SCH_1):TP_E1S_0_MFG':
 C_SIGNAL='@t6g_mb_lib.t6g(sch_1):tp_e1s_0_mfg';
NODE_NAME     J90 B7
 '@T6G_MB_LIB.T6G(SCH_1):PAGE297_I90@PURE_QUANTA.SCONN56_123276793(CHIPS)':
 'MFG': CDS_PINID='MFG';
NET_NAME
'TP_E1S_0_RFU'
 '@T6G_MB_LIB.T6G(SCH_1):TP_E1S_0_RFU':
 C_SIGNAL='@t6g_mb_lib.t6g(sch_1):tp_e1s_0_rfu';
NODE_NAME     J90 B8
 '@T6G_MB_LIB.T6G(SCH_1):PAGE297_I90@PURE_QUANTA.SCONN56_123276793(CHIPS)':
 'RFU': CDS_PINID='RFU';
NET_NAME
'TP_FM_CLK_BUFFER_EN_R'
 '@T6G_MB_LIB.T6G(SCH_1):TP_FM_CLK_BUFFER_EN_R':
 C_SIGNAL='@t6g_mb_lib.t6g(sch_1):tp_fm_clk_buffer_en_r';
NODE_NAME     U18 V19
 '@T6G_MB_LIB.T6G(SCH_1):PAGE80_I217@PURE_QUANTA.LCMXO3LF9400C5BG484C(CHIPS)':
 'PR29D': CDS_PINID='PR29D';
NET_NAME
'TP_J45_A1'
 '@T6G_MB_LIB.T6G(SCH_1):TP_J45_A1':
 C_SIGNAL='@t6g_mb_lib.t6g(sch_1):tp_j45_a1';
NODE_NAME     J45 A1
 '@T6G_MB_LIB.T6G(SCH_1):PAGE363_I466@PURE_QUANTA.CONN60_101062636003K02LF(CHIPS)':
 'A1': CDS_PINID='A1';
NET_NAME
'TP_JTAG_SCM_SLOT3_R_TCK'
 '@T6G_MB_LIB.T6G(SCH_1):TP_JTAG_SCM_SLOT3_R_TCK':
 C_SIGNAL='@t6g_mb_lib.t6g(sch_1):tp_jtag_scm_slot3_r_tck';
NODE_NAME     U160 12
 '@T6G_MB_LIB.T6G(SCH_1):PAGE148_I266@PURE_QUANTA.74LV4052PW(CHIPS)':
 '1Y0': CDS_PINID='\1y0\';
NET_NAME
'TP_JTAG_SCM_SLOT3_R_TDI'
 '@T6G_MB_LIB.T6G(SCH_1):TP_JTAG_SCM_SLOT3_R_TDI':
 C_SIGNAL='@t6g_mb_lib.t6g(sch_1):tp_jtag_scm_slot3_r_tdi';
NODE_NAME     U212 12
 '@T6G_MB_LIB.T6G(SCH_1):PAGE148_I302@PURE_QUANTA.74LV4052PW(CHIPS)':
 '1Y0': CDS_PINID='\1y0\';
NET_NAME
'TP_JTAG_SCM_SLOT3_R_TDO'
 '@T6G_MB_LIB.T6G(SCH_1):TP_JTAG_SCM_SLOT3_R_TDO':
 C_SIGNAL='@t6g_mb_lib.t6g(sch_1):tp_jtag_scm_slot3_r_tdo';
NODE_NAME     U212 1
 '@T6G_MB_LIB.T6G(SCH_1):PAGE148_I302@PURE_QUANTA.74LV4052PW(CHIPS)':
 '2Y0': CDS_PINID='\2y0\';
NET_NAME
'TP_JTAG_SCM_SLOT3_R_TMS'
 '@T6G_MB_LIB.T6G(SCH_1):TP_JTAG_SCM_SLOT3_R_TMS':
 C_SIGNAL='@t6g_mb_lib.t6g(sch_1):tp_jtag_scm_slot3_r_tms';
NODE_NAME     U160 1
 '@T6G_MB_LIB.T6G(SCH_1):PAGE148_I266@PURE_QUANTA.74LV4052PW(CHIPS)':
 '2Y0': CDS_PINID='\2y0\';
NET_NAME
'TP_M_A_CPU0_SA_TEST39A'
 '@T6G_MB_LIB.T6G(SCH_1):TP_M_A_CPU0_SA_TEST39A':
 C_SIGNAL='@t6g_mb_lib.t6g(sch_1):tp_m_a_cpu0_sa_test39a';
NODE_NAME     U25 BF72
 '@T6G_MB_LIB.T6G(SCH_1):PAGE10_I200@PURE_QUANTA.GENOA_SP5(CHIPS)':
 'TEST39A': CDS_PINID='TEST39A';
NET_NAME
'TP_M_A_CPU0_SA_TEST40'
 '@T6G_MB_LIB.T6G(SCH_1):TP_M_A_CPU0_SA_TEST40':
 C_SIGNAL='@t6g_mb_lib.t6g(sch_1):tp_m_a_cpu0_sa_test40';
NODE_NAME     U25 C60
 '@T6G_MB_LIB.T6G(SCH_1):PAGE10_I200@PURE_QUANTA.GENOA_SP5(CHIPS)':
 'TEST40': CDS_PINID='TEST40';
NET_NAME
'TP_M_A_CPU1_SA_TEST39A'
 '@T6G_MB_LIB.T6G(SCH_1):TP_M_A_CPU1_SA_TEST39A':
 C_SIGNAL='@t6g_mb_lib.t6g(sch_1):tp_m_a_cpu1_sa_test39a';
NODE_NAME     U26 BF72
 '@T6G_MB_LIB.T6G(SCH_1):PAGE37_I167@PURE_QUANTA.GENOA_SP5(CHIPS)':
 'TEST39A': CDS_PINID='TEST39A';
NET_NAME
'TP_M_A_CPU1_SA_TEST40'
 '@T6G_MB_LIB.T6G(SCH_1):TP_M_A_CPU1_SA_TEST40':
 C_SIGNAL='@t6g_mb_lib.t6g(sch_1):tp_m_a_cpu1_sa_test40';
NODE_NAME     U26 C60
 '@T6G_MB_LIB.T6G(SCH_1):PAGE37_I167@PURE_QUANTA.GENOA_SP5(CHIPS)':
 'TEST40': CDS_PINID='TEST40';
NET_NAME
'TP_M_B_CPU0_SA_TEST39B'
 '@T6G_MB_LIB.T6G(SCH_1):TP_M_B_CPU0_SA_TEST39B':
 C_SIGNAL='@t6g_mb_lib.t6g(sch_1):tp_m_b_cpu0_sa_test39b';
NODE_NAME     U25 BF62
 '@T6G_MB_LIB.T6G(SCH_1):PAGE11_I171@PURE_QUANTA.GENOA_SP5(CHIPS)':
 'TEST39B': CDS_PINID='TEST39B';
NET_NAME
'TP_M_B_CPU1_SA_TEST39B'
 '@T6G_MB_LIB.T6G(SCH_1):TP_M_B_CPU1_SA_TEST39B':
 C_SIGNAL='@t6g_mb_lib.t6g(sch_1):tp_m_b_cpu1_sa_test39b';
NODE_NAME     U26 BF62
 '@T6G_MB_LIB.T6G(SCH_1):PAGE38_I159@PURE_QUANTA.GENOA_SP5(CHIPS)':
 'TEST39B': CDS_PINID='TEST39B';
NET_NAME
'TP_M_C_CPU0_SA_TEST39C'
 '@T6G_MB_LIB.T6G(SCH_1):TP_M_C_CPU0_SA_TEST39C':
 C_SIGNAL='@t6g_mb_lib.t6g(sch_1):tp_m_c_cpu0_sa_test39c';
NODE_NAME     U25 BF55
 '@T6G_MB_LIB.T6G(SCH_1):PAGE12_I159@PURE_QUANTA.GENOA_SP5(CHIPS)':
 'TEST39C': CDS_PINID='TEST39C';
NET_NAME
'TP_M_C_CPU1_SA_TEST39C'
 '@T6G_MB_LIB.T6G(SCH_1):TP_M_C_CPU1_SA_TEST39C':
 C_SIGNAL='@t6g_mb_lib.t6g(sch_1):tp_m_c_cpu1_sa_test39c';
NODE_NAME     U26 BF55
 '@T6G_MB_LIB.T6G(SCH_1):PAGE39_I159@PURE_QUANTA.GENOA_SP5(CHIPS)':
 'TEST39C': CDS_PINID='TEST39C';
NET_NAME
'TP_M_D_CPU0_SA_TEST39D'
 '@T6G_MB_LIB.T6G(SCH_1):TP_M_D_CPU0_SA_TEST39D':
 C_SIGNAL='@t6g_mb_lib.t6g(sch_1):tp_m_d_cpu0_sa_test39d';
NODE_NAME     U25 BF58
 '@T6G_MB_LIB.T6G(SCH_1):PAGE13_I159@PURE_QUANTA.GENOA_SP5(CHIPS)':
 'TEST39D': CDS_PINID='TEST39D';
NET_NAME
'TP_M_D_CPU1_SA_TEST39D'
 '@T6G_MB_LIB.T6G(SCH_1):TP_M_D_CPU1_SA_TEST39D':
 C_SIGNAL='@t6g_mb_lib.t6g(sch_1):tp_m_d_cpu1_sa_test39d';
NODE_NAME     U26 BF58
 '@T6G_MB_LIB.T6G(SCH_1):PAGE40_I159@PURE_QUANTA.GENOA_SP5(CHIPS)':
 'TEST39D': CDS_PINID='TEST39D';
NET_NAME
'TP_M_E_CPU0_SA_TEST39E'
 '@T6G_MB_LIB.T6G(SCH_1):TP_M_E_CPU0_SA_TEST39E':
 C_SIGNAL='@t6g_mb_lib.t6g(sch_1):tp_m_e_cpu0_sa_test39e';
NODE_NAME     U25 BF69
 '@T6G_MB_LIB.T6G(SCH_1):PAGE14_I159@PURE_QUANTA.GENOA_SP5(CHIPS)':
 'TEST39E': CDS_PINID='TEST39E';
NET_NAME
'TP_M_E_CPU1_SA_TEST39E'
 '@T6G_MB_LIB.T6G(SCH_1):TP_M_E_CPU1_SA_TEST39E':
 C_SIGNAL='@t6g_mb_lib.t6g(sch_1):tp_m_e_cpu1_sa_test39e';
NODE_NAME     U26 BF69
 '@T6G_MB_LIB.T6G(SCH_1):PAGE41_I159@PURE_QUANTA.GENOA_SP5(CHIPS)':
 'TEST39E': CDS_PINID='TEST39E';
NET_NAME
'TP_M_F_CPU0_SA_TEST39F'
 '@T6G_MB_LIB.T6G(SCH_1):TP_M_F_CPU0_SA_TEST39F':
 C_SIGNAL='@t6g_mb_lib.t6g(sch_1):tp_m_f_cpu0_sa_test39f';
NODE_NAME     U25 BF65
 '@T6G_MB_LIB.T6G(SCH_1):PAGE15_I159@PURE_QUANTA.GENOA_SP5(CHIPS)':
 'TEST39F': CDS_PINID='TEST39F';
NET_NAME
'TP_M_F_CPU1_SA_TEST39F'
 '@T6G_MB_LIB.T6G(SCH_1):TP_M_F_CPU1_SA_TEST39F':
 C_SIGNAL='@t6g_mb_lib.t6g(sch_1):tp_m_f_cpu1_sa_test39f';
NODE_NAME     U26 BF65
 '@T6G_MB_LIB.T6G(SCH_1):PAGE42_I159@PURE_QUANTA.GENOA_SP5(CHIPS)':
 'TEST39F': CDS_PINID='TEST39F';
NET_NAME
'TP_M_G_CPU0_SA_TEST39G'
 '@T6G_MB_LIB.T6G(SCH_1):TP_M_G_CPU0_SA_TEST39G':
 C_SIGNAL='@t6g_mb_lib.t6g(sch_1):tp_m_g_cpu0_sa_test39g';
NODE_NAME     U25 BF4
 '@T6G_MB_LIB.T6G(SCH_1):PAGE16_I167@PURE_QUANTA.GENOA_SP5(CHIPS)':
 'TEST39G': CDS_PINID='TEST39G';
NET_NAME
'TP_M_G_CPU1_SA_TEST39G'
 '@T6G_MB_LIB.T6G(SCH_1):TP_M_G_CPU1_SA_TEST39G':
 C_SIGNAL='@t6g_mb_lib.t6g(sch_1):tp_m_g_cpu1_sa_test39g';
NODE_NAME     U26 BF4
 '@T6G_MB_LIB.T6G(SCH_1):PAGE43_I167@PURE_QUANTA.GENOA_SP5(CHIPS)':
 'TEST39G': CDS_PINID='TEST39G';
NET_NAME
'TP_M_H_CPU0_SA_TEST39H'
 '@T6G_MB_LIB.T6G(SCH_1):TP_M_H_CPU0_SA_TEST39H':
 C_SIGNAL='@t6g_mb_lib.t6g(sch_1):tp_m_h_cpu0_sa_test39h';
NODE_NAME     U25 BF14
 '@T6G_MB_LIB.T6G(SCH_1):PAGE17_I159@PURE_QUANTA.GENOA_SP5(CHIPS)':
 'TEST39H': CDS_PINID='TEST39H';
NET_NAME
'TP_M_H_CPU1_SA_TEST39H'
 '@T6G_MB_LIB.T6G(SCH_1):TP_M_H_CPU1_SA_TEST39H':
 C_SIGNAL='@t6g_mb_lib.t6g(sch_1):tp_m_h_cpu1_sa_test39h';
NODE_NAME     U26 BF14
 '@T6G_MB_LIB.T6G(SCH_1):PAGE44_I159@PURE_QUANTA.GENOA_SP5(CHIPS)':
 'TEST39H': CDS_PINID='TEST39H';
NET_NAME
'TP_M_I_CPU0_SA_TEST39I'
 '@T6G_MB_LIB.T6G(SCH_1):TP_M_I_CPU0_SA_TEST39I':
 C_SIGNAL='@t6g_mb_lib.t6g(sch_1):tp_m_i_cpu0_sa_test39i';
NODE_NAME     U25 BF21
 '@T6G_MB_LIB.T6G(SCH_1):PAGE18_I159@PURE_QUANTA.GENOA_SP5(CHIPS)':
 'TEST39I': CDS_PINID='TEST39I';
NET_NAME
'TP_M_I_CPU1_SA_TEST39I'
 '@T6G_MB_LIB.T6G(SCH_1):TP_M_I_CPU1_SA_TEST39I':
 C_SIGNAL='@t6g_mb_lib.t6g(sch_1):tp_m_i_cpu1_sa_test39i';
NODE_NAME     U26 BF21
 '@T6G_MB_LIB.T6G(SCH_1):PAGE45_I159@PURE_QUANTA.GENOA_SP5(CHIPS)':
 'TEST39I': CDS_PINID='TEST39I';
NET_NAME
'TP_M_J_CPU0_SA_TEST39J'
 '@T6G_MB_LIB.T6G(SCH_1):TP_M_J_CPU0_SA_TEST39J':
 C_SIGNAL='@t6g_mb_lib.t6g(sch_1):tp_m_j_cpu0_sa_test39j';
NODE_NAME     U25 BF18
 '@T6G_MB_LIB.T6G(SCH_1):PAGE19_I159@PURE_QUANTA.GENOA_SP5(CHIPS)':
 'TEST39J': CDS_PINID='TEST39J';
NET_NAME
'TP_M_J_CPU1_SA_TEST39J'
 '@T6G_MB_LIB.T6G(SCH_1):TP_M_J_CPU1_SA_TEST39J':
 C_SIGNAL='@t6g_mb_lib.t6g(sch_1):tp_m_j_cpu1_sa_test39j';
NODE_NAME     U26 BF18
 '@T6G_MB_LIB.T6G(SCH_1):PAGE46_I159@PURE_QUANTA.GENOA_SP5(CHIPS)':
 'TEST39J': CDS_PINID='TEST39J';
NET_NAME
'TP_M_K_CPU0_SA_TEST39K'
 '@T6G_MB_LIB.T6G(SCH_1):TP_M_K_CPU0_SA_TEST39K':
 C_SIGNAL='@t6g_mb_lib.t6g(sch_1):tp_m_k_cpu0_sa_test39k';
NODE_NAME     U25 BF7
 '@T6G_MB_LIB.T6G(SCH_1):PAGE20_I159@PURE_QUANTA.GENOA_SP5(CHIPS)':
 'TEST39K': CDS_PINID='TEST39K';
NET_NAME
'TP_M_K_CPU1_SA_TEST39K'
 '@T6G_MB_LIB.T6G(SCH_1):TP_M_K_CPU1_SA_TEST39K':
 C_SIGNAL='@t6g_mb_lib.t6g(sch_1):tp_m_k_cpu1_sa_test39k';
NODE_NAME     U26 BF7
 '@T6G_MB_LIB.T6G(SCH_1):PAGE47_I159@PURE_QUANTA.GENOA_SP5(CHIPS)':
 'TEST39K': CDS_PINID='TEST39K';
NET_NAME
'TP_M_L_CPU0_SA_TEST39L'
 '@T6G_MB_LIB.T6G(SCH_1):TP_M_L_CPU0_SA_TEST39L':
 C_SIGNAL='@t6g_mb_lib.t6g(sch_1):tp_m_l_cpu0_sa_test39l';
NODE_NAME     U25 BF11
 '@T6G_MB_LIB.T6G(SCH_1):PAGE21_I159@PURE_QUANTA.GENOA_SP5(CHIPS)':
 'TEST39L': CDS_PINID='TEST39L';
NET_NAME
'TP_M_L_CPU1_SA_TEST39L'
 '@T6G_MB_LIB.T6G(SCH_1):TP_M_L_CPU1_SA_TEST39L':
 C_SIGNAL='@t6g_mb_lib.t6g(sch_1):tp_m_l_cpu1_sa_test39l';
NODE_NAME     U26 BF11
 '@T6G_MB_LIB.T6G(SCH_1):PAGE48_I159@PURE_QUANTA.GENOA_SP5(CHIPS)':
 'TEST39L': CDS_PINID='TEST39L';
NET_NAME
'TP_OCP_SFF_B68'
 '@T6G_MB_LIB.T6G(SCH_1):TP_OCP_SFF_B68':
 C_SIGNAL='@t6g_mb_lib.t6g(sch_1):tp_ocp_sff_b68';
NODE_NAME     J38 B68
 '@T6G_MB_LIB.T6G(SCH_1):PAGE335_I168@PURE_QUANTA.SCONN168_ME1016810202011(CHIPS)':
 'RFU1_NC_B68': CDS_PINID='RFU1_NC_B68';
NET_NAME
'TP_OCP_SFF_B69'
 '@T6G_MB_LIB.T6G(SCH_1):TP_OCP_SFF_B69':
 C_SIGNAL='@t6g_mb_lib.t6g(sch_1):tp_ocp_sff_b69';
NODE_NAME     J38 B69
 '@T6G_MB_LIB.T6G(SCH_1):PAGE335_I168@PURE_QUANTA.SCONN168_ME1016810202011(CHIPS)':
 'RFU1_NC_B69': CDS_PINID='RFU1_NC_B69';
NET_NAME
'TP_OCP_V3_2_B68'
 '@T6G_MB_LIB.T6G(SCH_1):TP_OCP_V3_2_B68':
 C_SIGNAL='@t6g_mb_lib.t6g(sch_1):tp_ocp_v3_2_b68';
NODE_NAME     J35 B68
 '@T6G_MB_LIB.T6G(SCH_1):PAGE341_I168@PURE_QUANTA.SCONN168_ME1016810202011(CHIPS)':
 'RFU1_NC_B68': CDS_PINID='RFU1_NC_B68';
NET_NAME
'TP_OCP_V3_2_B69'
 '@T6G_MB_LIB.T6G(SCH_1):TP_OCP_V3_2_B69':
 C_SIGNAL='@t6g_mb_lib.t6g(sch_1):tp_ocp_v3_2_b69';
NODE_NAME     J35 B69
 '@T6G_MB_LIB.T6G(SCH_1):PAGE341_I168@PURE_QUANTA.SCONN168_ME1016810202011(CHIPS)':
 'RFU1_NC_B69': CDS_PINID='RFU1_NC_B69';
NET_NAME
'TP_P0V9_RETIMER_CPU0_PMALERT'
 '@T6G_MB_LIB.T6G(SCH_1):TP_P0V9_RETIMER_CPU0_PMALERT':
 C_SIGNAL='@t6g_mb_lib.t6g(sch_1):tp_p0v9_retimer_cpu0_pmalert';
NODE_NAME     PU6502 11
 '@T6G_MB_LIB.T6G(SCH_1):PAGE475_I42@PURE_QUANTA.ISL69260IRAZT(CHIPS)':
 'NPMALERT#': CDS_PINID='\npmalert#\';
NODE_NAME     R649 2
 '@T6G_MB_LIB.T6G(SCH_1):PAGE475_I207@PURE_QUANTA.Q_RES(CHIPS)':
 'B': CDS_PINID='B';
NET_NAME
'TP_P0V9_RETIMER_CPU0_SVID_ALERT_N'
 '@T6G_MB_LIB.T6G(SCH_1):TP_P0V9_RETIMER_CPU0_SVID_ALERT_N':
 C_SIGNAL='@t6g_mb_lib.t6g(sch_1):tp_p0v9_retimer_cpu0_svid_alert_n';
NODE_NAME     PU6502 19
 '@T6G_MB_LIB.T6G(SCH_1):PAGE475_I42@PURE_QUANTA.ISL69260IRAZT(CHIPS)':
 'NSVALERT#': CDS_PINID='\nsvalert#\';
NODE_NAME     PR6817 2
 '@T6G_MB_LIB.T6G(SCH_1):PAGE475_I169@PURE_QUANTA.Q_RES(CHIPS)':
 'B': CDS_PINID='B';
NODE_NAME     PR883 1
 '@T6G_MB_LIB.T6G(SCH_1):PAGE475_I210@PURE_QUANTA.Q_RES(CHIPS)':
 'A': CDS_PINID='A';
NET_NAME
'TP_P0V9_RETIMER_CPU0_VRHOT'
 '@T6G_MB_LIB.T6G(SCH_1):TP_P0V9_RETIMER_CPU0_VRHOT':
 C_SIGNAL='@t6g_mb_lib.t6g(sch_1):tp_p0v9_retimer_cpu0_vrhot';
NODE_NAME     PR6615 2
 '@T6G_MB_LIB.T6G(SCH_1):PAGE475_I135@PURE_QUANTA.Q_RES(CHIPS)':
 'B': CDS_PINID='B';
NODE_NAME     PR6616 2
 '@T6G_MB_LIB.T6G(SCH_1):PAGE475_I136@PURE_QUANTA.Q_RES(CHIPS)':
 'B': CDS_PINID='B';
NET_NAME
'TP_P0V9_RETIMER_CPU1_PMALERT'
 '@T6G_MB_LIB.T6G(SCH_1):TP_P0V9_RETIMER_CPU1_PMALERT':
 C_SIGNAL='@t6g_mb_lib.t6g(sch_1):tp_p0v9_retimer_cpu1_pmalert';
NODE_NAME     PU6510 11
 '@T6G_MB_LIB.T6G(SCH_1):PAGE477_I88@PURE_QUANTA.ISL69260IRAZT(CHIPS)':
 'NPMALERT#': CDS_PINID='\npmalert#\';
NODE_NAME     R660 2
 '@T6G_MB_LIB.T6G(SCH_1):PAGE477_I89@PURE_QUANTA.Q_RES(CHIPS)':
 'B': CDS_PINID='B';
NET_NAME
'TP_P0V9_RETIMER_CPU1_SVID_ALERT_N'
 '@T6G_MB_LIB.T6G(SCH_1):TP_P0V9_RETIMER_CPU1_SVID_ALERT_N':
 C_SIGNAL='@t6g_mb_lib.t6g(sch_1):tp_p0v9_retimer_cpu1_svid_alert_n';
NODE_NAME     PR6818 2
 '@T6G_MB_LIB.T6G(SCH_1):PAGE477_I32@PURE_QUANTA.Q_RES(CHIPS)':
 'B': CDS_PINID='B';
NODE_NAME     PR6802 1
 '@T6G_MB_LIB.T6G(SCH_1):PAGE477_I44@PURE_QUANTA.Q_RES(CHIPS)':
 'A': CDS_PINID='A';
NODE_NAME     PU6510 19
 '@T6G_MB_LIB.T6G(SCH_1):PAGE477_I88@PURE_QUANTA.ISL69260IRAZT(CHIPS)':
 'NSVALERT#': CDS_PINID='\nsvalert#\';
NET_NAME
'TP_P0V9_RETIMER_CPU1_VRHOT'
 '@T6G_MB_LIB.T6G(SCH_1):TP_P0V9_RETIMER_CPU1_VRHOT':
 C_SIGNAL='@t6g_mb_lib.t6g(sch_1):tp_p0v9_retimer_cpu1_vrhot';
NODE_NAME     PR6816 2
 '@T6G_MB_LIB.T6G(SCH_1):PAGE477_I56@PURE_QUANTA.Q_RES(CHIPS)':
 'B': CDS_PINID='B';
NODE_NAME     PR6812 2
 '@T6G_MB_LIB.T6G(SCH_1):PAGE477_I86@PURE_QUANTA.Q_RES(CHIPS)':
 'B': CDS_PINID='B';
NET_NAME
'TP_P12V_AUX_CPU0_DIMM_ISEN_N'
 '@T6G_MB_LIB.T6G(SCH_1):TP_P12V_AUX_CPU0_DIMM_ISEN_N':
 C_SIGNAL='@t6g_mb_lib.t6g(sch_1):tp_p12v_aux_cpu0_dimm_isen_n';
NODE_NAME     R1838 4
 '@T6G_MB_LIB.T6G(SCH_1):PAGE264_I58@PURE_QUANTA.Q_RES_4P_12(CHIPS)':
 '4': CDS_PINID='\4\';
NET_NAME
'TP_P12V_AUX_CPU0_DIMM_ISEN_P'
 '@T6G_MB_LIB.T6G(SCH_1):TP_P12V_AUX_CPU0_DIMM_ISEN_P':
 C_SIGNAL='@t6g_mb_lib.t6g(sch_1):tp_p12v_aux_cpu0_dimm_isen_p';
NODE_NAME     R1838 3
 '@T6G_MB_LIB.T6G(SCH_1):PAGE264_I58@PURE_QUANTA.Q_RES_4P_12(CHIPS)':
 '3': CDS_PINID='\3\';
NET_NAME
'TP_P12V_AUX_CPU1_DIMM_ISEN_N'
 '@T6G_MB_LIB.T6G(SCH_1):TP_P12V_AUX_CPU1_DIMM_ISEN_N':
 C_SIGNAL='@t6g_mb_lib.t6g(sch_1):tp_p12v_aux_cpu1_dimm_isen_n';
NODE_NAME     R1837 4
 '@T6G_MB_LIB.T6G(SCH_1):PAGE264_I54@PURE_QUANTA.Q_RES_4P_12(CHIPS)':
 '4': CDS_PINID='\4\';
NET_NAME
'TP_P12V_AUX_CPU1_DIMM_ISEN_P'
 '@T6G_MB_LIB.T6G(SCH_1):TP_P12V_AUX_CPU1_DIMM_ISEN_P':
 C_SIGNAL='@t6g_mb_lib.t6g(sch_1):tp_p12v_aux_cpu1_dimm_isen_p';
NODE_NAME     R1837 3
 '@T6G_MB_LIB.T6G(SCH_1):PAGE264_I54@PURE_QUANTA.Q_RES_4P_12(CHIPS)':
 '3': CDS_PINID='\3\';
NET_NAME
'TP_PCIE_RXN<1>'
 '@T6G_MB_LIB.T6G(SCH_1):TP_PCIE_RXN'<1>:
 C_SIGNAL='@t6g_mb_lib.t6g(sch_1):tp_pcie_rxn(1)';
NODE_NAME     J41 A63
 '@T6G_MB_LIB.T6G(SCH_1):PAGE348_I176@PURE_QUANTA.SCONN168_ME1016810202011(CHIPS)':
 'PERP14': CDS_PINID='PERP14';
NET_NAME
'TP_PCIE_RXP<1>'
 '@T6G_MB_LIB.T6G(SCH_1):TP_PCIE_RXP'<1>:
 C_SIGNAL='@t6g_mb_lib.t6g(sch_1):tp_pcie_rxp(1)';
NODE_NAME     J41 A62
 '@T6G_MB_LIB.T6G(SCH_1):PAGE348_I176@PURE_QUANTA.SCONN168_ME1016810202011(CHIPS)':
 'PERN14': CDS_PINID='PERN14';
NET_NAME
'TP_PCIE_TXN<1>'
 '@T6G_MB_LIB.T6G(SCH_1):TP_PCIE_TXN'<1>:
 C_SIGNAL='@t6g_mb_lib.t6g(sch_1):tp_pcie_txn(1)';
NODE_NAME     J41 B63
 '@T6G_MB_LIB.T6G(SCH_1):PAGE348_I176@PURE_QUANTA.SCONN168_ME1016810202011(CHIPS)':
 'PETP14': CDS_PINID='PETP14';
NET_NAME
'TP_PCIE_TXP<1>'
 '@T6G_MB_LIB.T6G(SCH_1):TP_PCIE_TXP'<1>:
 C_SIGNAL='@t6g_mb_lib.t6g(sch_1):tp_pcie_txp(1)';
NODE_NAME     J41 B62
 '@T6G_MB_LIB.T6G(SCH_1):PAGE348_I176@PURE_QUANTA.SCONN168_ME1016810202011(CHIPS)':
 'PETN14': CDS_PINID='PETN14';
NET_NAME
'TP_PCIE_TXP<3>'
 '@T6G_MB_LIB.T6G(SCH_1):TP_PCIE_TXP'<3>:
 C_SIGNAL='@t6g_mb_lib.t6g(sch_1):tp_pcie_txp(3)';
NODE_NAME     R3254 1
 '@T6G_MB_LIB.T6G(SCH_1):PAGE348_I50@PURE_QUANTA.Q_RES(CHIPS)':
 'A': CDS_PINID='A';
NODE_NAME     J41 B68
 '@T6G_MB_LIB.T6G(SCH_1):PAGE348_I176@PURE_QUANTA.SCONN168_ME1016810202011(CHIPS)':
 'RFU1_NC_B68': CDS_PINID='RFU1_NC_B68';
NET_NAME
'TP_PECI_BMC'
 '@T6G_MB_LIB.T6G(SCH_1):TP_PECI_BMC':
 C_SIGNAL='@t6g_mb_lib.t6g(sch_1):tp_peci_bmc';
NODE_NAME     J41 B27
 '@T6G_MB_LIB.T6G(SCH_1):PAGE348_I176@PURE_QUANTA.SCONN168_ME1016810202011(CHIPS)':
 'PETP3': CDS_PINID='PETP3';
NET_NAME
'TP_PVCCIO_PECI_BMC'
 '@T6G_MB_LIB.T6G(SCH_1):TP_PVCCIO_PECI_BMC':
 C_SIGNAL='@t6g_mb_lib.t6g(sch_1):tp_pvccio_peci_bmc';
NODE_NAME     J41 B28
 '@T6G_MB_LIB.T6G(SCH_1):PAGE348_I176@PURE_QUANTA.SCONN168_ME1016810202011(CHIPS)':
 'GND_B28': CDS_PINID='GND_B28';
NET_NAME
'TP_PWRGD_P12V_FAN_DR_R'
 '@T6G_MB_LIB.T6G(SCH_1):TP_PWRGD_P12V_FAN_DR_R':
 C_SIGNAL='@t6g_mb_lib.t6g(sch_1):tp_pwrgd_p12v_fan_dr_r';
NODE_NAME     U18 N20
 '@T6G_MB_LIB.T6G(SCH_1):PAGE80_I217@PURE_QUANTA.LCMXO3LF9400C5BG484C(CHIPS)':
 'PR19C': CDS_PINID='PR19C';
NET_NAME
'TP_SLOT1_CLKREQ_0_R_N'
 '@T6G_MB_LIB.T6G(SCH_1):TP_SLOT1_CLKREQ_0_R_N':
 C_SIGNAL='@t6g_mb_lib.t6g(sch_1):tp_slot1_clkreq_0_r_n';
NODE_NAME     U18 F18
 '@T6G_MB_LIB.T6G(SCH_1):PAGE80_I217@PURE_QUANTA.LCMXO3LF9400C5BG484C(CHIPS)':
 'PR5C': CDS_PINID='PR5C';
NET_NAME
'TP_SLOT2_BUF_SKU_ID0'
 '@T6G_MB_LIB.T6G(SCH_1):TP_SLOT2_BUF_SKU_ID0':
 C_SIGNAL='@t6g_mb_lib.t6g(sch_1):tp_slot2_buf_sku_id0';
NODE_NAME     U26 DF33
 '@T6G_MB_LIB.T6G(SCH_1):PAGE55_I182@PURE_QUANTA.GENOA_SP5(CHIPS)':
 'AGPIO21': CDS_PINID='AGPIO21';
NET_NAME
'TP_SLOT2_BUF_SKU_ID1'
 '@T6G_MB_LIB.T6G(SCH_1):TP_SLOT2_BUF_SKU_ID1':
 C_SIGNAL='@t6g_mb_lib.t6g(sch_1):tp_slot2_buf_sku_id1';
NODE_NAME     U26 DE32
 '@T6G_MB_LIB.T6G(SCH_1):PAGE55_I182@PURE_QUANTA.GENOA_SP5(CHIPS)':
 'AGPIO22': CDS_PINID='AGPIO22';
NET_NAME
'TP_SLOT2_CLKREQ_0_R_N'
 '@T6G_MB_LIB.T6G(SCH_1):TP_SLOT2_CLKREQ_0_R_N':
 C_SIGNAL='@t6g_mb_lib.t6g(sch_1):tp_slot2_clkreq_0_r_n';
NODE_NAME     U18 J21
 '@T6G_MB_LIB.T6G(SCH_1):PAGE80_I217@PURE_QUANTA.LCMXO3LF9400C5BG484C(CHIPS)':
 'PR12A': CDS_PINID='PR12A';
NET_NAME
'TP_SPI_2_PLD_CLK'
 '@T6G_MB_LIB.T6G(SCH_1):TP_SPI_2_PLD_CLK':
 C_SIGNAL='@t6g_mb_lib.t6g(sch_1):tp_spi_2_pld_clk';
NODE_NAME     J41 B43
 '@T6G_MB_LIB.T6G(SCH_1):PAGE348_I176@PURE_QUANTA.SCONN168_ME1016810202011(CHIPS)':
 'GND_B43': CDS_PINID='GND_B43';
NET_NAME
'TP_SPI_2_PLD_CS_N'
 '@T6G_MB_LIB.T6G(SCH_1):TP_SPI_2_PLD_CS_N':
 C_SIGNAL='@t6g_mb_lib.t6g(sch_1):tp_spi_2_pld_cs_n';
NODE_NAME     J41 B44
 '@T6G_MB_LIB.T6G(SCH_1):PAGE348_I176@PURE_QUANTA.SCONN168_ME1016810202011(CHIPS)':
 'PETN8': CDS_PINID='PETN8';
NET_NAME
'TP_SPI_2_PLD_IO0'
 '@T6G_MB_LIB.T6G(SCH_1):TP_SPI_2_PLD_IO0':
 C_SIGNAL='@t6g_mb_lib.t6g(sch_1):tp_spi_2_pld_io0';
NODE_NAME     J41 B45
 '@T6G_MB_LIB.T6G(SCH_1):PAGE348_I176@PURE_QUANTA.SCONN168_ME1016810202011(CHIPS)':
 'PETP8': CDS_PINID='PETP8';
NET_NAME
'TP_SPI_2_PLD_IO1'
 '@T6G_MB_LIB.T6G(SCH_1):TP_SPI_2_PLD_IO1':
 C_SIGNAL='@t6g_mb_lib.t6g(sch_1):tp_spi_2_pld_io1';
NODE_NAME     J41 B46
 '@T6G_MB_LIB.T6G(SCH_1):PAGE348_I176@PURE_QUANTA.SCONN168_ME1016810202011(CHIPS)':
 'GND_B46': CDS_PINID='GND_B46';
NET_NAME
'TP_SPI_2_PLD_IO2'
 '@T6G_MB_LIB.T6G(SCH_1):TP_SPI_2_PLD_IO2':
 C_SIGNAL='@t6g_mb_lib.t6g(sch_1):tp_spi_2_pld_io2';
NODE_NAME     J41 B47
 '@T6G_MB_LIB.T6G(SCH_1):PAGE348_I176@PURE_QUANTA.SCONN168_ME1016810202011(CHIPS)':
 'PETN9': CDS_PINID='PETN9';
NET_NAME
'TP_SPI_2_PLD_IO3'
 '@T6G_MB_LIB.T6G(SCH_1):TP_SPI_2_PLD_IO3':
 C_SIGNAL='@t6g_mb_lib.t6g(sch_1):tp_spi_2_pld_io3';
NODE_NAME     J41 B48
 '@T6G_MB_LIB.T6G(SCH_1):PAGE348_I176@PURE_QUANTA.SCONN168_ME1016810202011(CHIPS)':
 'PETP9': CDS_PINID='PETP9';
NET_NAME
'TP_STBY_EN'
 '@T6G_MB_LIB.T6G(SCH_1):TP_STBY_EN':
 C_SIGNAL='@t6g_mb_lib.t6g(sch_1):tp_stby_en';
NODE_NAME     J41 A45
 '@T6G_MB_LIB.T6G(SCH_1):PAGE348_I176@PURE_QUANTA.SCONN168_ME1016810202011(CHIPS)':
 'PERP8': CDS_PINID='PERP8';
NET_NAME
'TP_TCA9539_0_P0_2'
 '@T6G_MB_LIB.T6G(SCH_1):TP_TCA9539_0_P0_2':
 C_SIGNAL='@t6g_mb_lib.t6g(sch_1):tp_tca9539_0_p0_2';
NODE_NAME     U181 6
 '@T6G_MB_LIB.T6G(SCH_1):PAGE246_I83@PURE_QUANTA.PCA9539RPW(CHIPS)':
 'IO0_2': CDS_PINID='IO0_2';
NET_NAME
'TP_TCA9539_0_P0_3'
 '@T6G_MB_LIB.T6G(SCH_1):TP_TCA9539_0_P0_3':
 C_SIGNAL='@t6g_mb_lib.t6g(sch_1):tp_tca9539_0_p0_3';
NODE_NAME     U181 7
 '@T6G_MB_LIB.T6G(SCH_1):PAGE246_I83@PURE_QUANTA.PCA9539RPW(CHIPS)':
 'IO0_3': CDS_PINID='IO0_3';
NET_NAME
'TP_U27_EN'
 '@T6G_MB_LIB.T6G(SCH_1):TP_U27_EN':
 C_SIGNAL='@t6g_mb_lib.t6g(sch_1):tp_u27_en';
NODE_NAME     U27 5
 '@T6G_MB_LIB.T6G(SCH_1):PAGE34_I18@PURE_QUANTA.PCA9617ADP(CHIPS)':
 'EN': CDS_PINID='EN';
NET_NAME
'TP_UART_CPU0_UART0_RTS_N'
 '@T6G_MB_LIB.T6G(SCH_1):TP_UART_CPU0_UART0_RTS_N':
 C_SIGNAL='@t6g_mb_lib.t6g(sch_1):tp_uart_cpu0_uart0_rts_n';
NODE_NAME     U25 DF34
 '@T6G_MB_LIB.T6G(SCH_1):PAGE27_I227@PURE_QUANTA.GENOA_SP5(CHIPS)':
 'UART0_RTS_L||UART2_RXD||AGPIO137': CDS_PINID='\uart0_rts_l||uart2_rxd||agpio137\';
NET_NAME
'TP_USB2_CD'
 '@T6G_MB_LIB.T6G(SCH_1):TP_USB2_CD':
 C_SIGNAL='@t6g_mb_lib.t6g(sch_1):tp_usb2_cd';
NODE_NAME     U5201 4
 '@T6G_MB_LIB.T6G(SCH_1):PAGE358_I84@PURE_QUANTA.TUSB211IRWBR(CHIPS)':
 'CD': CDS_PINID='CD';
NET_NAME
'TP_USB2_ENA_HS'
 '@T6G_MB_LIB.T6G(SCH_1):TP_USB2_ENA_HS':
 C_SIGNAL='@t6g_mb_lib.t6g(sch_1):tp_usb2_ena_hs';
NODE_NAME     U5201 9
 '@T6G_MB_LIB.T6G(SCH_1):PAGE358_I84@PURE_QUANTA.TUSB211IRWBR(CHIPS)':
 'ENA_HS': CDS_PINID='ENA_HS';
NET_NAME
'TP_USB2_TEST'
 '@T6G_MB_LIB.T6G(SCH_1):TP_USB2_TEST':
 C_SIGNAL='@t6g_mb_lib.t6g(sch_1):tp_usb2_test';
NODE_NAME     U5201 3
 '@T6G_MB_LIB.T6G(SCH_1):PAGE358_I84@PURE_QUANTA.TUSB211IRWBR(CHIPS)':
 'TEST': CDS_PINID='TEST';
NET_NAME
'TP_VSENSE_PVDD33_S5_P0'
 '@T6G_MB_LIB.T6G(SCH_1):TP_VSENSE_PVDD33_S5_P0':
 C_SIGNAL='@t6g_mb_lib.t6g(sch_1):tp_vsense_pvdd33_s5_p0';
NODE_NAME     U25 BP53
 '@T6G_MB_LIB.T6G(SCH_1):PAGE27_I227@PURE_QUANTA.GENOA_SP5(CHIPS)':
 'VDD_33_S5_SENSE': CDS_PINID='VDD_33_S5_SENSE';
NET_NAME
'TP_VSENSE_PVDD33_S5_P1'
 '@T6G_MB_LIB.T6G(SCH_1):TP_VSENSE_PVDD33_S5_P1':
 C_SIGNAL='@t6g_mb_lib.t6g(sch_1):tp_vsense_pvdd33_s5_p1';
NODE_NAME     U26 BP53
 '@T6G_MB_LIB.T6G(SCH_1):PAGE54_I190@PURE_QUANTA.GENOA_SP5(CHIPS)':
 'VDD_33_S5_SENSE': CDS_PINID='VDD_33_S5_SENSE';
NET_NAME
'U11_E2'
 '@T6G_MB_LIB.T6G(SCH_1):U11_E2':
 C_SIGNAL='@t6g_mb_lib.t6g(sch_1):u11_e2';
NODE_NAME     U11 3
 '@T6G_MB_LIB.T6G(SCH_1):PAGE387_I3@PURE_QUANTA.M24M02DRMN6TP(CHIPS)':
 'E2': CDS_PINID='E2';
NODE_NAME     R6822 1
 '@T6G_MB_LIB.T6G(SCH_1):PAGE387_I24@PURE_QUANTA.Q_RES(CHIPS)':
 'A': CDS_PINID='A';
NET_NAME
'U124_VCC'
 '@T6G_MB_LIB.T6G(SCH_1):U124_VCC':
 C_SIGNAL='@t6g_mb_lib.t6g(sch_1):u124_vcc';
NODE_NAME     U124 5
 '@T6G_MB_LIB.T6G(SCH_1):PAGE144_I38@PURE_QUANTA.SN74LVC1G07DBVR(CHIPS)':
 'VCC': CDS_PINID='VCC';
NODE_NAME     C693 1
 '@T6G_MB_LIB.T6G(SCH_1):PAGE144_I39@PURE_QUANTA.Q_CAP(CHIPS)':
 'A': CDS_PINID='A';
NODE_NAME     R8018 2
 '@T6G_MB_LIB.T6G(SCH_1):PAGE144_I84@PURE_QUANTA.Q_RES(CHIPS)':
 'B': CDS_PINID='B';
NODE_NAME     R8017 2
 '@T6G_MB_LIB.T6G(SCH_1):PAGE144_I85@PURE_QUANTA.Q_RES(CHIPS)':
 'B': CDS_PINID='B';
NET_NAME
'U12_E2'
 '@T6G_MB_LIB.T6G(SCH_1):U12_E2':
 C_SIGNAL='@t6g_mb_lib.t6g(sch_1):u12_e2';
NODE_NAME     U12 3
 '@T6G_MB_LIB.T6G(SCH_1):PAGE399_I5@PURE_QUANTA.M24M02DRMN6TP(CHIPS)':
 'E2': CDS_PINID='E2';
NODE_NAME     R6788 1
 '@T6G_MB_LIB.T6G(SCH_1):PAGE399_I13@PURE_QUANTA.Q_RES(CHIPS)':
 'A': CDS_PINID='A';
NET_NAME
'U142_VS'
 '@T6G_MB_LIB.T6G(SCH_1):U142_VS':
 C_SIGNAL='@t6g_mb_lib.t6g(sch_1):u142_vs';
NODE_NAME     U142 5
 '@T6G_MB_LIB.T6G(SCH_1):PAGE371_I50@PURE_QUANTA.LT6700CS61TRPBF(CHIPS)':
 'VS': CDS_PINID='VS';
NODE_NAME     C6084 1
 '@T6G_MB_LIB.T6G(SCH_1):PAGE371_I107@PURE_QUANTA.Q_CAP(CHIPS)':
 'A': CDS_PINID='A';
NODE_NAME     R9020 2
 '@T6G_MB_LIB.T6G(SCH_1):PAGE371_I108@PURE_QUANTA.Q_RES(CHIPS)':
 'B': CDS_PINID='B';
NODE_NAME     C9003 1
 '@T6G_MB_LIB.T6G(SCH_1):PAGE371_I110@PURE_QUANTA.Q_CAP(CHIPS)':
 'A': CDS_PINID='A';
NET_NAME
'U152_OE_N'
 '@T6G_MB_LIB.T6G(SCH_1):U152_OE_N':
 C_SIGNAL='@t6g_mb_lib.t6g(sch_1):u152_oe_n';
NODE_NAME     U152 2
 '@T6G_MB_LIB.T6G(SCH_1):PAGE150_I60@PURE_QUANTA.SN74AVC2T245RSWR(CHIPS)':
 'OE_#': CDS_PINID='\oe_#\';
NODE_NAME     R1637 1
 '@T6G_MB_LIB.T6G(SCH_1):PAGE150_I71@PURE_QUANTA.Q_RES(CHIPS)':
 'A': CDS_PINID='A';
NET_NAME
'U15_E2'
 '@T6G_MB_LIB.T6G(SCH_1):U15_E2':
 C_SIGNAL='@t6g_mb_lib.t6g(sch_1):u15_e2';
NODE_NAME     U15 3
 '@T6G_MB_LIB.T6G(SCH_1):PAGE410_I5@PURE_QUANTA.M24M02DRMN6TP(CHIPS)':
 'E2': CDS_PINID='E2';
NODE_NAME     R1044 1
 '@T6G_MB_LIB.T6G(SCH_1):PAGE410_I20@PURE_QUANTA.Q_RES(CHIPS)':
 'A': CDS_PINID='A';
NET_NAME
'U160_EN_N'
 '@T6G_MB_LIB.T6G(SCH_1):U160_EN_N':
 C_SIGNAL='@t6g_mb_lib.t6g(sch_1):u160_en_n';
NODE_NAME     U160 6
 '@T6G_MB_LIB.T6G(SCH_1):PAGE148_I266@PURE_QUANTA.74LV4052PW(CHIPS)':
 'E_N': CDS_PINID='E_N';
NODE_NAME     JP6001 2
 '@T6G_MB_LIB.T6G(SCH_1):PAGE148_I387@PURE_QUANTA.CONN3_210HP1030BR1(CHIPS)':
 '2': CDS_PINID='\2\';
NET_NAME
'U16_E2'
 '@T6G_MB_LIB.T6G(SCH_1):U16_E2':
 C_SIGNAL='@t6g_mb_lib.t6g(sch_1):u16_e2';
NODE_NAME     U16 3
 '@T6G_MB_LIB.T6G(SCH_1):PAGE421_I5@PURE_QUANTA.M24M02DRMN6TP(CHIPS)':
 'E2': CDS_PINID='E2';
NODE_NAME     R1085 1
 '@T6G_MB_LIB.T6G(SCH_1):PAGE421_I18@PURE_QUANTA.Q_RES(CHIPS)':
 'A': CDS_PINID='A';
NET_NAME
'U17_E2'
 '@T6G_MB_LIB.T6G(SCH_1):U17_E2':
 C_SIGNAL='@t6g_mb_lib.t6g(sch_1):u17_e2';
NODE_NAME     U17 3
 '@T6G_MB_LIB.T6G(SCH_1):PAGE432_I5@PURE_QUANTA.M24M02DRMN6TP(CHIPS)':
 'E2': CDS_PINID='E2';
NODE_NAME     R1127 1
 '@T6G_MB_LIB.T6G(SCH_1):PAGE432_I18@PURE_QUANTA.Q_RES(CHIPS)':
 'A': CDS_PINID='A';
NET_NAME
'U19_E2'
 '@T6G_MB_LIB.T6G(SCH_1):U19_E2':
 C_SIGNAL='@t6g_mb_lib.t6g(sch_1):u19_e2';
NODE_NAME     U19 3
 '@T6G_MB_LIB.T6G(SCH_1):PAGE442_I5@PURE_QUANTA.M24M02DRMN6TP(CHIPS)':
 'E2': CDS_PINID='E2';
NODE_NAME     R6789 1
 '@T6G_MB_LIB.T6G(SCH_1):PAGE442_I19@PURE_QUANTA.Q_RES(CHIPS)':
 'A': CDS_PINID='A';
NET_NAME
'U206_VS'
 '@T6G_MB_LIB.T6G(SCH_1):U206_VS':
 C_SIGNAL='@t6g_mb_lib.t6g(sch_1):u206_vs';
NODE_NAME     U206 5
 '@T6G_MB_LIB.T6G(SCH_1):PAGE372_I49@PURE_QUANTA.LT6700CS61TRPBF(CHIPS)':
 'VS': CDS_PINID='VS';
NODE_NAME     C1561 1
 '@T6G_MB_LIB.T6G(SCH_1):PAGE372_I96@PURE_QUANTA.Q_CAP(CHIPS)':
 'A': CDS_PINID='A';
NODE_NAME     R9021 2
 '@T6G_MB_LIB.T6G(SCH_1):PAGE372_I97@PURE_QUANTA.Q_RES(CHIPS)':
 'B': CDS_PINID='B';
NODE_NAME     C9004 1
 '@T6G_MB_LIB.T6G(SCH_1):PAGE372_I99@PURE_QUANTA.Q_CAP(CHIPS)':
 'A': CDS_PINID='A';
NET_NAME
'U20_E2'
 '@T6G_MB_LIB.T6G(SCH_1):U20_E2':
 C_SIGNAL='@t6g_mb_lib.t6g(sch_1):u20_e2';
NODE_NAME     U20 3
 '@T6G_MB_LIB.T6G(SCH_1):PAGE453_I5@PURE_QUANTA.M24M02DRMN6TP(CHIPS)':
 'E2': CDS_PINID='E2';
NODE_NAME     R6790 1
 '@T6G_MB_LIB.T6G(SCH_1):PAGE453_I19@PURE_QUANTA.Q_RES(CHIPS)':
 'A': CDS_PINID='A';
NET_NAME
'U212_EN_N'
 '@T6G_MB_LIB.T6G(SCH_1):U212_EN_N':
 C_SIGNAL='@t6g_mb_lib.t6g(sch_1):u212_en_n';
NODE_NAME     U212 6
 '@T6G_MB_LIB.T6G(SCH_1):PAGE148_I302@PURE_QUANTA.74LV4052PW(CHIPS)':
 'E_N': CDS_PINID='E_N';
NODE_NAME     JP6000 2
 '@T6G_MB_LIB.T6G(SCH_1):PAGE148_I386@PURE_QUANTA.CONN3_210HP1030BR1(CHIPS)':
 '2': CDS_PINID='\2\';
NET_NAME
'U21_E2'
 '@T6G_MB_LIB.T6G(SCH_1):U21_E2':
 C_SIGNAL='@t6g_mb_lib.t6g(sch_1):u21_e2';
NODE_NAME     U21 3
 '@T6G_MB_LIB.T6G(SCH_1):PAGE464_I5@PURE_QUANTA.M24M02DRMN6TP(CHIPS)':
 'E2': CDS_PINID='E2';
NODE_NAME     R6791 1
 '@T6G_MB_LIB.T6G(SCH_1):PAGE464_I22@PURE_QUANTA.Q_RES(CHIPS)':
 'A': CDS_PINID='A';
NET_NAME
'U270_0_ADD0'
 '@T6G_MB_LIB.T6G(SCH_1):U270_0_ADD0':
 C_SIGNAL='@t6g_mb_lib.t6g(sch_1):u270_0_add0';
NODE_NAME     R4207 1
 '@T6G_MB_LIB.T6G(SCH_1):PAGE359_I85@PURE_QUANTA.Q_RES(CHIPS)':
 'A': CDS_PINID='A';
NODE_NAME     R4206 2
 '@T6G_MB_LIB.T6G(SCH_1):PAGE359_I86@PURE_QUANTA.Q_RES(CHIPS)':
 'B': CDS_PINID='B';
NODE_NAME     U270 7
 '@T6G_MB_LIB.T6G(SCH_1):PAGE359_I164@PURE_QUANTA.LM75BD(CHIPS)':
 'A0': CDS_PINID='A0';
NET_NAME
'U270_0_ADD1'
 '@T6G_MB_LIB.T6G(SCH_1):U270_0_ADD1':
 C_SIGNAL='@t6g_mb_lib.t6g(sch_1):u270_0_add1';
NODE_NAME     R4199 1
 '@T6G_MB_LIB.T6G(SCH_1):PAGE359_I81@PURE_QUANTA.Q_RES(CHIPS)':
 'A': CDS_PINID='A';
NODE_NAME     R4198 2
 '@T6G_MB_LIB.T6G(SCH_1):PAGE359_I82@PURE_QUANTA.Q_RES(CHIPS)':
 'B': CDS_PINID='B';
NODE_NAME     U270 6
 '@T6G_MB_LIB.T6G(SCH_1):PAGE359_I164@PURE_QUANTA.LM75BD(CHIPS)':
 'A1': CDS_PINID='A1';
NET_NAME
'U270_0_ADD2'
 '@T6G_MB_LIB.T6G(SCH_1):U270_0_ADD2':
 C_SIGNAL='@t6g_mb_lib.t6g(sch_1):u270_0_add2';
NODE_NAME     R4191 1
 '@T6G_MB_LIB.T6G(SCH_1):PAGE359_I89@PURE_QUANTA.Q_RES(CHIPS)':
 'A': CDS_PINID='A';
NODE_NAME     R4190 2
 '@T6G_MB_LIB.T6G(SCH_1):PAGE359_I91@PURE_QUANTA.Q_RES(CHIPS)':
 'B': CDS_PINID='B';
NODE_NAME     U270 5
 '@T6G_MB_LIB.T6G(SCH_1):PAGE359_I164@PURE_QUANTA.LM75BD(CHIPS)':
 'A2': CDS_PINID='A2';
NET_NAME
'U271_1_ADD0'
 '@T6G_MB_LIB.T6G(SCH_1):U271_1_ADD0':
 C_SIGNAL='@t6g_mb_lib.t6g(sch_1):u271_1_add0';
NODE_NAME     R4204 2
 '@T6G_MB_LIB.T6G(SCH_1):PAGE359_I94@PURE_QUANTA.Q_RES(CHIPS)':
 'B': CDS_PINID='B';
NODE_NAME     R4205 1
 '@T6G_MB_LIB.T6G(SCH_1):PAGE359_I96@PURE_QUANTA.Q_RES(CHIPS)':
 'A': CDS_PINID='A';
NODE_NAME     U271 7
 '@T6G_MB_LIB.T6G(SCH_1):PAGE359_I165@PURE_QUANTA.LM75BD(CHIPS)':
 'A0': CDS_PINID='A0';
NET_NAME
'U271_1_ADD1'
 '@T6G_MB_LIB.T6G(SCH_1):U271_1_ADD1':
 C_SIGNAL='@t6g_mb_lib.t6g(sch_1):u271_1_add1';
NODE_NAME     R4196 2
 '@T6G_MB_LIB.T6G(SCH_1):PAGE359_I95@PURE_QUANTA.Q_RES(CHIPS)':
 'B': CDS_PINID='B';
NODE_NAME     R4197 1
 '@T6G_MB_LIB.T6G(SCH_1):PAGE359_I98@PURE_QUANTA.Q_RES(CHIPS)':
 'A': CDS_PINID='A';
NODE_NAME     U271 6
 '@T6G_MB_LIB.T6G(SCH_1):PAGE359_I165@PURE_QUANTA.LM75BD(CHIPS)':
 'A1': CDS_PINID='A1';
NET_NAME
'U271_1_ADD2'
 '@T6G_MB_LIB.T6G(SCH_1):U271_1_ADD2':
 C_SIGNAL='@t6g_mb_lib.t6g(sch_1):u271_1_add2';
NODE_NAME     R4188 2
 '@T6G_MB_LIB.T6G(SCH_1):PAGE359_I101@PURE_QUANTA.Q_RES(CHIPS)':
 'B': CDS_PINID='B';
NODE_NAME     R4189 1
 '@T6G_MB_LIB.T6G(SCH_1):PAGE359_I102@PURE_QUANTA.Q_RES(CHIPS)':
 'A': CDS_PINID='A';
NODE_NAME     U271 5
 '@T6G_MB_LIB.T6G(SCH_1):PAGE359_I165@PURE_QUANTA.LM75BD(CHIPS)':
 'A2': CDS_PINID='A2';
NET_NAME
'U272_2_ADD0'
 '@T6G_MB_LIB.T6G(SCH_1):U272_2_ADD0':
 C_SIGNAL='@t6g_mb_lib.t6g(sch_1):u272_2_add0';
NODE_NAME     R4203 1
 '@T6G_MB_LIB.T6G(SCH_1):PAGE359_I127@PURE_QUANTA.Q_RES(CHIPS)':
 'A': CDS_PINID='A';
NODE_NAME     R4202 2
 '@T6G_MB_LIB.T6G(SCH_1):PAGE359_I129@PURE_QUANTA.Q_RES(CHIPS)':
 'B': CDS_PINID='B';
NODE_NAME     U272 7
 '@T6G_MB_LIB.T6G(SCH_1):PAGE359_I166@PURE_QUANTA.LM75BD(CHIPS)':
 'A0': CDS_PINID='A0';
NET_NAME
'U272_2_ADD1'
 '@T6G_MB_LIB.T6G(SCH_1):U272_2_ADD1':
 C_SIGNAL='@t6g_mb_lib.t6g(sch_1):u272_2_add1';
NODE_NAME     R4195 1
 '@T6G_MB_LIB.T6G(SCH_1):PAGE359_I125@PURE_QUANTA.Q_RES(CHIPS)':
 'A': CDS_PINID='A';
NODE_NAME     R4194 2
 '@T6G_MB_LIB.T6G(SCH_1):PAGE359_I128@PURE_QUANTA.Q_RES(CHIPS)':
 'B': CDS_PINID='B';
NODE_NAME     U272 6
 '@T6G_MB_LIB.T6G(SCH_1):PAGE359_I166@PURE_QUANTA.LM75BD(CHIPS)':
 'A1': CDS_PINID='A1';
NET_NAME
'U272_2_ADD2'
 '@T6G_MB_LIB.T6G(SCH_1):U272_2_ADD2':
 C_SIGNAL='@t6g_mb_lib.t6g(sch_1):u272_2_add2';
NODE_NAME     R4187 1
 '@T6G_MB_LIB.T6G(SCH_1):PAGE359_I121@PURE_QUANTA.Q_RES(CHIPS)':
 'A': CDS_PINID='A';
NODE_NAME     R4186 2
 '@T6G_MB_LIB.T6G(SCH_1):PAGE359_I122@PURE_QUANTA.Q_RES(CHIPS)':
 'B': CDS_PINID='B';
NODE_NAME     U272 5
 '@T6G_MB_LIB.T6G(SCH_1):PAGE359_I166@PURE_QUANTA.LM75BD(CHIPS)':
 'A2': CDS_PINID='A2';
NET_NAME
'U273_3_ADD0'
 '@T6G_MB_LIB.T6G(SCH_1):U273_3_ADD0':
 C_SIGNAL='@t6g_mb_lib.t6g(sch_1):u273_3_add0';
NODE_NAME     R4201 1
 '@T6G_MB_LIB.T6G(SCH_1):PAGE359_I147@PURE_QUANTA.Q_RES(CHIPS)':
 'A': CDS_PINID='A';
NODE_NAME     R4200 2
 '@T6G_MB_LIB.T6G(SCH_1):PAGE359_I149@PURE_QUANTA.Q_RES(CHIPS)':
 'B': CDS_PINID='B';
NODE_NAME     U273 7
 '@T6G_MB_LIB.T6G(SCH_1):PAGE359_I167@PURE_QUANTA.LM75BD(CHIPS)':
 'A0': CDS_PINID='A0';
NET_NAME
'U273_3_ADD1'
 '@T6G_MB_LIB.T6G(SCH_1):U273_3_ADD1':
 C_SIGNAL='@t6g_mb_lib.t6g(sch_1):u273_3_add1';
NODE_NAME     R4193 1
 '@T6G_MB_LIB.T6G(SCH_1):PAGE359_I145@PURE_QUANTA.Q_RES(CHIPS)':
 'A': CDS_PINID='A';
NODE_NAME     R4192 2
 '@T6G_MB_LIB.T6G(SCH_1):PAGE359_I148@PURE_QUANTA.Q_RES(CHIPS)':
 'B': CDS_PINID='B';
NODE_NAME     U273 6
 '@T6G_MB_LIB.T6G(SCH_1):PAGE359_I167@PURE_QUANTA.LM75BD(CHIPS)':
 'A1': CDS_PINID='A1';
NET_NAME
'U273_3_ADD2'
 '@T6G_MB_LIB.T6G(SCH_1):U273_3_ADD2':
 C_SIGNAL='@t6g_mb_lib.t6g(sch_1):u273_3_add2';
NODE_NAME     R4185 1
 '@T6G_MB_LIB.T6G(SCH_1):PAGE359_I141@PURE_QUANTA.Q_RES(CHIPS)':
 'A': CDS_PINID='A';
NODE_NAME     R4184 2
 '@T6G_MB_LIB.T6G(SCH_1):PAGE359_I142@PURE_QUANTA.Q_RES(CHIPS)':
 'B': CDS_PINID='B';
NODE_NAME     U273 5
 '@T6G_MB_LIB.T6G(SCH_1):PAGE359_I167@PURE_QUANTA.LM75BD(CHIPS)':
 'A2': CDS_PINID='A2';
NET_NAME
'U9_NR'
 '@T6G_MB_LIB.T6G(SCH_1):U9_NR':
 C_SIGNAL='@t6g_mb_lib.t6g(sch_1):u9_nr';
NODE_NAME     U9 4
 '@T6G_MB_LIB.T6G(SCH_1):PAGE156_I91@PURE_QUANTA.TPS71715DCKR(CHIPS)':
 'NR||FB': CDS_PINID='\nr||fb\';
NODE_NAME     C22 1
 '@T6G_MB_LIB.T6G(SCH_1):PAGE156_I113@PURE_QUANTA.Q_CAP(CHIPS)':
 'A': CDS_PINID='A';
NET_NAME
'UART_BMC_BIC_BUF_RX'
 '@T6G_MB_LIB.T6G(SCH_1):UART_BMC_BIC_BUF_RX':
 C_SIGNAL='@t6g_mb_lib.t6g(sch_1):uart_bmc_bic_buf_rx';
NODE_NAME     R3036 2
 '@T6G_MB_LIB.T6G(SCH_1):PAGE256_I197@PURE_QUANTA.Q_RES(CHIPS)':
 'B': CDS_PINID='B';
NODE_NAME     J41 OB6
 '@T6G_MB_LIB.T6G(SCH_1):PAGE348_I176@PURE_QUANTA.SCONN168_ME1016810202011(CHIPS)':
 'CLK': CDS_PINID='CLK';
NET_NAME
'UART_BMC_BIC_RX'
 '@T6G_MB_LIB.T6G(SCH_1):UART_BMC_BIC_RX':
 C_SIGNAL='@t6g_mb_lib.t6g(sch_1):uart_bmc_bic_rx';
NODE_NAME     R3033 1
 '@T6G_MB_LIB.T6G(SCH_1):PAGE256_I170@PURE_QUANTA.Q_RES(CHIPS)':
 'A': CDS_PINID='A';
NODE_NAME     R4515 2
 '@T6G_MB_LIB.T6G(SCH_1):PAGE256_I200@PURE_QUANTA.Q_RES(CHIPS)':
 'B': CDS_PINID='B';
NODE_NAME     J106 N6
 '@T6G_MB_LIB.T6G(SCH_1):PAGE327_I19@PURE_QUANTA.CONN112_10137002101LF(CHIPS)':
 'N6': CDS_PINID='N6';
NET_NAME
'UART_BMC_BIC_R_BUF_RX'
 '@T6G_MB_LIB.T6G(SCH_1):UART_BMC_BIC_R_BUF_RX':
 C_SIGNAL='@t6g_mb_lib.t6g(sch_1):uart_bmc_bic_r_buf_rx';
NODE_NAME     U204 4
 '@T6G_MB_LIB.T6G(SCH_1):PAGE256_I195@PURE_QUANTA.74LVC1G126SE7(CHIPS)':
 'Y': CDS_PINID='Y';
NODE_NAME     R3036 1
 '@T6G_MB_LIB.T6G(SCH_1):PAGE256_I197@PURE_QUANTA.Q_RES(CHIPS)':
 'A': CDS_PINID='A';
NODE_NAME     R4173 2
 '@T6G_MB_LIB.T6G(SCH_1):PAGE256_I204@PURE_QUANTA.Q_RES(CHIPS)':
 'B': CDS_PINID='B';
NET_NAME
'UART_BMC_BIC_R_RX'
 '@T6G_MB_LIB.T6G(SCH_1):UART_BMC_BIC_R_RX':
 C_SIGNAL='@t6g_mb_lib.t6g(sch_1):uart_bmc_bic_r_rx';
NODE_NAME     R3033 2
 '@T6G_MB_LIB.T6G(SCH_1):PAGE256_I170@PURE_QUANTA.Q_RES(CHIPS)':
 'B': CDS_PINID='B';
NODE_NAME     U204 2
 '@T6G_MB_LIB.T6G(SCH_1):PAGE256_I195@PURE_QUANTA.74LVC1G126SE7(CHIPS)':
 'A': CDS_PINID='A';
NET_NAME
'UART_BMC_BIC_TX'
 '@T6G_MB_LIB.T6G(SCH_1):UART_BMC_BIC_TX':
 C_SIGNAL='@t6g_mb_lib.t6g(sch_1):uart_bmc_bic_tx';
NODE_NAME     J41 OB5
 '@T6G_MB_LIB.T6G(SCH_1):PAGE348_I176@PURE_QUANTA.SCONN168_ME1016810202011(CHIPS)':
 'DATA_OUT': CDS_PINID='DATA_OUT';
NODE_NAME     J106 N8
 '@T6G_MB_LIB.T6G(SCH_1):PAGE327_I19@PURE_QUANTA.CONN112_10137002101LF(CHIPS)':
 'N8': CDS_PINID='N8';
NET_NAME
'UART_CPU0_LVC3_UART0_RX'
 '@T6G_MB_LIB.T6G(SCH_1):UART_CPU0_LVC3_UART0_RX':
 C_SIGNAL='@t6g_mb_lib.t6g(sch_1):uart_cpu0_lvc3_uart0_rx';
NODE_NAME     C364 1
 '@T6G_MB_LIB.T6G(SCH_1):PAGE141_I187@PURE_QUANTA.Q_CAP(CHIPS)':
 'A': CDS_PINID='A';
NODE_NAME     J13 2
 '@T6G_MB_LIB.T6G(SCH_1):PAGE141_I195@PURE_QUANTA.CONN4_HFK1040L0P1L7H(CHIPS)':
 '2': CDS_PINID='\2\';
NODE_NAME     R825 2
 '@T6G_MB_LIB.T6G(SCH_1):PAGE141_I203@PURE_QUANTA.Q_RES(CHIPS)':
 'B': CDS_PINID='B';
NODE_NAME     R819 2
 '@T6G_MB_LIB.T6G(SCH_1):PAGE141_I212@PURE_QUANTA.Q_RES(CHIPS)':
 'B': CDS_PINID='B';
NET_NAME
'UART_CPU0_LVC3_UART0_R_RX'
 '@T6G_MB_LIB.T6G(SCH_1):UART_CPU0_LVC3_UART0_R_RX':
 C_SIGNAL='@t6g_mb_lib.t6g(sch_1):uart_cpu0_lvc3_uart0_r_rx';
NODE_NAME     U116 11
 '@T6G_MB_LIB.T6G(SCH_1):PAGE141_I117@PURE_QUANTA.SN74AVC4T774PWR(CHIPS)':
 'B4': CDS_PINID='B4';
NODE_NAME     R819 1
 '@T6G_MB_LIB.T6G(SCH_1):PAGE141_I212@PURE_QUANTA.Q_RES(CHIPS)':
 'A': CDS_PINID='A';
NET_NAME
'UART_CPU0_LVC3_UART0_R_TX'
 '@T6G_MB_LIB.T6G(SCH_1):UART_CPU0_LVC3_UART0_R_TX':
 C_SIGNAL='@t6g_mb_lib.t6g(sch_1):uart_cpu0_lvc3_uart0_r_tx';
NODE_NAME     U116 12
 '@T6G_MB_LIB.T6G(SCH_1):PAGE141_I117@PURE_QUANTA.SN74AVC4T774PWR(CHIPS)':
 'B3': CDS_PINID='B3';
NODE_NAME     R818 1
 '@T6G_MB_LIB.T6G(SCH_1):PAGE141_I220@PURE_QUANTA.Q_RES(CHIPS)':
 'A': CDS_PINID='A';
NET_NAME
'UART_CPU0_LVC3_UART0_TX'
 '@T6G_MB_LIB.T6G(SCH_1):UART_CPU0_LVC3_UART0_TX':
 C_SIGNAL='@t6g_mb_lib.t6g(sch_1):uart_cpu0_lvc3_uart0_tx';
NODE_NAME     C363 1
 '@T6G_MB_LIB.T6G(SCH_1):PAGE141_I190@PURE_QUANTA.Q_CAP(CHIPS)':
 'A': CDS_PINID='A';
NODE_NAME     J13 3
 '@T6G_MB_LIB.T6G(SCH_1):PAGE141_I195@PURE_QUANTA.CONN4_HFK1040L0P1L7H(CHIPS)':
 '3': CDS_PINID='\3\';
NODE_NAME     R824 2
 '@T6G_MB_LIB.T6G(SCH_1):PAGE141_I204@PURE_QUANTA.Q_RES(CHIPS)':
 'B': CDS_PINID='B';
NODE_NAME     R818 2
 '@T6G_MB_LIB.T6G(SCH_1):PAGE141_I220@PURE_QUANTA.Q_RES(CHIPS)':
 'B': CDS_PINID='B';
NET_NAME
'UART_CPU0_SCM_LVC3_UART1_R1_TX'
 '@T6G_MB_LIB.T6G(SCH_1):UART_CPU0_SCM_LVC3_UART1_R1_TX':
 C_SIGNAL='@t6g_mb_lib.t6g(sch_1):uart_cpu0_scm_lvc3_uart1_r1_tx';
NODE_NAME     J41 OB9
 '@T6G_MB_LIB.T6G(SCH_1):PAGE348_I176@PURE_QUANTA.SCONN168_ME1016810202011(CHIPS)':
 'RBT_RXD0': CDS_PINID='RBT_RXD0';
NODE_NAME     R6065 1
 '@T6G_MB_LIB.T6G(SCH_1):PAGE348_I178@PURE_QUANTA.Q_RES(CHIPS)':
 'A': CDS_PINID='A';
NET_NAME
'UART_CPU0_SCM_LVC3_UART1_RX'
 '@T6G_MB_LIB.T6G(SCH_1):UART_CPU0_SCM_LVC3_UART1_RX':
 C_SIGNAL='@t6g_mb_lib.t6g(sch_1):uart_cpu0_scm_lvc3_uart1_rx';
NODE_NAME     J41 OB8
 '@T6G_MB_LIB.T6G(SCH_1):PAGE348_I176@PURE_QUANTA.SCONN168_ME1016810202011(CHIPS)':
 'RBT_RXD1': CDS_PINID='RBT_RXD1';
NODE_NAME     R6064 1
 '@T6G_MB_LIB.T6G(SCH_1):PAGE348_I177@PURE_QUANTA.Q_RES(CHIPS)':
 'A': CDS_PINID='A';
NET_NAME
'UART_CPU0_SCM_LVC3_UART1_R_RX'
 '@T6G_MB_LIB.T6G(SCH_1):UART_CPU0_SCM_LVC3_UART1_R_RX':
 C_SIGNAL='@t6g_mb_lib.t6g(sch_1):uart_cpu0_scm_lvc3_uart1_r_rx';
NODE_NAME     U116 13
 '@T6G_MB_LIB.T6G(SCH_1):PAGE141_I117@PURE_QUANTA.SN74AVC4T774PWR(CHIPS)':
 'B2': CDS_PINID='B2';
NODE_NAME     R823 2
 '@T6G_MB_LIB.T6G(SCH_1):PAGE141_I205@PURE_QUANTA.Q_RES(CHIPS)':
 'B': CDS_PINID='B';
NODE_NAME     C63 1
 '@T6G_MB_LIB.T6G(SCH_1):PAGE349_I112@PURE_QUANTA.Q_CAP(CHIPS)':
 'A': CDS_PINID='A';
NODE_NAME     J8 2
 '@T6G_MB_LIB.T6G(SCH_1):PAGE349_I148@PURE_QUANTA.CONN4_HFK1040L0P1L7H(CHIPS)':
 '2': CDS_PINID='\2\';
NODE_NAME     R6064 2
 '@T6G_MB_LIB.T6G(SCH_1):PAGE348_I177@PURE_QUANTA.Q_RES(CHIPS)':
 'B': CDS_PINID='B';
NET_NAME
'UART_CPU0_SCM_LVC3_UART1_R_TX'
 '@T6G_MB_LIB.T6G(SCH_1):UART_CPU0_SCM_LVC3_UART1_R_TX':
 C_SIGNAL='@t6g_mb_lib.t6g(sch_1):uart_cpu0_scm_lvc3_uart1_r_tx';
NODE_NAME     U116 14
 '@T6G_MB_LIB.T6G(SCH_1):PAGE141_I117@PURE_QUANTA.SN74AVC4T774PWR(CHIPS)':
 'B1': CDS_PINID='B1';
NODE_NAME     R1425 1
 '@T6G_MB_LIB.T6G(SCH_1):PAGE141_I221@PURE_QUANTA.Q_RES(CHIPS)':
 'A': CDS_PINID='A';
NET_NAME
'UART_CPU0_SCM_LVC3_UART1_TX'
 '@T6G_MB_LIB.T6G(SCH_1):UART_CPU0_SCM_LVC3_UART1_TX':
 C_SIGNAL='@t6g_mb_lib.t6g(sch_1):uart_cpu0_scm_lvc3_uart1_tx';
NODE_NAME     R822 2
 '@T6G_MB_LIB.T6G(SCH_1):PAGE141_I206@PURE_QUANTA.Q_RES(CHIPS)':
 'B': CDS_PINID='B';
NODE_NAME     J8 3
 '@T6G_MB_LIB.T6G(SCH_1):PAGE349_I148@PURE_QUANTA.CONN4_HFK1040L0P1L7H(CHIPS)':
 '3': CDS_PINID='\3\';
NODE_NAME     C62 1
 '@T6G_MB_LIB.T6G(SCH_1):PAGE349_I69@PURE_QUANTA.Q_CAP(CHIPS)':
 'A': CDS_PINID='A';
NODE_NAME     R6065 2
 '@T6G_MB_LIB.T6G(SCH_1):PAGE348_I178@PURE_QUANTA.Q_RES(CHIPS)':
 'B': CDS_PINID='B';
NODE_NAME     R1425 2
 '@T6G_MB_LIB.T6G(SCH_1):PAGE141_I221@PURE_QUANTA.Q_RES(CHIPS)':
 'B': CDS_PINID='B';
NET_NAME
'UART_CPU0_SCM_UART1_RX'
 '@T6G_MB_LIB.T6G(SCH_1):UART_CPU0_SCM_UART1_RX':
 C_SIGNAL='@t6g_mb_lib.t6g(sch_1):uart_cpu0_scm_uart1_rx';
NODE_NAME     U25 DH33
 '@T6G_MB_LIB.T6G(SCH_1):PAGE27_I227@PURE_QUANTA.GENOA_SP5(CHIPS)':
 'UART1_RXD||AGPIO141': CDS_PINID='\uart1_rxd||agpio141\';
NODE_NAME     R816 2
 '@T6G_MB_LIB.T6G(SCH_1):PAGE141_I196@PURE_QUANTA.Q_RES(CHIPS)':
 'B': CDS_PINID='B';
NODE_NAME     R1423 1
 '@T6G_MB_LIB.T6G(SCH_1):PAGE141_I232@PURE_QUANTA.Q_RES(CHIPS)':
 'A': CDS_PINID='A';
NET_NAME
'UART_CPU0_SCM_UART1_R_RX'
 '@T6G_MB_LIB.T6G(SCH_1):UART_CPU0_SCM_UART1_R_RX':
 C_SIGNAL='@t6g_mb_lib.t6g(sch_1):uart_cpu0_scm_uart1_r_rx';
NODE_NAME     U116 4
 '@T6G_MB_LIB.T6G(SCH_1):PAGE141_I117@PURE_QUANTA.SN74AVC4T774PWR(CHIPS)':
 'A2': CDS_PINID='A2';
NODE_NAME     R1423 2
 '@T6G_MB_LIB.T6G(SCH_1):PAGE141_I232@PURE_QUANTA.Q_RES(CHIPS)':
 'B': CDS_PINID='B';
NET_NAME
'UART_CPU0_SCM_UART1_R_TX'
 '@T6G_MB_LIB.T6G(SCH_1):UART_CPU0_SCM_UART1_R_TX':
 C_SIGNAL='@t6g_mb_lib.t6g(sch_1):uart_cpu0_scm_uart1_r_tx';
NODE_NAME     U25 DJ32
 '@T6G_MB_LIB.T6G(SCH_1):PAGE27_I227@PURE_QUANTA.GENOA_SP5(CHIPS)':
 'UART1_TXD||AGPIO142': CDS_PINID='\uart1_txd||agpio142\';
NODE_NAME     R2318 1
 '@T6G_MB_LIB.T6G(SCH_1):PAGE27_I288@PURE_QUANTA.Q_RES(CHIPS)':
 'A': CDS_PINID='A';
NET_NAME
'UART_CPU0_SCM_UART1_TX'
 '@T6G_MB_LIB.T6G(SCH_1):UART_CPU0_SCM_UART1_TX':
 C_SIGNAL='@t6g_mb_lib.t6g(sch_1):uart_cpu0_scm_uart1_tx';
NODE_NAME     R2318 2
 '@T6G_MB_LIB.T6G(SCH_1):PAGE27_I288@PURE_QUANTA.Q_RES(CHIPS)':
 'B': CDS_PINID='B';
NODE_NAME     R747 2
 '@T6G_MB_LIB.T6G(SCH_1):PAGE75_I8@PURE_QUANTA.Q_RES(CHIPS)':
 'B': CDS_PINID='B';
NODE_NAME     R729 2
 '@T6G_MB_LIB.T6G(SCH_1):PAGE75_I41@PURE_QUANTA.Q_RES(CHIPS)':
 'B': CDS_PINID='B';
NODE_NAME     U116 3
 '@T6G_MB_LIB.T6G(SCH_1):PAGE141_I117@PURE_QUANTA.SN74AVC4T774PWR(CHIPS)':
 'A1': CDS_PINID='A1';
NODE_NAME     R815 2
 '@T6G_MB_LIB.T6G(SCH_1):PAGE141_I197@PURE_QUANTA.Q_RES(CHIPS)':
 'B': CDS_PINID='B';
NET_NAME
'UART_CPU0_UART0_RX'
 '@T6G_MB_LIB.T6G(SCH_1):UART_CPU0_UART0_RX':
 C_SIGNAL='@t6g_mb_lib.t6g(sch_1):uart_cpu0_uart0_rx';
NODE_NAME     U25 DG35
 '@T6G_MB_LIB.T6G(SCH_1):PAGE27_I227@PURE_QUANTA.GENOA_SP5(CHIPS)':
 'UART0_RXD||AGPIO136': CDS_PINID='\uart0_rxd||agpio136\';
NODE_NAME     R813 2
 '@T6G_MB_LIB.T6G(SCH_1):PAGE141_I199@PURE_QUANTA.Q_RES(CHIPS)':
 'B': CDS_PINID='B';
NODE_NAME     R817 1
 '@T6G_MB_LIB.T6G(SCH_1):PAGE141_I231@PURE_QUANTA.Q_RES(CHIPS)':
 'A': CDS_PINID='A';
NET_NAME
'UART_CPU0_UART0_R_RX'
 '@T6G_MB_LIB.T6G(SCH_1):UART_CPU0_UART0_R_RX':
 C_SIGNAL='@t6g_mb_lib.t6g(sch_1):uart_cpu0_uart0_r_rx';
NODE_NAME     U116 6
 '@T6G_MB_LIB.T6G(SCH_1):PAGE141_I117@PURE_QUANTA.SN74AVC4T774PWR(CHIPS)':
 'A4': CDS_PINID='A4';
NODE_NAME     R817 2
 '@T6G_MB_LIB.T6G(SCH_1):PAGE141_I231@PURE_QUANTA.Q_RES(CHIPS)':
 'B': CDS_PINID='B';
NET_NAME
'UART_CPU0_UART0_R_TX'
 '@T6G_MB_LIB.T6G(SCH_1):UART_CPU0_UART0_R_TX':
 C_SIGNAL='@t6g_mb_lib.t6g(sch_1):uart_cpu0_uart0_r_tx';
NODE_NAME     U25 DJ34
 '@T6G_MB_LIB.T6G(SCH_1):PAGE27_I227@PURE_QUANTA.GENOA_SP5(CHIPS)':
 'UART0_TXD||AGPIO138': CDS_PINID='\uart0_txd||agpio138\';
NODE_NAME     R405 2
 '@T6G_MB_LIB.T6G(SCH_1):PAGE27_I279@PURE_QUANTA.Q_RES(CHIPS)':
 'B': CDS_PINID='B';
NET_NAME
'UART_CPU0_UART0_TX'
 '@T6G_MB_LIB.T6G(SCH_1):UART_CPU0_UART0_TX':
 C_SIGNAL='@t6g_mb_lib.t6g(sch_1):uart_cpu0_uart0_tx';
NODE_NAME     R405 1
 '@T6G_MB_LIB.T6G(SCH_1):PAGE27_I279@PURE_QUANTA.Q_RES(CHIPS)':
 'A': CDS_PINID='A';
NODE_NAME     U116 5
 '@T6G_MB_LIB.T6G(SCH_1):PAGE141_I117@PURE_QUANTA.SN74AVC4T774PWR(CHIPS)':
 'A3': CDS_PINID='A3';
NODE_NAME     R814 2
 '@T6G_MB_LIB.T6G(SCH_1):PAGE141_I198@PURE_QUANTA.Q_RES(CHIPS)':
 'B': CDS_PINID='B';
NET_NAME
'UART_LS_EN'
 '@T6G_MB_LIB.T6G(SCH_1):UART_LS_EN':
 C_SIGNAL='@t6g_mb_lib.t6g(sch_1):uart_ls_en';
NODE_NAME     Q61 G
 '@T6G_MB_LIB.T6G(SCH_1):PAGE141_I89@PURE_QUANTA.MOSFET_N_GSD(CHIPS)':
 'GATE': CDS_PINID='GATE';
NODE_NAME     R1563 1
 '@T6G_MB_LIB.T6G(SCH_1):PAGE80_I63@PURE_QUANTA.Q_RES(CHIPS)':
 'A': CDS_PINID='A';
NET_NAME
'UART_LS_EN_N'
 '@T6G_MB_LIB.T6G(SCH_1):UART_LS_EN_N':
 C_SIGNAL='@t6g_mb_lib.t6g(sch_1):uart_ls_en_n';
NODE_NAME     U116 9
 '@T6G_MB_LIB.T6G(SCH_1):PAGE141_I117@PURE_QUANTA.SN74AVC4T774PWR(CHIPS)':
 'OE': CDS_PINID='OE';
NODE_NAME     R1253 1
 '@T6G_MB_LIB.T6G(SCH_1):PAGE141_I211@PURE_QUANTA.Q_RES(CHIPS)':
 'A': CDS_PINID='A';
NET_NAME
'UART_LS_EN_R_N'
 '@T6G_MB_LIB.T6G(SCH_1):UART_LS_EN_R_N':
 C_SIGNAL='@t6g_mb_lib.t6g(sch_1):uart_ls_en_r_n';
NODE_NAME     Q61 D
 '@T6G_MB_LIB.T6G(SCH_1):PAGE141_I89@PURE_QUANTA.MOSFET_N_GSD(CHIPS)':
 'DRAIN': CDS_PINID='DRAIN';
NODE_NAME     R1419 2
 '@T6G_MB_LIB.T6G(SCH_1):PAGE141_I91@PURE_QUANTA.Q_RES(CHIPS)':
 'B': CDS_PINID='B';
NODE_NAME     R1253 2
 '@T6G_MB_LIB.T6G(SCH_1):PAGE141_I211@PURE_QUANTA.Q_RES(CHIPS)':
 'B': CDS_PINID='B';
NET_NAME
'UART_VCC_J13'
 '@T6G_MB_LIB.T6G(SCH_1):UART_VCC_J13':
 C_SIGNAL='@t6g_mb_lib.t6g(sch_1):uart_vcc_j13';
NODE_NAME     R821 2
 '@T6G_MB_LIB.T6G(SCH_1):PAGE141_I185@PURE_QUANTA.Q_RES(CHIPS)':
 'B': CDS_PINID='B';
NODE_NAME     R820 1
 '@T6G_MB_LIB.T6G(SCH_1):PAGE141_I186@PURE_QUANTA.Q_RES(CHIPS)':
 'A': CDS_PINID='A';
NODE_NAME     J13 1
 '@T6G_MB_LIB.T6G(SCH_1):PAGE141_I195@PURE_QUANTA.CONN4_HFK1040L0P1L7H(CHIPS)':
 '1': CDS_PINID='\1\';
NET_NAME
'UART_VCC_J8'
 '@T6G_MB_LIB.T6G(SCH_1):UART_VCC_J8':
 C_SIGNAL='@t6g_mb_lib.t6g(sch_1):uart_vcc_j8';
NODE_NAME     R131 2
 '@T6G_MB_LIB.T6G(SCH_1):PAGE349_I116@PURE_QUANTA.Q_RES(CHIPS)':
 'B': CDS_PINID='B';
NODE_NAME     J8 1
 '@T6G_MB_LIB.T6G(SCH_1):PAGE349_I148@PURE_QUANTA.CONN4_HFK1040L0P1L7H(CHIPS)':
 '1': CDS_PINID='\1\';
NODE_NAME     R130 1
 '@T6G_MB_LIB.T6G(SCH_1):PAGE349_I113@PURE_QUANTA.Q_RES(CHIPS)':
 'A': CDS_PINID='A';
NET_NAME
'USB2_CPU0_P0_DN'
 '@T6G_MB_LIB.T6G(SCH_1):USB2_CPU0_P0_DN':
 C_SIGNAL='@t6g_mb_lib.t6g(sch_1):usb2_cpu0_p0_dn';
NODE_NAME     U25 A25
 '@T6G_MB_LIB.T6G(SCH_1):PAGE29_I287@PURE_QUANTA.GENOA_SP5(CHIPS)':
 'USB00_DN': CDS_PINID='USB00_DN';
NODE_NAME     R6193 1
 '@T6G_MB_LIB.T6G(SCH_1):PAGE158_I4@PURE_QUANTA.Q_RES(CHIPS)':
 'A': CDS_PINID='A';
NODE_NAME     R6191 1
 '@T6G_MB_LIB.T6G(SCH_1):PAGE158_I5@PURE_QUANTA.Q_RES(CHIPS)':
 'A': CDS_PINID='A';
NODE_NAME     R340 1
 '@T6G_MB_LIB.T6G(SCH_1):PAGE158_I121@PURE_QUANTA.Q_RES(CHIPS)':
 'A': CDS_PINID='A';
NET_NAME
'USB2_CPU0_P0_DP'
 '@T6G_MB_LIB.T6G(SCH_1):USB2_CPU0_P0_DP':
 C_SIGNAL='@t6g_mb_lib.t6g(sch_1):usb2_cpu0_p0_dp';
NODE_NAME     U25 A26
 '@T6G_MB_LIB.T6G(SCH_1):PAGE29_I287@PURE_QUANTA.GENOA_SP5(CHIPS)':
 'USB00_DP': CDS_PINID='USB00_DP';
NODE_NAME     R6192 1
 '@T6G_MB_LIB.T6G(SCH_1):PAGE158_I3@PURE_QUANTA.Q_RES(CHIPS)':
 'A': CDS_PINID='A';
NODE_NAME     R6190 1
 '@T6G_MB_LIB.T6G(SCH_1):PAGE158_I6@PURE_QUANTA.Q_RES(CHIPS)':
 'A': CDS_PINID='A';
NODE_NAME     R339 1
 '@T6G_MB_LIB.T6G(SCH_1):PAGE158_I120@PURE_QUANTA.Q_RES(CHIPS)':
 'A': CDS_PINID='A';
NET_NAME
'USB2_CPU0_P0_HUB1_R_DN'
 '@T6G_MB_LIB.T6G(SCH_1):USB2_CPU0_P0_HUB1_R_DN':
 C_SIGNAL='@t6g_mb_lib.t6g(sch_1):usb2_cpu0_p0_hub1_r_dn';
NODE_NAME     U6001 59
 '@T6G_MB_LIB.T6G(SCH_1):PAGE153_I1@PURE_QUANTA.CYUSB330468LTXI(CHIPS)':
 'DS1_DM': CDS_PINID='DS1_DM';
NODE_NAME     R6195 1
 '@T6G_MB_LIB.T6G(SCH_1):PAGE158_I71@PURE_QUANTA.Q_RES(CHIPS)':
 'A': CDS_PINID='A';
NET_NAME
'USB2_CPU0_P0_HUB1_R_DP'
 '@T6G_MB_LIB.T6G(SCH_1):USB2_CPU0_P0_HUB1_R_DP':
 C_SIGNAL='@t6g_mb_lib.t6g(sch_1):usb2_cpu0_p0_hub1_r_dp';
NODE_NAME     U6001 60
 '@T6G_MB_LIB.T6G(SCH_1):PAGE153_I1@PURE_QUANTA.CYUSB330468LTXI(CHIPS)':
 'DS1_DP': CDS_PINID='DS1_DP';
NODE_NAME     R6194 1
 '@T6G_MB_LIB.T6G(SCH_1):PAGE158_I72@PURE_QUANTA.Q_RES(CHIPS)':
 'A': CDS_PINID='A';
NET_NAME
'USB2_CPU0_P0_HUB2_R_DN'
 '@T6G_MB_LIB.T6G(SCH_1):USB2_CPU0_P0_HUB2_R_DN':
 C_SIGNAL='@t6g_mb_lib.t6g(sch_1):usb2_cpu0_p0_hub2_r_dn';
NODE_NAME     R6197 1
 '@T6G_MB_LIB.T6G(SCH_1):PAGE158_I74@PURE_QUANTA.Q_RES(CHIPS)':
 'A': CDS_PINID='A';
NODE_NAME     U6002 10
 '@T6G_MB_LIB.T6G(SCH_1):PAGE155_I101@PURE_QUANTA.TUSB8042AIRGCR(CHIPS)':
 'USB_DM_DN2': CDS_PINID='USB_DM_DN2';
NET_NAME
'USB2_CPU0_P0_HUB2_R_DP'
 '@T6G_MB_LIB.T6G(SCH_1):USB2_CPU0_P0_HUB2_R_DP':
 C_SIGNAL='@t6g_mb_lib.t6g(sch_1):usb2_cpu0_p0_hub2_r_dp';
NODE_NAME     R6196 1
 '@T6G_MB_LIB.T6G(SCH_1):PAGE158_I73@PURE_QUANTA.Q_RES(CHIPS)':
 'A': CDS_PINID='A';
NODE_NAME     U6002 9
 '@T6G_MB_LIB.T6G(SCH_1):PAGE155_I101@PURE_QUANTA.TUSB8042AIRGCR(CHIPS)':
 'USB_DP_DN2': CDS_PINID='USB_DP_DN2';
NET_NAME
'USB2_CPU0_P0_R1_DN'
 '@T6G_MB_LIB.T6G(SCH_1):USB2_CPU0_P0_R1_DN':
 C_SIGNAL='@t6g_mb_lib.t6g(sch_1):usb2_cpu0_p0_r1_dn';
NODE_NAME     U6001 58
 '@T6G_MB_LIB.T6G(SCH_1):PAGE153_I1@PURE_QUANTA.CYUSB330468LTXI(CHIPS)':
 'US_DM': CDS_PINID='US_DM';
NODE_NAME     R6191 2
 '@T6G_MB_LIB.T6G(SCH_1):PAGE158_I5@PURE_QUANTA.Q_RES(CHIPS)':
 'B': CDS_PINID='B';
NET_NAME
'USB2_CPU0_P0_R1_DP'
 '@T6G_MB_LIB.T6G(SCH_1):USB2_CPU0_P0_R1_DP':
 C_SIGNAL='@t6g_mb_lib.t6g(sch_1):usb2_cpu0_p0_r1_dp';
NODE_NAME     U6001 57
 '@T6G_MB_LIB.T6G(SCH_1):PAGE153_I1@PURE_QUANTA.CYUSB330468LTXI(CHIPS)':
 'US_DP': CDS_PINID='US_DP';
NODE_NAME     R6190 2
 '@T6G_MB_LIB.T6G(SCH_1):PAGE158_I6@PURE_QUANTA.Q_RES(CHIPS)':
 'B': CDS_PINID='B';
NET_NAME
'USB2_CPU0_P0_R2_DN'
 '@T6G_MB_LIB.T6G(SCH_1):USB2_CPU0_P0_R2_DN':
 C_SIGNAL='@t6g_mb_lib.t6g(sch_1):usb2_cpu0_p0_r2_dn';
NODE_NAME     R6193 2
 '@T6G_MB_LIB.T6G(SCH_1):PAGE158_I4@PURE_QUANTA.Q_RES(CHIPS)':
 'B': CDS_PINID='B';
NODE_NAME     R345 1
 '@T6G_MB_LIB.T6G(SCH_1):PAGE158_I124@PURE_QUANTA.Q_RES(CHIPS)':
 'A': CDS_PINID='A';
NODE_NAME     U6002 54
 '@T6G_MB_LIB.T6G(SCH_1):PAGE155_I101@PURE_QUANTA.TUSB8042AIRGCR(CHIPS)':
 'USB_DM_UP': CDS_PINID='USB_DM_UP';
NET_NAME
'USB2_CPU0_P0_R2_DP'
 '@T6G_MB_LIB.T6G(SCH_1):USB2_CPU0_P0_R2_DP':
 C_SIGNAL='@t6g_mb_lib.t6g(sch_1):usb2_cpu0_p0_r2_dp';
NODE_NAME     R6192 2
 '@T6G_MB_LIB.T6G(SCH_1):PAGE158_I3@PURE_QUANTA.Q_RES(CHIPS)':
 'B': CDS_PINID='B';
NODE_NAME     R343 1
 '@T6G_MB_LIB.T6G(SCH_1):PAGE158_I125@PURE_QUANTA.Q_RES(CHIPS)':
 'A': CDS_PINID='A';
NODE_NAME     U6002 53
 '@T6G_MB_LIB.T6G(SCH_1):PAGE155_I101@PURE_QUANTA.TUSB8042AIRGCR(CHIPS)':
 'USB_DP_UP': CDS_PINID='USB_DP_UP';
NET_NAME
'USB2_CPU0_P10_DN'
 '@T6G_MB_LIB.T6G(SCH_1):USB2_CPU0_P10_DN':
 C_SIGNAL='@t6g_mb_lib.t6g(sch_1):usb2_cpu0_p10_dn';
NODE_NAME     U25 DH67
 '@T6G_MB_LIB.T6G(SCH_1):PAGE29_I287@PURE_QUANTA.GENOA_SP5(CHIPS)':
 'USB10_DN': CDS_PINID='USB10_DN';
NODE_NAME     R3177 2
 '@T6G_MB_LIB.T6G(SCH_1):PAGE341_I136@PURE_QUANTA.Q_RES(CHIPS)':
 'B': CDS_PINID='B';
NET_NAME
'USB2_CPU0_P10_DP'
 '@T6G_MB_LIB.T6G(SCH_1):USB2_CPU0_P10_DP':
 C_SIGNAL='@t6g_mb_lib.t6g(sch_1):usb2_cpu0_p10_dp';
NODE_NAME     U25 DJ67
 '@T6G_MB_LIB.T6G(SCH_1):PAGE29_I287@PURE_QUANTA.GENOA_SP5(CHIPS)':
 'USB10_DP': CDS_PINID='USB10_DP';
NODE_NAME     R3178 2
 '@T6G_MB_LIB.T6G(SCH_1):PAGE341_I135@PURE_QUANTA.Q_RES(CHIPS)':
 'B': CDS_PINID='B';
NET_NAME
'USB2_CPU0_P11_DN'
 '@T6G_MB_LIB.T6G(SCH_1):USB2_CPU0_P11_DN':
 C_SIGNAL='@t6g_mb_lib.t6g(sch_1):usb2_cpu0_p11_dn';
NODE_NAME     U25 DJ60
 '@T6G_MB_LIB.T6G(SCH_1):PAGE29_I287@PURE_QUANTA.GENOA_SP5(CHIPS)':
 'USB11_DN': CDS_PINID='USB11_DN';
NODE_NAME     R42 2
 '@T6G_MB_LIB.T6G(SCH_1):PAGE335_I166@PURE_QUANTA.Q_RES(CHIPS)':
 'B': CDS_PINID='B';
NET_NAME
'USB2_CPU0_P11_DP'
 '@T6G_MB_LIB.T6G(SCH_1):USB2_CPU0_P11_DP':
 C_SIGNAL='@t6g_mb_lib.t6g(sch_1):usb2_cpu0_p11_dp';
NODE_NAME     U25 DH60
 '@T6G_MB_LIB.T6G(SCH_1):PAGE29_I287@PURE_QUANTA.GENOA_SP5(CHIPS)':
 'USB11_DP': CDS_PINID='USB11_DP';
NODE_NAME     R46 2
 '@T6G_MB_LIB.T6G(SCH_1):PAGE335_I108@PURE_QUANTA.Q_RES(CHIPS)':
 'B': CDS_PINID='B';
NET_NAME
'USB2_CPU0_P1_DN'
 '@T6G_MB_LIB.T6G(SCH_1):USB2_CPU0_P1_DN':
 C_SIGNAL='@t6g_mb_lib.t6g(sch_1):usb2_cpu0_p1_dn';
NODE_NAME     U25 A29
 '@T6G_MB_LIB.T6G(SCH_1):PAGE29_I287@PURE_QUANTA.GENOA_SP5(CHIPS)':
 'USB01_DN': CDS_PINID='USB01_DN';
NODE_NAME     J41 B54
 '@T6G_MB_LIB.T6G(SCH_1):PAGE348_I176@PURE_QUANTA.SCONN168_ME1016810202011(CHIPS)':
 'PETP11': CDS_PINID='PETP11';
NET_NAME
'USB2_CPU0_P1_DP'
 '@T6G_MB_LIB.T6G(SCH_1):USB2_CPU0_P1_DP':
 C_SIGNAL='@t6g_mb_lib.t6g(sch_1):usb2_cpu0_p1_dp';
NODE_NAME     U25 A28
 '@T6G_MB_LIB.T6G(SCH_1):PAGE29_I287@PURE_QUANTA.GENOA_SP5(CHIPS)':
 'USB01_DP': CDS_PINID='USB01_DP';
NODE_NAME     J41 B53
 '@T6G_MB_LIB.T6G(SCH_1):PAGE348_I176@PURE_QUANTA.SCONN168_ME1016810202011(CHIPS)':
 'PETN11': CDS_PINID='PETN11';
NET_NAME
'USB2_HOST_BMC_B_BUF_DN'
 '@T6G_MB_LIB.T6G(SCH_1):USB2_HOST_BMC_B_BUF_DN':
 C_SIGNAL='@t6g_mb_lib.t6g(sch_1):usb2_host_bmc_b_buf_dn';
NODE_NAME     R2791 2
 '@T6G_MB_LIB.T6G(SCH_1):PAGE358_I97@PURE_QUANTA.Q_RES(CHIPS)':
 'B': CDS_PINID='B';
NODE_NAME     R2789 1
 '@T6G_MB_LIB.T6G(SCH_1):PAGE358_I98@PURE_QUANTA.Q_RES(CHIPS)':
 'A': CDS_PINID='A';
NODE_NAME     R4483 1
 '@T6G_MB_LIB.T6G(SCH_1):PAGE358_I206@PURE_QUANTA.Q_RES(CHIPS)':
 'A': CDS_PINID='A';
NET_NAME
'USB2_HOST_BMC_B_BUF_DP'
 '@T6G_MB_LIB.T6G(SCH_1):USB2_HOST_BMC_B_BUF_DP':
 C_SIGNAL='@t6g_mb_lib.t6g(sch_1):usb2_host_bmc_b_buf_dp';
NODE_NAME     R2790 2
 '@T6G_MB_LIB.T6G(SCH_1):PAGE358_I96@PURE_QUANTA.Q_RES(CHIPS)':
 'B': CDS_PINID='B';
NODE_NAME     R2788 1
 '@T6G_MB_LIB.T6G(SCH_1):PAGE358_I99@PURE_QUANTA.Q_RES(CHIPS)':
 'A': CDS_PINID='A';
NODE_NAME     R4482 1
 '@T6G_MB_LIB.T6G(SCH_1):PAGE358_I208@PURE_QUANTA.Q_RES(CHIPS)':
 'A': CDS_PINID='A';
NET_NAME
'USB2_HOST_BMC_B_DN'
 '@T6G_MB_LIB.T6G(SCH_1):USB2_HOST_BMC_B_DN':
 C_SIGNAL='@t6g_mb_lib.t6g(sch_1):usb2_host_bmc_b_dn';
NODE_NAME     R2791 1
 '@T6G_MB_LIB.T6G(SCH_1):PAGE358_I97@PURE_QUANTA.Q_RES(CHIPS)':
 'A': CDS_PINID='A';
NODE_NAME     R3652 2
 '@T6G_MB_LIB.T6G(SCH_1):PAGE358_I137@PURE_QUANTA.Q_RES(CHIPS)':
 'B': CDS_PINID='B';
NODE_NAME     R4420 1
 '@T6G_MB_LIB.T6G(SCH_1):PAGE358_I202@PURE_QUANTA.Q_RES(CHIPS)':
 'A': CDS_PINID='A';
NODE_NAME     J41 B51
 '@T6G_MB_LIB.T6G(SCH_1):PAGE348_I176@PURE_QUANTA.SCONN168_ME1016810202011(CHIPS)':
 'PETP10': CDS_PINID='PETP10';
NET_NAME
'USB2_HOST_BMC_B_DP'
 '@T6G_MB_LIB.T6G(SCH_1):USB2_HOST_BMC_B_DP':
 C_SIGNAL='@t6g_mb_lib.t6g(sch_1):usb2_host_bmc_b_dp';
NODE_NAME     R2790 1
 '@T6G_MB_LIB.T6G(SCH_1):PAGE358_I96@PURE_QUANTA.Q_RES(CHIPS)':
 'A': CDS_PINID='A';
NODE_NAME     R3651 2
 '@T6G_MB_LIB.T6G(SCH_1):PAGE358_I138@PURE_QUANTA.Q_RES(CHIPS)':
 'B': CDS_PINID='B';
NODE_NAME     R4419 1
 '@T6G_MB_LIB.T6G(SCH_1):PAGE358_I203@PURE_QUANTA.Q_RES(CHIPS)':
 'A': CDS_PINID='A';
NODE_NAME     J41 B50
 '@T6G_MB_LIB.T6G(SCH_1):PAGE348_I176@PURE_QUANTA.SCONN168_ME1016810202011(CHIPS)':
 'PETN10': CDS_PINID='PETN10';
NET_NAME
'USB2_HUB_BUF_SWB_DN'
 '@T6G_MB_LIB.T6G(SCH_1):USB2_HUB_BUF_SWB_DN':
 C_SIGNAL='@t6g_mb_lib.t6g(sch_1):usb2_hub_buf_swb_dn';
NODE_NAME     R5236 2
 '@T6G_MB_LIB.T6G(SCH_1):PAGE358_I90@PURE_QUANTA.Q_RES(CHIPS)':
 'B': CDS_PINID='B';
NODE_NAME     J112 R1
 '@T6G_MB_LIB.T6G(SCH_1):PAGE329_I102@PURE_QUANTA.CONN160_10131762101LF(CHIPS)':
 'R1': CDS_PINID='R1';
NET_NAME
'USB2_HUB_BUF_SWB_DP'
 '@T6G_MB_LIB.T6G(SCH_1):USB2_HUB_BUF_SWB_DP':
 C_SIGNAL='@t6g_mb_lib.t6g(sch_1):usb2_hub_buf_swb_dp';
NODE_NAME     R5234 2
 '@T6G_MB_LIB.T6G(SCH_1):PAGE358_I91@PURE_QUANTA.Q_RES(CHIPS)':
 'B': CDS_PINID='B';
NODE_NAME     J112 S1
 '@T6G_MB_LIB.T6G(SCH_1):PAGE329_I102@PURE_QUANTA.CONN160_10131762101LF(CHIPS)':
 'S1': CDS_PINID='S1';
NET_NAME
'USB2_HUB_BUF_SWB_R_DN'
 '@T6G_MB_LIB.T6G(SCH_1):USB2_HUB_BUF_SWB_R_DN':
 C_SIGNAL='@t6g_mb_lib.t6g(sch_1):usb2_hub_buf_swb_r_dn';
NODE_NAME     R2787 2
 '@T6G_MB_LIB.T6G(SCH_1):PAGE358_I78@PURE_QUANTA.Q_RES(CHIPS)':
 'B': CDS_PINID='B';
NODE_NAME     U5201 1
 '@T6G_MB_LIB.T6G(SCH_1):PAGE358_I84@PURE_QUANTA.TUSB211IRWBR(CHIPS)':
 'D1M': CDS_PINID='D1M';
NODE_NAME     U5201 8
 '@T6G_MB_LIB.T6G(SCH_1):PAGE358_I84@PURE_QUANTA.TUSB211IRWBR(CHIPS)':
 'D2M': CDS_PINID='D2M';
NODE_NAME     R5236 1
 '@T6G_MB_LIB.T6G(SCH_1):PAGE358_I90@PURE_QUANTA.Q_RES(CHIPS)':
 'A': CDS_PINID='A';
NODE_NAME     R2789 2
 '@T6G_MB_LIB.T6G(SCH_1):PAGE358_I98@PURE_QUANTA.Q_RES(CHIPS)':
 'B': CDS_PINID='B';
NET_NAME
'USB2_HUB_BUF_SWB_R_DP'
 '@T6G_MB_LIB.T6G(SCH_1):USB2_HUB_BUF_SWB_R_DP':
 C_SIGNAL='@t6g_mb_lib.t6g(sch_1):usb2_hub_buf_swb_r_dp';
NODE_NAME     R2786 2
 '@T6G_MB_LIB.T6G(SCH_1):PAGE358_I79@PURE_QUANTA.Q_RES(CHIPS)':
 'B': CDS_PINID='B';
NODE_NAME     U5201 2
 '@T6G_MB_LIB.T6G(SCH_1):PAGE358_I84@PURE_QUANTA.TUSB211IRWBR(CHIPS)':
 'D1P': CDS_PINID='D1P';
NODE_NAME     U5201 7
 '@T6G_MB_LIB.T6G(SCH_1):PAGE358_I84@PURE_QUANTA.TUSB211IRWBR(CHIPS)':
 'D2P': CDS_PINID='D2P';
NODE_NAME     R5234 1
 '@T6G_MB_LIB.T6G(SCH_1):PAGE358_I91@PURE_QUANTA.Q_RES(CHIPS)':
 'A': CDS_PINID='A';
NODE_NAME     R2788 2
 '@T6G_MB_LIB.T6G(SCH_1):PAGE358_I99@PURE_QUANTA.Q_RES(CHIPS)':
 'B': CDS_PINID='B';
NET_NAME
'USB2_HUB_EXT_DN'
 '@T6G_MB_LIB.T6G(SCH_1):USB2_HUB_EXT_DN':
 C_SIGNAL='@t6g_mb_lib.t6g(sch_1):usb2_hub_ext_dn';
NODE_NAME     J41 B57
 '@T6G_MB_LIB.T6G(SCH_1):PAGE348_I176@PURE_QUANTA.SCONN168_ME1016810202011(CHIPS)':
 'PETP12': CDS_PINID='PETP12';
NODE_NAME     R6195 2
 '@T6G_MB_LIB.T6G(SCH_1):PAGE158_I71@PURE_QUANTA.Q_RES(CHIPS)':
 'B': CDS_PINID='B';
NODE_NAME     R6197 2
 '@T6G_MB_LIB.T6G(SCH_1):PAGE158_I74@PURE_QUANTA.Q_RES(CHIPS)':
 'B': CDS_PINID='B';
NET_NAME
'USB2_HUB_EXT_DP'
 '@T6G_MB_LIB.T6G(SCH_1):USB2_HUB_EXT_DP':
 C_SIGNAL='@t6g_mb_lib.t6g(sch_1):usb2_hub_ext_dp';
NODE_NAME     J41 B56
 '@T6G_MB_LIB.T6G(SCH_1):PAGE348_I176@PURE_QUANTA.SCONN168_ME1016810202011(CHIPS)':
 'PETN12': CDS_PINID='PETN12';
NODE_NAME     R6194 2
 '@T6G_MB_LIB.T6G(SCH_1):PAGE158_I72@PURE_QUANTA.Q_RES(CHIPS)':
 'B': CDS_PINID='B';
NODE_NAME     R6196 2
 '@T6G_MB_LIB.T6G(SCH_1):PAGE158_I73@PURE_QUANTA.Q_RES(CHIPS)':
 'B': CDS_PINID='B';
NET_NAME
'USB2_HUB_SWB_DN'
 '@T6G_MB_LIB.T6G(SCH_1):USB2_HUB_SWB_DN':
 C_SIGNAL='@t6g_mb_lib.t6g(sch_1):usb2_hub_swb_dn';
NODE_NAME     R2787 1
 '@T6G_MB_LIB.T6G(SCH_1):PAGE358_I78@PURE_QUANTA.Q_RES(CHIPS)':
 'A': CDS_PINID='A';
NODE_NAME     U268 3
 '@T6G_MB_LIB.T6G(SCH_1):PAGE358_I100@PURE_QUANTA.GL852GOHY60(CHIPS)':
 'DM1': CDS_PINID='DM1';
NET_NAME
'USB2_HUB_SWB_DP'
 '@T6G_MB_LIB.T6G(SCH_1):USB2_HUB_SWB_DP':
 C_SIGNAL='@t6g_mb_lib.t6g(sch_1):usb2_hub_swb_dp';
NODE_NAME     R2786 1
 '@T6G_MB_LIB.T6G(SCH_1):PAGE358_I79@PURE_QUANTA.Q_RES(CHIPS)':
 'A': CDS_PINID='A';
NODE_NAME     U268 4
 '@T6G_MB_LIB.T6G(SCH_1):PAGE358_I100@PURE_QUANTA.GL852GOHY60(CHIPS)':
 'DP1': CDS_PINID='DP1';
NET_NAME
'USB2_P0_R_DN'
 '@T6G_MB_LIB.T6G(SCH_1):USB2_P0_R_DN':
 C_SIGNAL='@t6g_mb_lib.t6g(sch_1):usb2_p0_r_dn';
NODE_NAME     U268 1
 '@T6G_MB_LIB.T6G(SCH_1):PAGE358_I100@PURE_QUANTA.GL852GOHY60(CHIPS)':
 'DM0': CDS_PINID='DM0';
NODE_NAME     R3652 1
 '@T6G_MB_LIB.T6G(SCH_1):PAGE358_I137@PURE_QUANTA.Q_RES(CHIPS)':
 'A': CDS_PINID='A';
NET_NAME
'USB2_P0_R_DP'
 '@T6G_MB_LIB.T6G(SCH_1):USB2_P0_R_DP':
 C_SIGNAL='@t6g_mb_lib.t6g(sch_1):usb2_p0_r_dp';
NODE_NAME     U268 2
 '@T6G_MB_LIB.T6G(SCH_1):PAGE358_I100@PURE_QUANTA.GL852GOHY60(CHIPS)':
 'DP0': CDS_PINID='DP0';
NODE_NAME     R3651 1
 '@T6G_MB_LIB.T6G(SCH_1):PAGE358_I138@PURE_QUANTA.Q_RES(CHIPS)':
 'A': CDS_PINID='A';
NET_NAME
'USB2_P10_DN'
 '@T6G_MB_LIB.T6G(SCH_1):USB2_P10_DN':
 C_SIGNAL='@t6g_mb_lib.t6g(sch_1):usb2_p10_dn';
NODE_NAME     J35 A68
 '@T6G_MB_LIB.T6G(SCH_1):PAGE341_I168@PURE_QUANTA.SCONN168_ME1016810202011(CHIPS)':
 'USB_DATN': CDS_PINID='USB_DATN';
NODE_NAME     R3177 1
 '@T6G_MB_LIB.T6G(SCH_1):PAGE341_I136@PURE_QUANTA.Q_RES(CHIPS)':
 'A': CDS_PINID='A';
NET_NAME
'USB2_P10_DP'
 '@T6G_MB_LIB.T6G(SCH_1):USB2_P10_DP':
 C_SIGNAL='@t6g_mb_lib.t6g(sch_1):usb2_p10_dp';
NODE_NAME     J35 A69
 '@T6G_MB_LIB.T6G(SCH_1):PAGE341_I168@PURE_QUANTA.SCONN168_ME1016810202011(CHIPS)':
 'USB_DATP': CDS_PINID='USB_DATP';
NODE_NAME     R3178 1
 '@T6G_MB_LIB.T6G(SCH_1):PAGE341_I135@PURE_QUANTA.Q_RES(CHIPS)':
 'A': CDS_PINID='A';
NET_NAME
'USB2_P11_DN'
 '@T6G_MB_LIB.T6G(SCH_1):USB2_P11_DN':
 C_SIGNAL='@t6g_mb_lib.t6g(sch_1):usb2_p11_dn';
NODE_NAME     J38 A68
 '@T6G_MB_LIB.T6G(SCH_1):PAGE335_I168@PURE_QUANTA.SCONN168_ME1016810202011(CHIPS)':
 'USB_DATN': CDS_PINID='USB_DATN';
NODE_NAME     R42 1
 '@T6G_MB_LIB.T6G(SCH_1):PAGE335_I166@PURE_QUANTA.Q_RES(CHIPS)':
 'A': CDS_PINID='A';
NET_NAME
'USB2_P11_DP'
 '@T6G_MB_LIB.T6G(SCH_1):USB2_P11_DP':
 C_SIGNAL='@t6g_mb_lib.t6g(sch_1):usb2_p11_dp';
NODE_NAME     J38 A69
 '@T6G_MB_LIB.T6G(SCH_1):PAGE335_I168@PURE_QUANTA.SCONN168_ME1016810202011(CHIPS)':
 'USB_DATP': CDS_PINID='USB_DATP';
NODE_NAME     R46 1
 '@T6G_MB_LIB.T6G(SCH_1):PAGE335_I108@PURE_QUANTA.Q_RES(CHIPS)':
 'A': CDS_PINID='A';
NET_NAME
'USB3_CPU0_BMC_HUB1_TX_DN'
 '@T6G_MB_LIB.T6G(SCH_1):USB3_CPU0_BMC_HUB1_TX_DN':
 C_SIGNAL='@t6g_mb_lib.t6g(sch_1):usb3_cpu0_bmc_hub1_tx_dn';
NODE_NAME     U6001 48
 '@T6G_MB_LIB.T6G(SCH_1):PAGE153_I1@PURE_QUANTA.CYUSB330468LTXI(CHIPS)':
 'DS1_TXM': CDS_PINID='DS1_TXM';
NODE_NAME     C6024 1
 '@T6G_MB_LIB.T6G(SCH_1):PAGE158_I138@PURE_QUANTA.Q_CAP(CHIPS)':
 'A': CDS_PINID='A';
NET_NAME
'USB3_CPU0_BMC_HUB1_TX_DP'
 '@T6G_MB_LIB.T6G(SCH_1):USB3_CPU0_BMC_HUB1_TX_DP':
 C_SIGNAL='@t6g_mb_lib.t6g(sch_1):usb3_cpu0_bmc_hub1_tx_dp';
NODE_NAME     U6001 47
 '@T6G_MB_LIB.T6G(SCH_1):PAGE153_I1@PURE_QUANTA.CYUSB330468LTXI(CHIPS)':
 'DS1_TXP': CDS_PINID='DS1_TXP';
NODE_NAME     C6023 1
 '@T6G_MB_LIB.T6G(SCH_1):PAGE158_I137@PURE_QUANTA.Q_CAP(CHIPS)':
 'A': CDS_PINID='A';
NET_NAME
'USB3_CPU0_BMC_HUB2_TX_DN'
 '@T6G_MB_LIB.T6G(SCH_1):USB3_CPU0_BMC_HUB2_TX_DN':
 C_SIGNAL='@t6g_mb_lib.t6g(sch_1):usb3_cpu0_bmc_hub2_tx_dn';
NODE_NAME     C6026 1
 '@T6G_MB_LIB.T6G(SCH_1):PAGE158_I140@PURE_QUANTA.Q_CAP(CHIPS)':
 'A': CDS_PINID='A';
NODE_NAME     U6002 12
 '@T6G_MB_LIB.T6G(SCH_1):PAGE155_I101@PURE_QUANTA.TUSB8042AIRGCR(CHIPS)':
 'USB_SSTXM_DN2': CDS_PINID='USB_SSTXM_DN2';
NET_NAME
'USB3_CPU0_BMC_HUB2_TX_DP'
 '@T6G_MB_LIB.T6G(SCH_1):USB3_CPU0_BMC_HUB2_TX_DP':
 C_SIGNAL='@t6g_mb_lib.t6g(sch_1):usb3_cpu0_bmc_hub2_tx_dp';
NODE_NAME     C6025 1
 '@T6G_MB_LIB.T6G(SCH_1):PAGE158_I139@PURE_QUANTA.Q_CAP(CHIPS)':
 'A': CDS_PINID='A';
NODE_NAME     U6002 11
 '@T6G_MB_LIB.T6G(SCH_1):PAGE155_I101@PURE_QUANTA.TUSB8042AIRGCR(CHIPS)':
 'USB_SSTXP_DN2': CDS_PINID='USB_SSTXP_DN2';
NET_NAME
'USB3_CPU0_BMC_RX_C1_DN'
 '@T6G_MB_LIB.T6G(SCH_1):USB3_CPU0_BMC_RX_C1_DN':
 C_SIGNAL='@t6g_mb_lib.t6g(sch_1):usb3_cpu0_bmc_rx_c1_dn';
NODE_NAME     U6001 50
 '@T6G_MB_LIB.T6G(SCH_1):PAGE153_I1@PURE_QUANTA.CYUSB330468LTXI(CHIPS)':
 'DS1_RXM': CDS_PINID='DS1_RXM';
NODE_NAME     C6020 2
 '@T6G_MB_LIB.T6G(SCH_1):PAGE158_I86@PURE_QUANTA.Q_CAP_DIFFBUS(CHIPS)':
 '2': CDS_PINID='\2\';
NET_NAME
'USB3_CPU0_BMC_RX_C1_DP'
 '@T6G_MB_LIB.T6G(SCH_1):USB3_CPU0_BMC_RX_C1_DP':
 C_SIGNAL='@t6g_mb_lib.t6g(sch_1):usb3_cpu0_bmc_rx_c1_dp';
NODE_NAME     U6001 51
 '@T6G_MB_LIB.T6G(SCH_1):PAGE153_I1@PURE_QUANTA.CYUSB330468LTXI(CHIPS)':
 'DS1_RXP': CDS_PINID='DS1_RXP';
NODE_NAME     C6019 2
 '@T6G_MB_LIB.T6G(SCH_1):PAGE158_I85@PURE_QUANTA.Q_CAP_DIFFBUS(CHIPS)':
 '2': CDS_PINID='\2\';
NET_NAME
'USB3_CPU0_BMC_RX_C2_DN'
 '@T6G_MB_LIB.T6G(SCH_1):USB3_CPU0_BMC_RX_C2_DN':
 C_SIGNAL='@t6g_mb_lib.t6g(sch_1):usb3_cpu0_bmc_rx_c2_dn';
NODE_NAME     C6022 2
 '@T6G_MB_LIB.T6G(SCH_1):PAGE158_I88@PURE_QUANTA.Q_CAP_DIFFBUS(CHIPS)':
 '2': CDS_PINID='\2\';
NODE_NAME     U6002 15
 '@T6G_MB_LIB.T6G(SCH_1):PAGE155_I101@PURE_QUANTA.TUSB8042AIRGCR(CHIPS)':
 'USB_SSRXM_DN2': CDS_PINID='USB_SSRXM_DN2';
NET_NAME
'USB3_CPU0_BMC_RX_C2_DP'
 '@T6G_MB_LIB.T6G(SCH_1):USB3_CPU0_BMC_RX_C2_DP':
 C_SIGNAL='@t6g_mb_lib.t6g(sch_1):usb3_cpu0_bmc_rx_c2_dp';
NODE_NAME     C6021 2
 '@T6G_MB_LIB.T6G(SCH_1):PAGE158_I87@PURE_QUANTA.Q_CAP_DIFFBUS(CHIPS)':
 '2': CDS_PINID='\2\';
NODE_NAME     U6002 14
 '@T6G_MB_LIB.T6G(SCH_1):PAGE155_I101@PURE_QUANTA.TUSB8042AIRGCR(CHIPS)':
 'USB_SSRXP_DN2': CDS_PINID='USB_SSRXP_DN2';
NET_NAME
'USB3_CPU0_BMC_RX_DN'
 '@T6G_MB_LIB.T6G(SCH_1):USB3_CPU0_BMC_RX_DN':
 C_SIGNAL='@t6g_mb_lib.t6g(sch_1):usb3_cpu0_bmc_rx_dn';
NODE_NAME     J41 A60
 '@T6G_MB_LIB.T6G(SCH_1):PAGE348_I176@PURE_QUANTA.SCONN168_ME1016810202011(CHIPS)':
 'PERP13': CDS_PINID='PERP13';
NODE_NAME     C6020 1
 '@T6G_MB_LIB.T6G(SCH_1):PAGE158_I86@PURE_QUANTA.Q_CAP_DIFFBUS(CHIPS)':
 '1': CDS_PINID='\1\';
NODE_NAME     C6022 1
 '@T6G_MB_LIB.T6G(SCH_1):PAGE158_I88@PURE_QUANTA.Q_CAP_DIFFBUS(CHIPS)':
 '1': CDS_PINID='\1\';
NET_NAME
'USB3_CPU0_BMC_RX_DP'
 '@T6G_MB_LIB.T6G(SCH_1):USB3_CPU0_BMC_RX_DP':
 C_SIGNAL='@t6g_mb_lib.t6g(sch_1):usb3_cpu0_bmc_rx_dp';
NODE_NAME     J41 A59
 '@T6G_MB_LIB.T6G(SCH_1):PAGE348_I176@PURE_QUANTA.SCONN168_ME1016810202011(CHIPS)':
 'PERN13': CDS_PINID='PERN13';
NODE_NAME     C6019 1
 '@T6G_MB_LIB.T6G(SCH_1):PAGE158_I85@PURE_QUANTA.Q_CAP_DIFFBUS(CHIPS)':
 '1': CDS_PINID='\1\';
NODE_NAME     C6021 1
 '@T6G_MB_LIB.T6G(SCH_1):PAGE158_I87@PURE_QUANTA.Q_CAP_DIFFBUS(CHIPS)':
 '1': CDS_PINID='\1\';
NET_NAME
'USB3_CPU0_BMC_RX_HUB1_DN'
 '@T6G_MB_LIB.T6G(SCH_1):USB3_CPU0_BMC_RX_HUB1_DN':
 C_SIGNAL='@t6g_mb_lib.t6g(sch_1):usb3_cpu0_bmc_rx_hub1_dn';
NODE_NAME     U6001 5
 '@T6G_MB_LIB.T6G(SCH_1):PAGE153_I1@PURE_QUANTA.CYUSB330468LTXI(CHIPS)':
 'US_TXM': CDS_PINID='US_TXM';
NODE_NAME     C6016 1
 '@T6G_MB_LIB.T6G(SCH_1):PAGE158_I50@PURE_QUANTA.Q_CAP_DIFFBUS(CHIPS)':
 '1': CDS_PINID='\1\';
NET_NAME
'USB3_CPU0_BMC_RX_HUB1_DP'
 '@T6G_MB_LIB.T6G(SCH_1):USB3_CPU0_BMC_RX_HUB1_DP':
 C_SIGNAL='@t6g_mb_lib.t6g(sch_1):usb3_cpu0_bmc_rx_hub1_dp';
NODE_NAME     U6001 6
 '@T6G_MB_LIB.T6G(SCH_1):PAGE153_I1@PURE_QUANTA.CYUSB330468LTXI(CHIPS)':
 'US_TXP': CDS_PINID='US_TXP';
NODE_NAME     C6015 1
 '@T6G_MB_LIB.T6G(SCH_1):PAGE158_I49@PURE_QUANTA.Q_CAP_DIFFBUS(CHIPS)':
 '1': CDS_PINID='\1\';
NET_NAME
'USB3_CPU0_BMC_RX_HUB2_DN'
 '@T6G_MB_LIB.T6G(SCH_1):USB3_CPU0_BMC_RX_HUB2_DN':
 C_SIGNAL='@t6g_mb_lib.t6g(sch_1):usb3_cpu0_bmc_rx_hub2_dn';
NODE_NAME     U6002 56
 '@T6G_MB_LIB.T6G(SCH_1):PAGE155_I101@PURE_QUANTA.TUSB8042AIRGCR(CHIPS)':
 'USB_SSTXM_UP': CDS_PINID='USB_SSTXM_UP';
NODE_NAME     C6018 1
 '@T6G_MB_LIB.T6G(SCH_1):PAGE158_I147@PURE_QUANTA.Q_CAP(CHIPS)':
 'A': CDS_PINID='A';
NET_NAME
'USB3_CPU0_BMC_RX_HUB2_DP'
 '@T6G_MB_LIB.T6G(SCH_1):USB3_CPU0_BMC_RX_HUB2_DP':
 C_SIGNAL='@t6g_mb_lib.t6g(sch_1):usb3_cpu0_bmc_rx_hub2_dp';
NODE_NAME     U6002 55
 '@T6G_MB_LIB.T6G(SCH_1):PAGE155_I101@PURE_QUANTA.TUSB8042AIRGCR(CHIPS)':
 'USB_SSTXP_UP': CDS_PINID='USB_SSTXP_UP';
NODE_NAME     C6017 1
 '@T6G_MB_LIB.T6G(SCH_1):PAGE158_I148@PURE_QUANTA.Q_CAP(CHIPS)':
 'A': CDS_PINID='A';
NET_NAME
'USB3_CPU0_BMC_RX_HUB_C_DN'
 '@T6G_MB_LIB.T6G(SCH_1):USB3_CPU0_BMC_RX_HUB_C_DN':
 C_SIGNAL='@t6g_mb_lib.t6g(sch_1):usb3_cpu0_bmc_rx_hub_c_dn';
NODE_NAME     U25 E26
 '@T6G_MB_LIB.T6G(SCH_1):PAGE29_I287@PURE_QUANTA.GENOA_SP5(CHIPS)':
 'USB00_RXN': CDS_PINID='USB00_RXN';
NODE_NAME     C6016 2
 '@T6G_MB_LIB.T6G(SCH_1):PAGE158_I50@PURE_QUANTA.Q_CAP_DIFFBUS(CHIPS)':
 '2': CDS_PINID='\2\';
NODE_NAME     C6018 2
 '@T6G_MB_LIB.T6G(SCH_1):PAGE158_I147@PURE_QUANTA.Q_CAP(CHIPS)':
 'B': CDS_PINID='B';
NET_NAME
'USB3_CPU0_BMC_RX_HUB_C_DP'
 '@T6G_MB_LIB.T6G(SCH_1):USB3_CPU0_BMC_RX_HUB_C_DP':
 C_SIGNAL='@t6g_mb_lib.t6g(sch_1):usb3_cpu0_bmc_rx_hub_c_dp';
NODE_NAME     U25 E27
 '@T6G_MB_LIB.T6G(SCH_1):PAGE29_I287@PURE_QUANTA.GENOA_SP5(CHIPS)':
 'USB00_RXP': CDS_PINID='USB00_RXP';
NODE_NAME     C6015 2
 '@T6G_MB_LIB.T6G(SCH_1):PAGE158_I49@PURE_QUANTA.Q_CAP_DIFFBUS(CHIPS)':
 '2': CDS_PINID='\2\';
NODE_NAME     C6017 2
 '@T6G_MB_LIB.T6G(SCH_1):PAGE158_I148@PURE_QUANTA.Q_CAP(CHIPS)':
 'B': CDS_PINID='B';
NET_NAME
'USB3_CPU0_BMC_TX_BUF_C_DN'
 '@T6G_MB_LIB.T6G(SCH_1):USB3_CPU0_BMC_TX_BUF_C_DN':
 C_SIGNAL='@t6g_mb_lib.t6g(sch_1):usb3_cpu0_bmc_tx_buf_c_dn';
NODE_NAME     J41 B60
 '@T6G_MB_LIB.T6G(SCH_1):PAGE348_I176@PURE_QUANTA.SCONN168_ME1016810202011(CHIPS)':
 'PETP13': CDS_PINID='PETP13';
NODE_NAME     C6024 2
 '@T6G_MB_LIB.T6G(SCH_1):PAGE158_I138@PURE_QUANTA.Q_CAP(CHIPS)':
 'B': CDS_PINID='B';
NODE_NAME     C6026 2
 '@T6G_MB_LIB.T6G(SCH_1):PAGE158_I140@PURE_QUANTA.Q_CAP(CHIPS)':
 'B': CDS_PINID='B';
NET_NAME
'USB3_CPU0_BMC_TX_BUF_C_DP'
 '@T6G_MB_LIB.T6G(SCH_1):USB3_CPU0_BMC_TX_BUF_C_DP':
 C_SIGNAL='@t6g_mb_lib.t6g(sch_1):usb3_cpu0_bmc_tx_buf_c_dp';
NODE_NAME     J41 B59
 '@T6G_MB_LIB.T6G(SCH_1):PAGE348_I176@PURE_QUANTA.SCONN168_ME1016810202011(CHIPS)':
 'PETN13': CDS_PINID='PETN13';
NODE_NAME     C6023 2
 '@T6G_MB_LIB.T6G(SCH_1):PAGE158_I137@PURE_QUANTA.Q_CAP(CHIPS)':
 'B': CDS_PINID='B';
NODE_NAME     C6025 2
 '@T6G_MB_LIB.T6G(SCH_1):PAGE158_I139@PURE_QUANTA.Q_CAP(CHIPS)':
 'B': CDS_PINID='B';
NET_NAME
'USB3_CPU0_BMC_TX_C1_DN'
 '@T6G_MB_LIB.T6G(SCH_1):USB3_CPU0_BMC_TX_C1_DN':
 C_SIGNAL='@t6g_mb_lib.t6g(sch_1):usb3_cpu0_bmc_tx_c1_dn';
NODE_NAME     U6001 8
 '@T6G_MB_LIB.T6G(SCH_1):PAGE153_I1@PURE_QUANTA.CYUSB330468LTXI(CHIPS)':
 'US_RXM': CDS_PINID='US_RXM';
NODE_NAME     C6004 2
 '@T6G_MB_LIB.T6G(SCH_1):PAGE158_I143@PURE_QUANTA.Q_CAP(CHIPS)':
 'B': CDS_PINID='B';
NET_NAME
'USB3_CPU0_BMC_TX_C1_DP'
 '@T6G_MB_LIB.T6G(SCH_1):USB3_CPU0_BMC_TX_C1_DP':
 C_SIGNAL='@t6g_mb_lib.t6g(sch_1):usb3_cpu0_bmc_tx_c1_dp';
NODE_NAME     U6001 9
 '@T6G_MB_LIB.T6G(SCH_1):PAGE153_I1@PURE_QUANTA.CYUSB330468LTXI(CHIPS)':
 'US_RXP': CDS_PINID='US_RXP';
NODE_NAME     C6003 2
 '@T6G_MB_LIB.T6G(SCH_1):PAGE158_I144@PURE_QUANTA.Q_CAP(CHIPS)':
 'B': CDS_PINID='B';
NET_NAME
'USB3_CPU0_BMC_TX_C2_DN'
 '@T6G_MB_LIB.T6G(SCH_1):USB3_CPU0_BMC_TX_C2_DN':
 C_SIGNAL='@t6g_mb_lib.t6g(sch_1):usb3_cpu0_bmc_tx_c2_dn';
NODE_NAME     R346 1
 '@T6G_MB_LIB.T6G(SCH_1):PAGE158_I126@PURE_QUANTA.Q_RES(CHIPS)':
 'A': CDS_PINID='A';
NODE_NAME     C6014 2
 '@T6G_MB_LIB.T6G(SCH_1):PAGE158_I141@PURE_QUANTA.Q_CAP(CHIPS)':
 'B': CDS_PINID='B';
NODE_NAME     U6002 59
 '@T6G_MB_LIB.T6G(SCH_1):PAGE155_I101@PURE_QUANTA.TUSB8042AIRGCR(CHIPS)':
 'USB_SSRXM_UP': CDS_PINID='USB_SSRXM_UP';
NET_NAME
'USB3_CPU0_BMC_TX_C2_DP'
 '@T6G_MB_LIB.T6G(SCH_1):USB3_CPU0_BMC_TX_C2_DP':
 C_SIGNAL='@t6g_mb_lib.t6g(sch_1):usb3_cpu0_bmc_tx_c2_dp';
NODE_NAME     R344 1
 '@T6G_MB_LIB.T6G(SCH_1):PAGE158_I127@PURE_QUANTA.Q_RES(CHIPS)':
 'A': CDS_PINID='A';
NODE_NAME     C6013 2
 '@T6G_MB_LIB.T6G(SCH_1):PAGE158_I142@PURE_QUANTA.Q_CAP(CHIPS)':
 'B': CDS_PINID='B';
NODE_NAME     U6002 58
 '@T6G_MB_LIB.T6G(SCH_1):PAGE155_I101@PURE_QUANTA.TUSB8042AIRGCR(CHIPS)':
 'USB_SSRXP_UP': CDS_PINID='USB_SSRXP_UP';
NET_NAME
'USB3_CPU0_BMC_TX_DN'
 '@T6G_MB_LIB.T6G(SCH_1):USB3_CPU0_BMC_TX_DN':
 C_SIGNAL='@t6g_mb_lib.t6g(sch_1):usb3_cpu0_bmc_tx_dn';
NODE_NAME     U25 C26
 '@T6G_MB_LIB.T6G(SCH_1):PAGE29_I287@PURE_QUANTA.GENOA_SP5(CHIPS)':
 'USB00_TXN': CDS_PINID='USB00_TXN';
NODE_NAME     C6014 1
 '@T6G_MB_LIB.T6G(SCH_1):PAGE158_I141@PURE_QUANTA.Q_CAP(CHIPS)':
 'A': CDS_PINID='A';
NODE_NAME     C6004 1
 '@T6G_MB_LIB.T6G(SCH_1):PAGE158_I143@PURE_QUANTA.Q_CAP(CHIPS)':
 'A': CDS_PINID='A';
NODE_NAME     R342 1
 '@T6G_MB_LIB.T6G(SCH_1):PAGE158_I146@PURE_QUANTA.Q_RES(CHIPS)':
 'A': CDS_PINID='A';
NET_NAME
'USB3_CPU0_BMC_TX_DP'
 '@T6G_MB_LIB.T6G(SCH_1):USB3_CPU0_BMC_TX_DP':
 C_SIGNAL='@t6g_mb_lib.t6g(sch_1):usb3_cpu0_bmc_tx_dp';
NODE_NAME     U25 C25
 '@T6G_MB_LIB.T6G(SCH_1):PAGE29_I287@PURE_QUANTA.GENOA_SP5(CHIPS)':
 'USB00_TXP': CDS_PINID='USB00_TXP';
NODE_NAME     C6013 1
 '@T6G_MB_LIB.T6G(SCH_1):PAGE158_I142@PURE_QUANTA.Q_CAP(CHIPS)':
 'A': CDS_PINID='A';
NODE_NAME     C6003 1
 '@T6G_MB_LIB.T6G(SCH_1):PAGE158_I144@PURE_QUANTA.Q_CAP(CHIPS)':
 'A': CDS_PINID='A';
NODE_NAME     R341 1
 '@T6G_MB_LIB.T6G(SCH_1):PAGE158_I145@PURE_QUANTA.Q_RES(CHIPS)':
 'A': CDS_PINID='A';
NET_NAME
'USB_CPU0_ADD_A0'
 '@T6G_MB_LIB.T6G(SCH_1):USB_CPU0_ADD_A0':
 C_SIGNAL='@t6g_mb_lib.t6g(sch_1):usb_cpu0_add_a0';
NODE_NAME     U6003 1
 '@T6G_MB_LIB.T6G(SCH_1):PAGE153_I64@PURE_QUANTA.M24128BWMN6TP(CHIPS)':
 'E0': CDS_PINID='E0';
NODE_NAME     R6222 2
 '@T6G_MB_LIB.T6G(SCH_1):PAGE153_I65@PURE_QUANTA.Q_RES(CHIPS)':
 'B': CDS_PINID='B';
NODE_NAME     R6217 1
 '@T6G_MB_LIB.T6G(SCH_1):PAGE153_I68@PURE_QUANTA.Q_RES(CHIPS)':
 'A': CDS_PINID='A';
NET_NAME
'USB_CPU0_ADD_A1'
 '@T6G_MB_LIB.T6G(SCH_1):USB_CPU0_ADD_A1':
 C_SIGNAL='@t6g_mb_lib.t6g(sch_1):usb_cpu0_add_a1';
NODE_NAME     U6003 2
 '@T6G_MB_LIB.T6G(SCH_1):PAGE153_I64@PURE_QUANTA.M24128BWMN6TP(CHIPS)':
 'E1': CDS_PINID='E1';
NODE_NAME     R6219 1
 '@T6G_MB_LIB.T6G(SCH_1):PAGE153_I66@PURE_QUANTA.Q_RES(CHIPS)':
 'A': CDS_PINID='A';
NODE_NAME     R6218 2
 '@T6G_MB_LIB.T6G(SCH_1):PAGE153_I69@PURE_QUANTA.Q_RES(CHIPS)':
 'B': CDS_PINID='B';
NET_NAME
'USB_CPU0_ADD_A2'
 '@T6G_MB_LIB.T6G(SCH_1):USB_CPU0_ADD_A2':
 C_SIGNAL='@t6g_mb_lib.t6g(sch_1):usb_cpu0_add_a2';
NODE_NAME     U6003 3
 '@T6G_MB_LIB.T6G(SCH_1):PAGE153_I64@PURE_QUANTA.M24128BWMN6TP(CHIPS)':
 'E2': CDS_PINID='E2';
NODE_NAME     R6221 1
 '@T6G_MB_LIB.T6G(SCH_1):PAGE153_I67@PURE_QUANTA.Q_RES(CHIPS)':
 'A': CDS_PINID='A';
NODE_NAME     R6220 2
 '@T6G_MB_LIB.T6G(SCH_1):PAGE153_I70@PURE_QUANTA.Q_RES(CHIPS)':
 'B': CDS_PINID='B';
NET_NAME
'USB_CPU0_HUB1_MODE_SEL0'
 '@T6G_MB_LIB.T6G(SCH_1):USB_CPU0_HUB1_MODE_SEL0':
 C_SIGNAL='@t6g_mb_lib.t6g(sch_1):usb_cpu0_hub1_mode_sel0';
NODE_NAME     U6001 23
 '@T6G_MB_LIB.T6G(SCH_1):PAGE153_I1@PURE_QUANTA.CYUSB330468LTXI(CHIPS)':
 'MODE_SEL0': CDS_PINID='MODE_SEL0';
NODE_NAME     R6215 2
 '@T6G_MB_LIB.T6G(SCH_1):PAGE153_I89@PURE_QUANTA.Q_RES(CHIPS)':
 'B': CDS_PINID='B';
NODE_NAME     R6216 1
 '@T6G_MB_LIB.T6G(SCH_1):PAGE153_I90@PURE_QUANTA.Q_RES(CHIPS)':
 'A': CDS_PINID='A';
NET_NAME
'USB_CPU0_HUB1_MODE_SEL1'
 '@T6G_MB_LIB.T6G(SCH_1):USB_CPU0_HUB1_MODE_SEL1':
 C_SIGNAL='@t6g_mb_lib.t6g(sch_1):usb_cpu0_hub1_mode_sel1';
NODE_NAME     U6001 24
 '@T6G_MB_LIB.T6G(SCH_1):PAGE153_I1@PURE_QUANTA.CYUSB330468LTXI(CHIPS)':
 'MODE_SEL1': CDS_PINID='MODE_SEL1';
NODE_NAME     R6213 2
 '@T6G_MB_LIB.T6G(SCH_1):PAGE153_I87@PURE_QUANTA.Q_RES(CHIPS)':
 'B': CDS_PINID='B';
NODE_NAME     R6214 1
 '@T6G_MB_LIB.T6G(SCH_1):PAGE153_I88@PURE_QUANTA.Q_RES(CHIPS)':
 'A': CDS_PINID='A';
NET_NAME
'USB_CPU0_HUB1_RREF_SS'
 '@T6G_MB_LIB.T6G(SCH_1):USB_CPU0_HUB1_RREF_SS':
 C_SIGNAL='@t6g_mb_lib.t6g(sch_1):usb_cpu0_hub1_rref_ss';
NODE_NAME     U6001 26
 '@T6G_MB_LIB.T6G(SCH_1):PAGE153_I1@PURE_QUANTA.CYUSB330468LTXI(CHIPS)':
 'RREF_SS': CDS_PINID='RREF_SS';
NODE_NAME     R6202 2
 '@T6G_MB_LIB.T6G(SCH_1):PAGE153_I37@PURE_QUANTA.Q_RES(CHIPS)':
 'B': CDS_PINID='B';
NET_NAME
'USB_CPU0_HUB1_RREF_USB2'
 '@T6G_MB_LIB.T6G(SCH_1):USB_CPU0_HUB1_RREF_USB2':
 C_SIGNAL='@t6g_mb_lib.t6g(sch_1):usb_cpu0_hub1_rref_usb2';
NODE_NAME     U6001 2
 '@T6G_MB_LIB.T6G(SCH_1):PAGE153_I1@PURE_QUANTA.CYUSB330468LTXI(CHIPS)':
 'RREF_USB2': CDS_PINID='RREF_USB2';
NODE_NAME     R6203 2
 '@T6G_MB_LIB.T6G(SCH_1):PAGE153_I39@PURE_QUANTA.Q_RES(CHIPS)':
 'B': CDS_PINID='B';
NET_NAME
'USB_CPU0_HUB1_VBUS_DS'
 '@T6G_MB_LIB.T6G(SCH_1):USB_CPU0_HUB1_VBUS_DS':
 C_SIGNAL='@t6g_mb_lib.t6g(sch_1):usb_cpu0_hub1_vbus_ds';
NODE_NAME     U6001 18
 '@T6G_MB_LIB.T6G(SCH_1):PAGE153_I1@PURE_QUANTA.CYUSB330468LTXI(CHIPS)':
 'VBUS_DS': CDS_PINID='VBUS_DS';
NODE_NAME     R4450 1
 '@T6G_MB_LIB.T6G(SCH_1):PAGE153_I27@PURE_QUANTA.Q_RES(CHIPS)':
 'A': CDS_PINID='A';
NET_NAME
'USB_CPU0_HUB1_VBUS_US'
 '@T6G_MB_LIB.T6G(SCH_1):USB_CPU0_HUB1_VBUS_US':
 C_SIGNAL='@t6g_mb_lib.t6g(sch_1):usb_cpu0_hub1_vbus_us';
NODE_NAME     U6001 17
 '@T6G_MB_LIB.T6G(SCH_1):PAGE153_I1@PURE_QUANTA.CYUSB330468LTXI(CHIPS)':
 'VBUS_US': CDS_PINID='VBUS_US';
NODE_NAME     R6208 2
 '@T6G_MB_LIB.T6G(SCH_1):PAGE153_I47@PURE_QUANTA.Q_RES(CHIPS)':
 'B': CDS_PINID='B';
NODE_NAME     R6209 1
 '@T6G_MB_LIB.T6G(SCH_1):PAGE153_I48@PURE_QUANTA.Q_RES(CHIPS)':
 'A': CDS_PINID='A';
NET_NAME
'USB_HUB2_MRP_CFG_BC_EN'
 '@T6G_MB_LIB.T6G(SCH_1):USB_HUB2_MRP_CFG_BC_EN':
 C_SIGNAL='@t6g_mb_lib.t6g(sch_1):usb_hub2_mrp_cfg_bc_en';
NODE_NAME     R6303 2
 '@T6G_MB_LIB.T6G(SCH_1):PAGE155_I169@PURE_QUANTA.Q_RES(CHIPS)':
 'B': CDS_PINID='B';
NODE_NAME     R6302 1
 '@T6G_MB_LIB.T6G(SCH_1):PAGE155_I175@PURE_QUANTA.Q_RES(CHIPS)':
 'A': CDS_PINID='A';
NODE_NAME     R6300 1
 '@T6G_MB_LIB.T6G(SCH_1):PAGE155_I181@PURE_QUANTA.Q_RES(CHIPS)':
 'A': CDS_PINID='A';
NET_NAME
'USB_HUB2_MRP_CFG_NON_REM'
 '@T6G_MB_LIB.T6G(SCH_1):USB_HUB2_MRP_CFG_NON_REM':
 C_SIGNAL='@t6g_mb_lib.t6g(sch_1):usb_hub2_mrp_cfg_non_rem';
NODE_NAME     R6305 1
 '@T6G_MB_LIB.T6G(SCH_1):PAGE157_I150@PURE_QUANTA.Q_RES(CHIPS)':
 'A': CDS_PINID='A';
NODE_NAME     R6308 2
 '@T6G_MB_LIB.T6G(SCH_1):PAGE157_I153@PURE_QUANTA.Q_RES(CHIPS)':
 'B': CDS_PINID='B';
NODE_NAME     R6309 1
 '@T6G_MB_LIB.T6G(SCH_1):PAGE157_I158@PURE_QUANTA.Q_RES(CHIPS)':
 'A': CDS_PINID='A';
NET_NAME
'USB_HUB2_MRP_CFG_STRAP'
 '@T6G_MB_LIB.T6G(SCH_1):USB_HUB2_MRP_CFG_STRAP':
 C_SIGNAL='@t6g_mb_lib.t6g(sch_1):usb_hub2_mrp_cfg_strap';
NODE_NAME     R6271 2
 '@T6G_MB_LIB.T6G(SCH_1):PAGE155_I102@PURE_QUANTA.Q_RES(CHIPS)':
 'B': CDS_PINID='B';
NODE_NAME     R6273 2
 '@T6G_MB_LIB.T6G(SCH_1):PAGE155_I104@PURE_QUANTA.Q_RES(CHIPS)':
 'B': CDS_PINID='B';
NODE_NAME     R6272 1
 '@T6G_MB_LIB.T6G(SCH_1):PAGE155_I105@PURE_QUANTA.Q_RES(CHIPS)':
 'A': CDS_PINID='A';
NET_NAME
'USB_HUB2_MRP_I2C_SLV_CFG0'
 '@T6G_MB_LIB.T6G(SCH_1):USB_HUB2_MRP_I2C_SLV_CFG0':
 C_SIGNAL='@t6g_mb_lib.t6g(sch_1):usb_hub2_mrp_i2c_slv_cfg0';
NODE_NAME     R6291 2
 '@T6G_MB_LIB.T6G(SCH_1):PAGE157_I75@PURE_QUANTA.Q_RES(CHIPS)':
 'B': CDS_PINID='B';
NODE_NAME     R6294 2
 '@T6G_MB_LIB.T6G(SCH_1):PAGE157_I81@PURE_QUANTA.Q_RES(CHIPS)':
 'B': CDS_PINID='B';
NET_NAME
'USB_HUB2_MRP_I2C_SLV_CFG1'
 '@T6G_MB_LIB.T6G(SCH_1):USB_HUB2_MRP_I2C_SLV_CFG1':
 C_SIGNAL='@t6g_mb_lib.t6g(sch_1):usb_hub2_mrp_i2c_slv_cfg1';
NODE_NAME     R6296 1
 '@T6G_MB_LIB.T6G(SCH_1):PAGE155_I183@PURE_QUANTA.Q_RES(CHIPS)':
 'A': CDS_PINID='A';
NODE_NAME     R6298 2
 '@T6G_MB_LIB.T6G(SCH_1):PAGE155_I187@PURE_QUANTA.Q_RES(CHIPS)':
 'B': CDS_PINID='B';
NET_NAME
'USB_HUB2_MRP_PROG_FUNC6'
 '@T6G_MB_LIB.T6G(SCH_1):USB_HUB2_MRP_PROG_FUNC6':
 C_SIGNAL='@t6g_mb_lib.t6g(sch_1):usb_hub2_mrp_prog_func6';
NODE_NAME     R6326 1
 '@T6G_MB_LIB.T6G(SCH_1):PAGE155_I89@PURE_QUANTA.Q_RES(CHIPS)':
 'A': CDS_PINID='A';
NODE_NAME     R6327 2
 '@T6G_MB_LIB.T6G(SCH_1):PAGE155_I91@PURE_QUANTA.Q_RES(CHIPS)':
 'B': CDS_PINID='B';
NODE_NAME     R6324 1
 '@T6G_MB_LIB.T6G(SCH_1):PAGE155_I118@PURE_QUANTA.Q_RES(CHIPS)':
 'A': CDS_PINID='A';
NET_NAME
'USB_HUB2_MRP_PRT_CTL4_GANGPWR'
 '@T6G_MB_LIB.T6G(SCH_1):USB_HUB2_MRP_PRT_CTL4_GANGPWR':
 C_SIGNAL='@t6g_mb_lib.t6g(sch_1):usb_hub2_mrp_prt_ctl4_gangpwr';
NODE_NAME     R6278 1
 '@T6G_MB_LIB.T6G(SCH_1):PAGE157_I124@PURE_QUANTA.Q_RES(CHIPS)':
 'A': CDS_PINID='A';
NODE_NAME     R6276 2
 '@T6G_MB_LIB.T6G(SCH_1):PAGE157_I125@PURE_QUANTA.Q_RES(CHIPS)':
 'B': CDS_PINID='B';
NODE_NAME     R6277 2
 '@T6G_MB_LIB.T6G(SCH_1):PAGE157_I130@PURE_QUANTA.Q_RES(CHIPS)':
 'B': CDS_PINID='B';
NET_NAME
'USB_HUB2_MRP_RESET_N'
 '@T6G_MB_LIB.T6G(SCH_1):USB_HUB2_MRP_RESET_N':
 C_SIGNAL='@t6g_mb_lib.t6g(sch_1):usb_hub2_mrp_reset_n';
NODE_NAME     R6317 1
 '@T6G_MB_LIB.T6G(SCH_1):PAGE155_I124@PURE_QUANTA.Q_RES(CHIPS)':
 'A': CDS_PINID='A';
NODE_NAME     C6088 1
 '@T6G_MB_LIB.T6G(SCH_1):PAGE155_I127@PURE_QUANTA.Q_CAP(CHIPS)':
 'A': CDS_PINID='A';
NODE_NAME     R6321 1
 '@T6G_MB_LIB.T6G(SCH_1):PAGE155_I129@PURE_QUANTA.Q_RES(CHIPS)':
 'A': CDS_PINID='A';
NODE_NAME     R6322 2
 '@T6G_MB_LIB.T6G(SCH_1):PAGE155_I131@PURE_QUANTA.Q_RES(CHIPS)':
 'B': CDS_PINID='B';
NODE_NAME     R6320 2
 '@T6G_MB_LIB.T6G(SCH_1):PAGE155_I212@PURE_QUANTA.Q_RES(CHIPS)':
 'B': CDS_PINID='B';
NET_NAME
'USB_HUB2_MRP_VBUS_DET'
 '@T6G_MB_LIB.T6G(SCH_1):USB_HUB2_MRP_VBUS_DET':
 C_SIGNAL='@t6g_mb_lib.t6g(sch_1):usb_hub2_mrp_vbus_det';
NODE_NAME     R6286 1
 '@T6G_MB_LIB.T6G(SCH_1):PAGE155_I193@PURE_QUANTA.Q_RES(CHIPS)':
 'A': CDS_PINID='A';
NODE_NAME     R6289 2
 '@T6G_MB_LIB.T6G(SCH_1):PAGE155_I195@PURE_QUANTA.Q_RES(CHIPS)':
 'B': CDS_PINID='B';
NET_NAME
'USB_HUB2_TI_FULLPWRMGMTZ_MRP_PROG_FUNC3'
 '@T6G_MB_LIB.T6G(SCH_1):USB_HUB2_TI_FULLPWRMGMTZ_MRP_PROG_FUNC3':
 C_SIGNAL='@t6g_mb_lib.t6g(sch_1):usb_hub2_ti_fullpwrmgmtz_mrp_prog_func3';
NODE_NAME     R6283 2
 '@T6G_MB_LIB.T6G(SCH_1):PAGE157_I63@PURE_QUANTA.Q_RES(CHIPS)':
 'B': CDS_PINID='B';
NODE_NAME     U6002 40
 '@T6G_MB_LIB.T6G(SCH_1):PAGE157_I119@PURE_QUANTA.TUSB8042AIRGCR(CHIPS)':
 'FULLPWRMGMTZ||FULLAUTOZ||SMBA1||SS_UP': CDS_PINID='\fullpwrmgmtz||fullautoz||smba1||ss_up\';
NODE_NAME     R6284 1
 '@T6G_MB_LIB.T6G(SCH_1):PAGE157_I171@PURE_QUANTA.Q_RES(CHIPS)':
 'A': CDS_PINID='A';
NET_NAME
'USB_HUB2_TI_GANGED'
 '@T6G_MB_LIB.T6G(SCH_1):USB_HUB2_TI_GANGED':
 C_SIGNAL='@t6g_mb_lib.t6g(sch_1):usb_hub2_ti_ganged';
NODE_NAME     R6290 2
 '@T6G_MB_LIB.T6G(SCH_1):PAGE157_I76@PURE_QUANTA.Q_RES(CHIPS)':
 'B': CDS_PINID='B';
NODE_NAME     R6292 2
 '@T6G_MB_LIB.T6G(SCH_1):PAGE157_I77@PURE_QUANTA.Q_RES(CHIPS)':
 'B': CDS_PINID='B';
NODE_NAME     R6293 1
 '@T6G_MB_LIB.T6G(SCH_1):PAGE157_I79@PURE_QUANTA.Q_RES(CHIPS)':
 'A': CDS_PINID='A';
NET_NAME
'USB_HUB2_TI_GANGED_MRP_I2C_SLV_CFG0'
 '@T6G_MB_LIB.T6G(SCH_1):USB_HUB2_TI_GANGED_MRP_I2C_SLV_CFG0':
 C_SIGNAL='@t6g_mb_lib.t6g(sch_1):usb_hub2_ti_ganged_mrp_i2c_slv_cfg0';
NODE_NAME     R6291 1
 '@T6G_MB_LIB.T6G(SCH_1):PAGE157_I75@PURE_QUANTA.Q_RES(CHIPS)':
 'A': CDS_PINID='A';
NODE_NAME     R6290 1
 '@T6G_MB_LIB.T6G(SCH_1):PAGE157_I76@PURE_QUANTA.Q_RES(CHIPS)':
 'A': CDS_PINID='A';
NODE_NAME     U6002 42
 '@T6G_MB_LIB.T6G(SCH_1):PAGE157_I119@PURE_QUANTA.TUSB8042AIRGCR(CHIPS)':
 'GANGED||SMBA2||HS_UP': CDS_PINID='\ganged||smba2||hs_up\';
NET_NAME
'USB_HUB2_TI_GRSTZ_MRP_PROG_FUNC1'
 '@T6G_MB_LIB.T6G(SCH_1):USB_HUB2_TI_GRSTZ_MRP_PROG_FUNC1':
 C_SIGNAL='@t6g_mb_lib.t6g(sch_1):usb_hub2_ti_grstz_mrp_prog_func1';
NODE_NAME     U6002 50
 '@T6G_MB_LIB.T6G(SCH_1):PAGE155_I101@PURE_QUANTA.TUSB8042AIRGCR(CHIPS)':
 'GRSTZ': CDS_PINID='GRSTZ';
NODE_NAME     R6333 1
 '@T6G_MB_LIB.T6G(SCH_1):PAGE155_I111@PURE_QUANTA.Q_RES(CHIPS)':
 'A': CDS_PINID='A';
NODE_NAME     R6328 2
 '@T6G_MB_LIB.T6G(SCH_1):PAGE155_I114@PURE_QUANTA.Q_RES(CHIPS)':
 'B': CDS_PINID='B';
NODE_NAME     C6089 1
 '@T6G_MB_LIB.T6G(SCH_1):PAGE155_I145@PURE_QUANTA.Q_CAP(CHIPS)':
 'A': CDS_PINID='A';
NODE_NAME     R6329 2
 '@T6G_MB_LIB.T6G(SCH_1):PAGE155_I213@PURE_QUANTA.Q_RES(CHIPS)':
 'B': CDS_PINID='B';
NET_NAME
'USB_HUB2_TI_HS_SUSPEND'
 '@T6G_MB_LIB.T6G(SCH_1):USB_HUB2_TI_HS_SUSPEND':
 C_SIGNAL='@t6g_mb_lib.t6g(sch_1):usb_hub2_ti_hs_suspend';
NODE_NAME     R6304 1
 '@T6G_MB_LIB.T6G(SCH_1):PAGE157_I151@PURE_QUANTA.Q_RES(CHIPS)':
 'A': CDS_PINID='A';
NODE_NAME     R6306 2
 '@T6G_MB_LIB.T6G(SCH_1):PAGE157_I155@PURE_QUANTA.Q_RES(CHIPS)':
 'B': CDS_PINID='B';
NODE_NAME     R6307 1
 '@T6G_MB_LIB.T6G(SCH_1):PAGE157_I156@PURE_QUANTA.Q_RES(CHIPS)':
 'A': CDS_PINID='A';
NET_NAME
'USB_HUB2_TI_HS_SUSPEND_MRP_CFG_NON_REM'
 '@T6G_MB_LIB.T6G(SCH_1):USB_HUB2_TI_HS_SUSPEND_MRP_CFG_NON_REM':
 C_SIGNAL='@t6g_mb_lib.t6g(sch_1):usb_hub2_ti_hs_suspend_mrp_cfg_non_rem';
NODE_NAME     U6002 45
 '@T6G_MB_LIB.T6G(SCH_1):PAGE157_I119@PURE_QUANTA.TUSB8042AIRGCR(CHIPS)':
 'AUTOENZ||HS_SUSPEND': CDS_PINID='\autoenz||hs_suspend\';
NODE_NAME     R6305 2
 '@T6G_MB_LIB.T6G(SCH_1):PAGE157_I150@PURE_QUANTA.Q_RES(CHIPS)':
 'B': CDS_PINID='B';
NODE_NAME     R6304 2
 '@T6G_MB_LIB.T6G(SCH_1):PAGE157_I151@PURE_QUANTA.Q_RES(CHIPS)':
 'B': CDS_PINID='B';
NET_NAME
'USB_HUB2_TI_NC_MRP_ATEST'
 '@T6G_MB_LIB.T6G(SCH_1):USB_HUB2_TI_NC_MRP_ATEST':
 C_SIGNAL='@t6g_mb_lib.t6g(sch_1):usb_hub2_ti_nc_mrp_atest';
NODE_NAME     U6002 60
 '@T6G_MB_LIB.T6G(SCH_1):PAGE155_I101@PURE_QUANTA.TUSB8042AIRGCR(CHIPS)':
 'NC_1': CDS_PINID='NC_1';
NODE_NAME     R6330 2
 '@T6G_MB_LIB.T6G(SCH_1):PAGE155_I188@PURE_QUANTA.Q_RES(CHIPS)':
 'B': CDS_PINID='B';
NET_NAME
'USB_HUB2_TI_OVERCCUR4'
 '@T6G_MB_LIB.T6G(SCH_1):USB_HUB2_TI_OVERCCUR4':
 C_SIGNAL='@t6g_mb_lib.t6g(sch_1):usb_hub2_ti_overccur4';
NODE_NAME     R6295 1
 '@T6G_MB_LIB.T6G(SCH_1):PAGE155_I182@PURE_QUANTA.Q_RES(CHIPS)':
 'A': CDS_PINID='A';
NODE_NAME     R6297 2
 '@T6G_MB_LIB.T6G(SCH_1):PAGE155_I185@PURE_QUANTA.Q_RES(CHIPS)':
 'B': CDS_PINID='B';
NET_NAME
'USB_HUB2_TI_OVERCUR1'
 '@T6G_MB_LIB.T6G(SCH_1):USB_HUB2_TI_OVERCUR1':
 C_SIGNAL='@t6g_mb_lib.t6g(sch_1):usb_hub2_ti_overcur1';
NODE_NAME     R6310 1
 '@T6G_MB_LIB.T6G(SCH_1):PAGE155_I202@PURE_QUANTA.Q_RES(CHIPS)':
 'A': CDS_PINID='A';
NODE_NAME     R6312 2
 '@T6G_MB_LIB.T6G(SCH_1):PAGE155_I205@PURE_QUANTA.Q_RES(CHIPS)':
 'B': CDS_PINID='B';
NET_NAME
'USB_HUB2_TI_OVERCUR1_MRP_PROG_FUNC4'
 '@T6G_MB_LIB.T6G(SCH_1):USB_HUB2_TI_OVERCUR1_MRP_PROG_FUNC4':
 C_SIGNAL='@t6g_mb_lib.t6g(sch_1):usb_hub2_ti_overcur1_mrp_prog_func4';
NODE_NAME     U6002 46
 '@T6G_MB_LIB.T6G(SCH_1):PAGE155_I101@PURE_QUANTA.TUSB8042AIRGCR(CHIPS)':
 'OVERCUR1Z': CDS_PINID='OVERCUR1Z';
NODE_NAME     R6311 2
 '@T6G_MB_LIB.T6G(SCH_1):PAGE155_I200@PURE_QUANTA.Q_RES(CHIPS)':
 'B': CDS_PINID='B';
NODE_NAME     R6310 2
 '@T6G_MB_LIB.T6G(SCH_1):PAGE155_I202@PURE_QUANTA.Q_RES(CHIPS)':
 'B': CDS_PINID='B';
NET_NAME
'USB_HUB2_TI_OVERCUR2'
 '@T6G_MB_LIB.T6G(SCH_1):USB_HUB2_TI_OVERCUR2':
 C_SIGNAL='@t6g_mb_lib.t6g(sch_1):usb_hub2_ti_overcur2';
NODE_NAME     R6313 1
 '@T6G_MB_LIB.T6G(SCH_1):PAGE155_I138@PURE_QUANTA.Q_RES(CHIPS)':
 'A': CDS_PINID='A';
NODE_NAME     R6315 2
 '@T6G_MB_LIB.T6G(SCH_1):PAGE155_I140@PURE_QUANTA.Q_RES(CHIPS)':
 'B': CDS_PINID='B';
NET_NAME
'USB_HUB2_TI_OVERCUR2_MRP_PROG_FUNC5'
 '@T6G_MB_LIB.T6G(SCH_1):USB_HUB2_TI_OVERCUR2_MRP_PROG_FUNC5':
 C_SIGNAL='@t6g_mb_lib.t6g(sch_1):usb_hub2_ti_overcur2_mrp_prog_func5';
NODE_NAME     U6002 47
 '@T6G_MB_LIB.T6G(SCH_1):PAGE155_I101@PURE_QUANTA.TUSB8042AIRGCR(CHIPS)':
 'OVERCUR2Z': CDS_PINID='OVERCUR2Z';
NODE_NAME     R6314 2
 '@T6G_MB_LIB.T6G(SCH_1):PAGE155_I137@PURE_QUANTA.Q_RES(CHIPS)':
 'B': CDS_PINID='B';
NODE_NAME     R6313 2
 '@T6G_MB_LIB.T6G(SCH_1):PAGE155_I138@PURE_QUANTA.Q_RES(CHIPS)':
 'B': CDS_PINID='B';
NET_NAME
'USB_HUB2_TI_OVERCUR3'
 '@T6G_MB_LIB.T6G(SCH_1):USB_HUB2_TI_OVERCUR3':
 C_SIGNAL='@t6g_mb_lib.t6g(sch_1):usb_hub2_ti_overcur3';
NODE_NAME     R6301 2
 '@T6G_MB_LIB.T6G(SCH_1):PAGE155_I179@PURE_QUANTA.Q_RES(CHIPS)':
 'B': CDS_PINID='B';
NODE_NAME     R6299 1
 '@T6G_MB_LIB.T6G(SCH_1):PAGE155_I180@PURE_QUANTA.Q_RES(CHIPS)':
 'A': CDS_PINID='A';
NET_NAME
'USB_HUB2_TI_OVERCUR3_MRP_CFG_BC_EN'
 '@T6G_MB_LIB.T6G(SCH_1):USB_HUB2_TI_OVERCUR3_MRP_CFG_BC_EN':
 C_SIGNAL='@t6g_mb_lib.t6g(sch_1):usb_hub2_ti_overcur3_mrp_cfg_bc_en';
NODE_NAME     U6002 44
 '@T6G_MB_LIB.T6G(SCH_1):PAGE155_I101@PURE_QUANTA.TUSB8042AIRGCR(CHIPS)':
 'OVERCUR3Z': CDS_PINID='OVERCUR3Z';
NODE_NAME     R6299 2
 '@T6G_MB_LIB.T6G(SCH_1):PAGE155_I180@PURE_QUANTA.Q_RES(CHIPS)':
 'B': CDS_PINID='B';
NODE_NAME     R6300 2
 '@T6G_MB_LIB.T6G(SCH_1):PAGE155_I181@PURE_QUANTA.Q_RES(CHIPS)':
 'B': CDS_PINID='B';
NET_NAME
'USB_HUB2_TI_OVERCUR4_MRP_I2C_SLV_CFG1'
 '@T6G_MB_LIB.T6G(SCH_1):USB_HUB2_TI_OVERCUR4_MRP_I2C_SLV_CFG1':
 C_SIGNAL='@t6g_mb_lib.t6g(sch_1):usb_hub2_ti_overcur4_mrp_i2c_slv_cfg1';
NODE_NAME     U6002 43
 '@T6G_MB_LIB.T6G(SCH_1):PAGE155_I101@PURE_QUANTA.TUSB8042AIRGCR(CHIPS)':
 'OVERCUR4Z': CDS_PINID='OVERCUR4Z';
NODE_NAME     R6295 2
 '@T6G_MB_LIB.T6G(SCH_1):PAGE155_I182@PURE_QUANTA.Q_RES(CHIPS)':
 'B': CDS_PINID='B';
NODE_NAME     R6296 2
 '@T6G_MB_LIB.T6G(SCH_1):PAGE155_I183@PURE_QUANTA.Q_RES(CHIPS)':
 'B': CDS_PINID='B';
NET_NAME
'USB_HUB2_TI_PWRCTL2_MRP_VDD12'
 '@T6G_MB_LIB.T6G(SCH_1):USB_HUB2_TI_PWRCTL2_MRP_VDD12':
 C_SIGNAL='@t6g_mb_lib.t6g(sch_1):usb_hub2_ti_pwrctl2_mrp_vdd12';
NODE_NAME     U6002 35
 '@T6G_MB_LIB.T6G(SCH_1):PAGE155_I101@PURE_QUANTA.TUSB8042AIRGCR(CHIPS)':
 'PWRCTL2||BATEN2': CDS_PINID='\pwrctl2||baten2\';
NODE_NAME     R6258 2
 '@T6G_MB_LIB.T6G(SCH_1):PAGE155_I164@PURE_QUANTA.Q_RES(CHIPS)':
 'B': CDS_PINID='B';
NODE_NAME     R6259 2
 '@T6G_MB_LIB.T6G(SCH_1):PAGE155_I166@PURE_QUANTA.Q_RES(CHIPS)':
 'B': CDS_PINID='B';
NET_NAME
'USB_HUB2_TI_PWRCTL3_MRP_VDD33'
 '@T6G_MB_LIB.T6G(SCH_1):USB_HUB2_TI_PWRCTL3_MRP_VDD33':
 C_SIGNAL='@t6g_mb_lib.t6g(sch_1):usb_hub2_ti_pwrctl3_mrp_vdd33';
NODE_NAME     U6002 33
 '@T6G_MB_LIB.T6G(SCH_1):PAGE155_I101@PURE_QUANTA.TUSB8042AIRGCR(CHIPS)':
 'PWRCTL3||BATEN3': CDS_PINID='\pwrctl3||baten3\';
NODE_NAME     R6270 2
 '@T6G_MB_LIB.T6G(SCH_1):PAGE155_I143@PURE_QUANTA.Q_RES(CHIPS)':
 'B': CDS_PINID='B';
NET_NAME
'USB_HUB2_TI_PWRCTL_POL'
 '@T6G_MB_LIB.T6G(SCH_1):USB_HUB2_TI_PWRCTL_POL':
 C_SIGNAL='@t6g_mb_lib.t6g(sch_1):usb_hub2_ti_pwrctl_pol';
NODE_NAME     R6285 1
 '@T6G_MB_LIB.T6G(SCH_1):PAGE155_I192@PURE_QUANTA.Q_RES(CHIPS)':
 'A': CDS_PINID='A';
NODE_NAME     R6287 2
 '@T6G_MB_LIB.T6G(SCH_1):PAGE155_I197@PURE_QUANTA.Q_RES(CHIPS)':
 'B': CDS_PINID='B';
NODE_NAME     R6288 1
 '@T6G_MB_LIB.T6G(SCH_1):PAGE155_I198@PURE_QUANTA.Q_RES(CHIPS)':
 'A': CDS_PINID='A';
NET_NAME
'USB_HUB2_TI_PWRCTL_POL_MRP_VBUS_DET'
 '@T6G_MB_LIB.T6G(SCH_1):USB_HUB2_TI_PWRCTL_POL_MRP_VBUS_DET':
 C_SIGNAL='@t6g_mb_lib.t6g(sch_1):usb_hub2_ti_pwrctl_pol_mrp_vbus_det';
NODE_NAME     U6002 41
 '@T6G_MB_LIB.T6G(SCH_1):PAGE155_I101@PURE_QUANTA.TUSB8042AIRGCR(CHIPS)':
 'PWRCTL_POL': CDS_PINID='PWRCTL_POL';
NODE_NAME     R6285 2
 '@T6G_MB_LIB.T6G(SCH_1):PAGE155_I192@PURE_QUANTA.Q_RES(CHIPS)':
 'B': CDS_PINID='B';
NODE_NAME     R6286 2
 '@T6G_MB_LIB.T6G(SCH_1):PAGE155_I193@PURE_QUANTA.Q_RES(CHIPS)':
 'B': CDS_PINID='B';
NET_NAME
'USB_HUB2_TI_SMBUSZ_MRP_PROG_FUNC2'
 '@T6G_MB_LIB.T6G(SCH_1):USB_HUB2_TI_SMBUSZ_MRP_PROG_FUNC2':
 C_SIGNAL='@t6g_mb_lib.t6g(sch_1):usb_hub2_ti_smbusz_mrp_prog_func2';
NODE_NAME     U6002 39
 '@T6G_MB_LIB.T6G(SCH_1):PAGE157_I119@PURE_QUANTA.TUSB8042AIRGCR(CHIPS)':
 'SMBUSZ||SS_SUSPEND': CDS_PINID='\smbusz||ss_suspend\';
NODE_NAME     R6282 2
 '@T6G_MB_LIB.T6G(SCH_1):PAGE157_I138@PURE_QUANTA.Q_RES(CHIPS)':
 'B': CDS_PINID='B';
NODE_NAME     R6281 1
 '@T6G_MB_LIB.T6G(SCH_1):PAGE157_I139@PURE_QUANTA.Q_RES(CHIPS)':
 'A': CDS_PINID='A';
NET_NAME
'USB_HUB2_TI_TEST'
 '@T6G_MB_LIB.T6G(SCH_1):USB_HUB2_TI_TEST':
 C_SIGNAL='@t6g_mb_lib.t6g(sch_1):usb_hub2_ti_test';
NODE_NAME     R6323 1
 '@T6G_MB_LIB.T6G(SCH_1):PAGE155_I115@PURE_QUANTA.Q_RES(CHIPS)':
 'A': CDS_PINID='A';
NODE_NAME     R6325 1
 '@T6G_MB_LIB.T6G(SCH_1):PAGE155_I116@PURE_QUANTA.Q_RES(CHIPS)':
 'A': CDS_PINID='A';
NET_NAME
'USB_HUB2_TI_TEST_MRP_PROG_FUNC6'
 '@T6G_MB_LIB.T6G(SCH_1):USB_HUB2_TI_TEST_MRP_PROG_FUNC6':
 C_SIGNAL='@t6g_mb_lib.t6g(sch_1):usb_hub2_ti_test_mrp_prog_func6';
NODE_NAME     U6002 49
 '@T6G_MB_LIB.T6G(SCH_1):PAGE155_I101@PURE_QUANTA.TUSB8042AIRGCR(CHIPS)':
 'TEST': CDS_PINID='TEST';
NODE_NAME     R6323 2
 '@T6G_MB_LIB.T6G(SCH_1):PAGE155_I115@PURE_QUANTA.Q_RES(CHIPS)':
 'B': CDS_PINID='B';
NODE_NAME     R6324 2
 '@T6G_MB_LIB.T6G(SCH_1):PAGE155_I118@PURE_QUANTA.Q_RES(CHIPS)':
 'B': CDS_PINID='B';
NET_NAME
'USB_HUB2_TI_USB_DM_DN3_MRP_VDD33'
 '@T6G_MB_LIB.T6G(SCH_1):USB_HUB2_TI_USB_DM_DN3_MRP_VDD33':
 C_SIGNAL='@t6g_mb_lib.t6g(sch_1):usb_hub2_ti_usb_dm_dn3_mrp_vdd33';
NODE_NAME     U6002 18
 '@T6G_MB_LIB.T6G(SCH_1):PAGE155_I101@PURE_QUANTA.TUSB8042AIRGCR(CHIPS)':
 'USB_DM_DN3': CDS_PINID='USB_DM_DN3';
NODE_NAME     R6264 1
 '@T6G_MB_LIB.T6G(SCH_1):PAGE155_I151@PURE_QUANTA.Q_RES(CHIPS)':
 'A': CDS_PINID='A';
NET_NAME
'USB_HUB2_TI_USB_DP_DN1_MRP_CFG_STRAP'
 '@T6G_MB_LIB.T6G(SCH_1):USB_HUB2_TI_USB_DP_DN1_MRP_CFG_STRAP':
 C_SIGNAL='@t6g_mb_lib.t6g(sch_1):usb_hub2_ti_usb_dp_dn1_mrp_cfg_strap';
NODE_NAME     U6002 1
 '@T6G_MB_LIB.T6G(SCH_1):PAGE155_I101@PURE_QUANTA.TUSB8042AIRGCR(CHIPS)':
 'USB_DP_DN1': CDS_PINID='USB_DP_DN1';
NODE_NAME     R6271 1
 '@T6G_MB_LIB.T6G(SCH_1):PAGE155_I102@PURE_QUANTA.Q_RES(CHIPS)':
 'A': CDS_PINID='A';
NET_NAME
'USB_HUB2_TI_USB_DP_DN3_MRP_VDD12'
 '@T6G_MB_LIB.T6G(SCH_1):USB_HUB2_TI_USB_DP_DN3_MRP_VDD12':
 C_SIGNAL='@t6g_mb_lib.t6g(sch_1):usb_hub2_ti_usb_dp_dn3_mrp_vdd12';
NODE_NAME     U6002 17
 '@T6G_MB_LIB.T6G(SCH_1):PAGE155_I101@PURE_QUANTA.TUSB8042AIRGCR(CHIPS)':
 'USB_DP_DN3': CDS_PINID='USB_DP_DN3';
NODE_NAME     R6263 1
 '@T6G_MB_LIB.T6G(SCH_1):PAGE155_I155@PURE_QUANTA.Q_RES(CHIPS)':
 'A': CDS_PINID='A';
NET_NAME
'USB_HUB2_TI_USB_R1_MRP_RBIAS'
 '@T6G_MB_LIB.T6G(SCH_1):USB_HUB2_TI_USB_R1_MRP_RBIAS':
 C_SIGNAL='@t6g_mb_lib.t6g(sch_1):usb_hub2_ti_usb_r1_mrp_rbias';
NODE_NAME     U6002 64
 '@T6G_MB_LIB.T6G(SCH_1):PAGE155_I101@PURE_QUANTA.TUSB8042AIRGCR(CHIPS)':
 'USB_R1': CDS_PINID='USB_R1';
NODE_NAME     R6331 1
 '@T6G_MB_LIB.T6G(SCH_1):PAGE155_I207@PURE_QUANTA.Q_RES(CHIPS)':
 'A': CDS_PINID='A';
NODE_NAME     R6332 1
 '@T6G_MB_LIB.T6G(SCH_1):PAGE155_I208@PURE_QUANTA.Q_RES(CHIPS)':
 'A': CDS_PINID='A';
NET_NAME
'USB_HUB2_TI_USB_SSRXM_DN3_MRP_VDD12'
 '@T6G_MB_LIB.T6G(SCH_1):USB_HUB2_TI_USB_SSRXM_DN3_MRP_VDD12':
 C_SIGNAL='@t6g_mb_lib.t6g(sch_1):usb_hub2_ti_usb_ssrxm_dn3_mrp_vdd12';
NODE_NAME     U6002 23
 '@T6G_MB_LIB.T6G(SCH_1):PAGE155_I101@PURE_QUANTA.TUSB8042AIRGCR(CHIPS)':
 'USB_SSRXM_DN3': CDS_PINID='USB_SSRXM_DN3';
NODE_NAME     R6266 1
 '@T6G_MB_LIB.T6G(SCH_1):PAGE155_I136@PURE_QUANTA.Q_RES(CHIPS)':
 'A': CDS_PINID='A';
NET_NAME
'USB_HUB2_TI_USB_SSRXM_DN4_MRP_VDD12'
 '@T6G_MB_LIB.T6G(SCH_1):USB_HUB2_TI_USB_SSRXM_DN4_MRP_VDD12':
 C_SIGNAL='@t6g_mb_lib.t6g(sch_1):usb_hub2_ti_usb_ssrxm_dn4_mrp_vdd12';
NODE_NAME     U6002 30
 '@T6G_MB_LIB.T6G(SCH_1):PAGE155_I101@PURE_QUANTA.TUSB8042AIRGCR(CHIPS)':
 'USB_SSRXM_DN4': CDS_PINID='USB_SSRXM_DN4';
NODE_NAME     R6268 1
 '@T6G_MB_LIB.T6G(SCH_1):PAGE155_I149@PURE_QUANTA.Q_RES(CHIPS)':
 'A': CDS_PINID='A';
NET_NAME
'USB_HUB2_TI_USB_SSRXP_DN1_MRP_VDD12'
 '@T6G_MB_LIB.T6G(SCH_1):USB_HUB2_TI_USB_SSRXP_DN1_MRP_VDD12':
 C_SIGNAL='@t6g_mb_lib.t6g(sch_1):usb_hub2_ti_usb_ssrxp_dn1_mrp_vdd12';
NODE_NAME     U6002 6
 '@T6G_MB_LIB.T6G(SCH_1):PAGE155_I101@PURE_QUANTA.TUSB8042AIRGCR(CHIPS)':
 'USB_SSRXP_DN1': CDS_PINID='USB_SSRXP_DN1';
NODE_NAME     R6261 1
 '@T6G_MB_LIB.T6G(SCH_1):PAGE155_I134@PURE_QUANTA.Q_RES(CHIPS)':
 'A': CDS_PINID='A';
NET_NAME
'USB_HUB2_TI_USB_VBUS'
 '@T6G_MB_LIB.T6G(SCH_1):USB_HUB2_TI_USB_VBUS':
 C_SIGNAL='@t6g_mb_lib.t6g(sch_1):usb_hub2_ti_usb_vbus';
NODE_NAME     R6316 1
 '@T6G_MB_LIB.T6G(SCH_1):PAGE155_I119@PURE_QUANTA.Q_RES(CHIPS)':
 'A': CDS_PINID='A';
NODE_NAME     R6319 1
 '@T6G_MB_LIB.T6G(SCH_1):PAGE155_I121@PURE_QUANTA.Q_RES(CHIPS)':
 'A': CDS_PINID='A';
NODE_NAME     R6318 2
 '@T6G_MB_LIB.T6G(SCH_1):PAGE155_I123@PURE_QUANTA.Q_RES(CHIPS)':
 'B': CDS_PINID='B';
NET_NAME
'USB_HUB2_TI_USB_VBUS_MRP_RESET_N'
 '@T6G_MB_LIB.T6G(SCH_1):USB_HUB2_TI_USB_VBUS_MRP_RESET_N':
 C_SIGNAL='@t6g_mb_lib.t6g(sch_1):usb_hub2_ti_usb_vbus_mrp_reset_n';
NODE_NAME     U6002 48
 '@T6G_MB_LIB.T6G(SCH_1):PAGE155_I101@PURE_QUANTA.TUSB8042AIRGCR(CHIPS)':
 'USB_VBUS': CDS_PINID='USB_VBUS';
NODE_NAME     R6316 2
 '@T6G_MB_LIB.T6G(SCH_1):PAGE155_I119@PURE_QUANTA.Q_RES(CHIPS)':
 'B': CDS_PINID='B';
NODE_NAME     R6317 2
 '@T6G_MB_LIB.T6G(SCH_1):PAGE155_I124@PURE_QUANTA.Q_RES(CHIPS)':
 'B': CDS_PINID='B';
NET_NAME
'USB_HUB2_TI_VDD33_MRP_PROG_FUNC7'
 '@T6G_MB_LIB.T6G(SCH_1):USB_HUB2_TI_VDD33_MRP_PROG_FUNC7':
 C_SIGNAL='@t6g_mb_lib.t6g(sch_1):usb_hub2_ti_vdd33_mrp_prog_func7';
NODE_NAME     U6002 16
 '@T6G_MB_LIB.T6G(SCH_1):PAGE157_I119@PURE_QUANTA.TUSB8042AIRGCR(CHIPS)':
 'VDD33_16': CDS_PINID='VDD33_16';
NODE_NAME     R6274 1
 '@T6G_MB_LIB.T6G(SCH_1):PAGE157_I142@PURE_QUANTA.Q_RES(CHIPS)':
 'A': CDS_PINID='A';
NET_NAME
'USB_HUB2_TI_VDD33_MRP_PRT_CTL4_GANGPWR'
 '@T6G_MB_LIB.T6G(SCH_1):USB_HUB2_TI_VDD33_MRP_PRT_CTL4_GANGPWR':
 C_SIGNAL='@t6g_mb_lib.t6g(sch_1):usb_hub2_ti_vdd33_mrp_prt_ctl4_gangpwr';
NODE_NAME     U6002 34
 '@T6G_MB_LIB.T6G(SCH_1):PAGE157_I119@PURE_QUANTA.TUSB8042AIRGCR(CHIPS)':
 'VDD33_34': CDS_PINID='VDD33_34';
NODE_NAME     R6276 1
 '@T6G_MB_LIB.T6G(SCH_1):PAGE157_I125@PURE_QUANTA.Q_RES(CHIPS)':
 'A': CDS_PINID='A';
NODE_NAME     R6275 1
 '@T6G_MB_LIB.T6G(SCH_1):PAGE157_I131@PURE_QUANTA.Q_RES(CHIPS)':
 'A': CDS_PINID='A';
NET_NAME
'USB_HUB2_TI_VDD_MRP_USB3DN_RXDM1'
 '@T6G_MB_LIB.T6G(SCH_1):USB_HUB2_TI_VDD_MRP_USB3DN_RXDM1':
 C_SIGNAL='@t6g_mb_lib.t6g(sch_1):usb_hub2_ti_vdd_mrp_usb3dn_rxdm1';
NODE_NAME     U6002 8
 '@T6G_MB_LIB.T6G(SCH_1):PAGE157_I119@PURE_QUANTA.TUSB8042AIRGCR(CHIPS)':
 'VDD_8': CDS_PINID='VDD_8';
NODE_NAME     R6262 1
 '@T6G_MB_LIB.T6G(SCH_1):PAGE157_I134@PURE_QUANTA.Q_RES(CHIPS)':
 'A': CDS_PINID='A';
NET_NAME
'USB_HUB2_TI_VDD_MRP_USB3DN_RXDP4'
 '@T6G_MB_LIB.T6G(SCH_1):USB_HUB2_TI_VDD_MRP_USB3DN_RXDP4':
 C_SIGNAL='@t6g_mb_lib.t6g(sch_1):usb_hub2_ti_vdd_mrp_usb3dn_rxdp4';
NODE_NAME     U6002 31
 '@T6G_MB_LIB.T6G(SCH_1):PAGE157_I119@PURE_QUANTA.TUSB8042AIRGCR(CHIPS)':
 'VDD_31': CDS_PINID='VDD_31';
NODE_NAME     R6269 1
 '@T6G_MB_LIB.T6G(SCH_1):PAGE157_I136@PURE_QUANTA.Q_RES(CHIPS)':
 'A': CDS_PINID='A';
NET_NAME
'USB_HUB2_TI_VDD_MRP_USB3DN_TXDM1'
 '@T6G_MB_LIB.T6G(SCH_1):USB_HUB2_TI_VDD_MRP_USB3DN_TXDM1':
 C_SIGNAL='@t6g_mb_lib.t6g(sch_1):usb_hub2_ti_vdd_mrp_usb3dn_txdm1';
NODE_NAME     U6002 5
 '@T6G_MB_LIB.T6G(SCH_1):PAGE157_I119@PURE_QUANTA.TUSB8042AIRGCR(CHIPS)':
 'VDD_5': CDS_PINID='VDD_5';
NODE_NAME     R6260 1
 '@T6G_MB_LIB.T6G(SCH_1):PAGE157_I170@PURE_QUANTA.Q_RES(CHIPS)':
 'A': CDS_PINID='A';
NET_NAME
'USB_HUB2_TI_VDD_MRP_USB3DN_TXDP3'
 '@T6G_MB_LIB.T6G(SCH_1):USB_HUB2_TI_VDD_MRP_USB3DN_TXDP3':
 C_SIGNAL='@t6g_mb_lib.t6g(sch_1):usb_hub2_ti_vdd_mrp_usb3dn_txdp3';
NODE_NAME     U6002 21
 '@T6G_MB_LIB.T6G(SCH_1):PAGE157_I119@PURE_QUANTA.TUSB8042AIRGCR(CHIPS)':
 'VDD_21': CDS_PINID='VDD_21';
NODE_NAME     R6265 1
 '@T6G_MB_LIB.T6G(SCH_1):PAGE157_I145@PURE_QUANTA.Q_RES(CHIPS)':
 'A': CDS_PINID='A';
NET_NAME
'USB_HUB2_TI_VDD_MRP_USB3DN_TXDP4'
 '@T6G_MB_LIB.T6G(SCH_1):USB_HUB2_TI_VDD_MRP_USB3DN_TXDP4':
 C_SIGNAL='@t6g_mb_lib.t6g(sch_1):usb_hub2_ti_vdd_mrp_usb3dn_txdp4';
NODE_NAME     U6002 28
 '@T6G_MB_LIB.T6G(SCH_1):PAGE157_I119@PURE_QUANTA.TUSB8042AIRGCR(CHIPS)':
 'VDD_28': CDS_PINID='VDD_28';
NODE_NAME     R6267 1
 '@T6G_MB_LIB.T6G(SCH_1):PAGE157_I122@PURE_QUANTA.Q_RES(CHIPS)':
 'A': CDS_PINID='A';
NET_NAME
'USB_HUB_DVDD'
 '@T6G_MB_LIB.T6G(SCH_1):USB_HUB_DVDD':
 C_SIGNAL='@t6g_mb_lib.t6g(sch_1):usb_hub_dvdd';
NODE_NAME     U268 21
 '@T6G_MB_LIB.T6G(SCH_1):PAGE358_I100@PURE_QUANTA.GL852GOHY60(CHIPS)':
 'DVDD': CDS_PINID='DVDD';
NODE_NAME     R3662 2
 '@T6G_MB_LIB.T6G(SCH_1):PAGE358_I167@PURE_QUANTA.Q_RES(CHIPS)':
 'B': CDS_PINID='B';
NET_NAME
'USB_HUB_OVCUR1'
 '@T6G_MB_LIB.T6G(SCH_1):USB_HUB_OVCUR1':
 C_SIGNAL='@t6g_mb_lib.t6g(sch_1):usb_hub_ovcur1';
NODE_NAME     U268 25
 '@T6G_MB_LIB.T6G(SCH_1):PAGE358_I100@PURE_QUANTA.GL852GOHY60(CHIPS)':
 'OVCUR1#||SMC': CDS_PINID='\ovcur1#||smc\';
NODE_NAME     R3656 2
 '@T6G_MB_LIB.T6G(SCH_1):PAGE358_I194@PURE_QUANTA.Q_RES(CHIPS)':
 'B': CDS_PINID='B';
NET_NAME
'USB_HUB_OVCUR2'
 '@T6G_MB_LIB.T6G(SCH_1):USB_HUB_OVCUR2':
 C_SIGNAL='@t6g_mb_lib.t6g(sch_1):usb_hub_ovcur2';
NODE_NAME     U268 24
 '@T6G_MB_LIB.T6G(SCH_1):PAGE358_I100@PURE_QUANTA.GL852GOHY60(CHIPS)':
 'OVCUR2#||SMD': CDS_PINID='\ovcur2#||smd\';
NODE_NAME     R3657 2
 '@T6G_MB_LIB.T6G(SCH_1):PAGE358_I195@PURE_QUANTA.Q_RES(CHIPS)':
 'B': CDS_PINID='B';
NET_NAME
'USB_HUB_OVCUR3'
 '@T6G_MB_LIB.T6G(SCH_1):USB_HUB_OVCUR3':
 C_SIGNAL='@t6g_mb_lib.t6g(sch_1):usb_hub_ovcur3';
NODE_NAME     U268 20
 '@T6G_MB_LIB.T6G(SCH_1):PAGE358_I100@PURE_QUANTA.GL852GOHY60(CHIPS)':
 'OVCUR3#': CDS_PINID='\ovcur3#\';
NODE_NAME     R3658 2
 '@T6G_MB_LIB.T6G(SCH_1):PAGE358_I196@PURE_QUANTA.Q_RES(CHIPS)':
 'B': CDS_PINID='B';
NET_NAME
'USB_HUB_OVCUR4'
 '@T6G_MB_LIB.T6G(SCH_1):USB_HUB_OVCUR4':
 C_SIGNAL='@t6g_mb_lib.t6g(sch_1):usb_hub_ovcur4';
NODE_NAME     U268 19
 '@T6G_MB_LIB.T6G(SCH_1):PAGE358_I100@PURE_QUANTA.GL852GOHY60(CHIPS)':
 'OVCUR4#': CDS_PINID='\ovcur4#\';
NODE_NAME     R3659 2
 '@T6G_MB_LIB.T6G(SCH_1):PAGE358_I198@PURE_QUANTA.Q_RES(CHIPS)':
 'B': CDS_PINID='B';
NET_NAME
'USB_HUB_PGANG'
 '@T6G_MB_LIB.T6G(SCH_1):USB_HUB_PGANG':
 C_SIGNAL='@t6g_mb_lib.t6g(sch_1):usb_hub_pgang';
NODE_NAME     U268 23
 '@T6G_MB_LIB.T6G(SCH_1):PAGE358_I100@PURE_QUANTA.GL852GOHY60(CHIPS)':
 'PGANG': CDS_PINID='PGANG';
NODE_NAME     R3665 1
 '@T6G_MB_LIB.T6G(SCH_1):PAGE358_I182@PURE_QUANTA.Q_RES(CHIPS)':
 'A': CDS_PINID='A';
NET_NAME
'USB_HUB_PSELF'
 '@T6G_MB_LIB.T6G(SCH_1):USB_HUB_PSELF':
 C_SIGNAL='@t6g_mb_lib.t6g(sch_1):usb_hub_pself';
NODE_NAME     U268 22
 '@T6G_MB_LIB.T6G(SCH_1):PAGE358_I100@PURE_QUANTA.GL852GOHY60(CHIPS)':
 'PSELF': CDS_PINID='PSELF';
NODE_NAME     R3663 2
 '@T6G_MB_LIB.T6G(SCH_1):PAGE358_I186@PURE_QUANTA.Q_RES(CHIPS)':
 'B': CDS_PINID='B';
NODE_NAME     R3664 1
 '@T6G_MB_LIB.T6G(SCH_1):PAGE358_I187@PURE_QUANTA.Q_RES(CHIPS)':
 'A': CDS_PINID='A';
NET_NAME
'USB_HUB_RREF'
 '@T6G_MB_LIB.T6G(SCH_1):USB_HUB_RREF':
 C_SIGNAL='@t6g_mb_lib.t6g(sch_1):usb_hub_rref';
NODE_NAME     U268 8
 '@T6G_MB_LIB.T6G(SCH_1):PAGE358_I100@PURE_QUANTA.GL852GOHY60(CHIPS)':
 'RREF': CDS_PINID='RREF';
NODE_NAME     R3653 1
 '@T6G_MB_LIB.T6G(SCH_1):PAGE358_I139@PURE_QUANTA.Q_RES(CHIPS)':
 'A': CDS_PINID='A';
NET_NAME
'USB_HUB_TEST'
 '@T6G_MB_LIB.T6G(SCH_1):USB_HUB_TEST':
 C_SIGNAL='@t6g_mb_lib.t6g(sch_1):usb_hub_test';
NODE_NAME     U268 18
 '@T6G_MB_LIB.T6G(SCH_1):PAGE358_I100@PURE_QUANTA.GL852GOHY60(CHIPS)':
 'TEST||SCL': CDS_PINID='\test||scl\';
NODE_NAME     R3666 1
 '@T6G_MB_LIB.T6G(SCH_1):PAGE358_I199@PURE_QUANTA.Q_RES(CHIPS)':
 'A': CDS_PINID='A';
NET_NAME
'USB_HUB_XTAL_IN'
 '@T6G_MB_LIB.T6G(SCH_1):USB_HUB_XTAL_IN':
 C_SIGNAL='@t6g_mb_lib.t6g(sch_1):usb_hub_xtal_in';
NODE_NAME     U268 10
 '@T6G_MB_LIB.T6G(SCH_1):PAGE358_I100@PURE_QUANTA.GL852GOHY60(CHIPS)':
 'X1': CDS_PINID='X1';
NODE_NAME     Y8004 1
 '@T6G_MB_LIB.T6G(SCH_1):PAGE358_I210@PURE_QUANTA.Q_XTAL_4P_13BI_24GND(CHIPS)':
 'X1': CDS_PINID='X1';
NODE_NAME     C2029 1
 '@T6G_MB_LIB.T6G(SCH_1):PAGE358_I212@PURE_QUANTA.Q_CAP(CHIPS)':
 'A': CDS_PINID='A';
NET_NAME
'USB_HUB_XTAL_OUT'
 '@T6G_MB_LIB.T6G(SCH_1):USB_HUB_XTAL_OUT':
 C_SIGNAL='@t6g_mb_lib.t6g(sch_1):usb_hub_xtal_out';
NODE_NAME     U268 11
 '@T6G_MB_LIB.T6G(SCH_1):PAGE358_I100@PURE_QUANTA.GL852GOHY60(CHIPS)':
 'X2': CDS_PINID='X2';
NODE_NAME     Y8004 3
 '@T6G_MB_LIB.T6G(SCH_1):PAGE358_I210@PURE_QUANTA.Q_XTAL_4P_13BI_24GND(CHIPS)':
 'X2': CDS_PINID='X2';
NODE_NAME     C2030 1
 '@T6G_MB_LIB.T6G(SCH_1):PAGE358_I211@PURE_QUANTA.Q_CAP(CHIPS)':
 'A': CDS_PINID='A';
NET_NAME
'UV_ADR_P2V5_COMP'
 '@T6G_MB_LIB.T6G(SCH_1):UV_ADR_P2V5_COMP':
 C_SIGNAL='@t6g_mb_lib.t6g(sch_1):uv_adr_p2v5_comp';
NODE_NAME     U8007 1
 '@T6G_MB_LIB.T6G(SCH_1):PAGE372_I51@PURE_QUANTA.LM4040AIM3X25NOPB(CHIPS)':
 '1+': CDS_PINID='\1+\';
NODE_NAME     R8113 2
 '@T6G_MB_LIB.T6G(SCH_1):PAGE372_I52@PURE_QUANTA.Q_RES(CHIPS)':
 'B': CDS_PINID='B';
NODE_NAME     C8017 1
 '@T6G_MB_LIB.T6G(SCH_1):PAGE372_I59@PURE_QUANTA.Q_CAP(CHIPS)':
 'A': CDS_PINID='A';
NODE_NAME     U8008 1
 '@T6G_MB_LIB.T6G(SCH_1):PAGE372_I71@PURE_QUANTA.AP331AWG7(CHIPS)':
 'IN-': CDS_PINID='\in-\';
NET_NAME
'UV_ALERT_N'
 '@T6G_MB_LIB.T6G(SCH_1):UV_ALERT_N':
 C_SIGNAL='@t6g_mb_lib.t6g(sch_1):uv_alert_n';
NODE_NAME     R6038 1
 '@T6G_MB_LIB.T6G(SCH_1):PAGE79_I21@PURE_QUANTA.Q_RES(CHIPS)':
 'A': CDS_PINID='A';
NODE_NAME     U18 B10
 '@T6G_MB_LIB.T6G(SCH_1):PAGE79_I94@PURE_QUANTA.LCMXO3LF9400C5BG484C(CHIPS)':
 'PT23A||PCLKT0_1': CDS_PINID='\pt23a||pclkt0_1\';
NET_NAME
'UV_P2V5_COMP'
 '@T6G_MB_LIB.T6G(SCH_1):UV_P2V5_COMP':
 C_SIGNAL='@t6g_mb_lib.t6g(sch_1):uv_p2v5_comp';
NODE_NAME     R8120 2
 '@T6G_MB_LIB.T6G(SCH_1):PAGE372_I72@PURE_QUANTA.Q_RES(CHIPS)':
 'B': CDS_PINID='B';
NODE_NAME     C8020 1
 '@T6G_MB_LIB.T6G(SCH_1):PAGE372_I79@PURE_QUANTA.Q_CAP(CHIPS)':
 'A': CDS_PINID='A';
NODE_NAME     U8010 1
 '@T6G_MB_LIB.T6G(SCH_1):PAGE372_I80@PURE_QUANTA.AP331AWG7(CHIPS)':
 'IN-': CDS_PINID='\in-\';
NODE_NAME     U8009 1
 '@T6G_MB_LIB.T6G(SCH_1):PAGE372_I93@PURE_QUANTA.LM4040AIM3X25NOPB(CHIPS)':
 '1+': CDS_PINID='\1+\';
NET_NAME
'VFG3P3_CLK_GEN'
 '@T6G_MB_LIB.T6G(SCH_1):VFG3P3_CLK_GEN':
 C_SIGNAL='@t6g_mb_lib.t6g(sch_1):vfg3p3_clk_gen',
 CDS_GLOBAL_NET='TRUE';
NODE_NAME     L17 2
 '@T6G_MB_LIB.T6G(SCH_1):PAGE232_I33@PURE_QUANTA.Q_INDUCTOR(CHIPS)':
 '2': CDS_PINID='\2\';
NODE_NAME     C1883 1
 '@T6G_MB_LIB.T6G(SCH_1):PAGE232_I36@PURE_QUANTA.Q_CAP(CHIPS)':
 'A': CDS_PINID='A';
NODE_NAME     C2257 1
 '@T6G_MB_LIB.T6G(SCH_1):PAGE232_I37@PURE_QUANTA.Q_CAP(CHIPS)':
 'A': CDS_PINID='A';
NODE_NAME     C1886 1
 '@T6G_MB_LIB.T6G(SCH_1):PAGE232_I40@PURE_QUANTA.Q_CAP(CHIPS)':
 'A': CDS_PINID='A';
NODE_NAME     C1889 1
 '@T6G_MB_LIB.T6G(SCH_1):PAGE232_I41@PURE_QUANTA.Q_CAP(CHIPS)':
 'A': CDS_PINID='A';
NODE_NAME     C95 1
 '@T6G_MB_LIB.T6G(SCH_1):PAGE232_I42@PURE_QUANTA.Q_CAP(CHIPS)':
 'A': CDS_PINID='A';
NODE_NAME     R4077 1
 '@T6G_MB_LIB.T6G(SCH_1):PAGE232_I43@PURE_QUANTA.Q_RES(CHIPS)':
 'A': CDS_PINID='A';
NODE_NAME     U247 11
 '@T6G_MB_LIB.T6G(SCH_1):PAGE232_I77@PURE_QUANTA.9FGL0251DKILFT(CHIPS)':
 'VDD3.3_11': CDS_PINID='\vdd3.3_11\';
NODE_NAME     U247 20
 '@T6G_MB_LIB.T6G(SCH_1):PAGE232_I77@PURE_QUANTA.9FGL0251DKILFT(CHIPS)':
 'VDD3.3_20': CDS_PINID='\vdd3.3_20\';
NODE_NAME     U247 7
 '@T6G_MB_LIB.T6G(SCH_1):PAGE232_I77@PURE_QUANTA.9FGL0251DKILFT(CHIPS)':
 'VDDDIG3.3': CDS_PINID='\vdddig3.3\';
NODE_NAME     U247 3
 '@T6G_MB_LIB.T6G(SCH_1):PAGE232_I77@PURE_QUANTA.9FGL0251DKILFT(CHIPS)':
 'VDDXTAL3.3': CDS_PINID='\vddxtal3.3\';
NET_NAME
'VFG_3P3A_CLK_GEN'
 '@T6G_MB_LIB.T6G(SCH_1):VFG_3P3A_CLK_GEN':
 C_SIGNAL='@t6g_mb_lib.t6g(sch_1):vfg_3p3a_clk_gen',
 CDS_GLOBAL_NET='TRUE';
NODE_NAME     R4077 2
 '@T6G_MB_LIB.T6G(SCH_1):PAGE232_I43@PURE_QUANTA.Q_RES(CHIPS)':
 'B': CDS_PINID='B';
NODE_NAME     C1884 1
 '@T6G_MB_LIB.T6G(SCH_1):PAGE232_I68@PURE_QUANTA.Q_CAP(CHIPS)':
 'A': CDS_PINID='A';
NODE_NAME     C97 1
 '@T6G_MB_LIB.T6G(SCH_1):PAGE232_I69@PURE_QUANTA.Q_CAP(CHIPS)':
 'A': CDS_PINID='A';
NODE_NAME     U247 16
 '@T6G_MB_LIB.T6G(SCH_1):PAGE232_I77@PURE_QUANTA.9FGL0251DKILFT(CHIPS)':
 'VDDA3.3': CDS_PINID='\vdda3.3\';
NET_NAME
'VIRTUAL_RESEAT'
 '@T6G_MB_LIB.T6G(SCH_1):VIRTUAL_RESEAT':
 C_SIGNAL='@t6g_mb_lib.t6g(sch_1):virtual_reseat';
NODE_NAME     J41 OA14
 '@T6G_MB_LIB.T6G(SCH_1):PAGE348_I176@PURE_QUANTA.SCONN168_ME1016810202011(CHIPS)':
 'RBT_CLK_IN': CDS_PINID='RBT_CLK_IN';
NODE_NAME     U18 F16
 '@T6G_MB_LIB.T6G(SCH_1):PAGE79_I25@PURE_QUANTA.LCMXO3LF9400C5BG484C(CHIPS)':
 'PT44C||INITN': CDS_PINID='\pt44c||initn\';
NET_NAME
'VIRTUAL_RESEAT_FPGA_N'
 '@T6G_MB_LIB.T6G(SCH_1):VIRTUAL_RESEAT_FPGA_N':
 C_SIGNAL='@t6g_mb_lib.t6g(sch_1):virtual_reseat_fpga_n';
NODE_NAME     R3996 1
 '@T6G_MB_LIB.T6G(SCH_1):PAGE350_I17@PURE_QUANTA.Q_RES(CHIPS)':
 'A': CDS_PINID='A';
NODE_NAME     R6031 1
 '@T6G_MB_LIB.T6G(SCH_1):PAGE79_I55@PURE_QUANTA.Q_RES(CHIPS)':
 'A': CDS_PINID='A';
NET_NAME
'VIRTUAL_RESEAT_FPGA_R_N'
 '@T6G_MB_LIB.T6G(SCH_1):VIRTUAL_RESEAT_FPGA_R_N':
 C_SIGNAL='@t6g_mb_lib.t6g(sch_1):virtual_reseat_fpga_r_n';
NODE_NAME     U18 E17
 '@T6G_MB_LIB.T6G(SCH_1):PAGE79_I25@PURE_QUANTA.LCMXO3LF9400C5BG484C(CHIPS)':
 'PT44D||DONE': CDS_PINID='\pt44d||done\';
NODE_NAME     R6031 2
 '@T6G_MB_LIB.T6G(SCH_1):PAGE79_I55@PURE_QUANTA.Q_RES(CHIPS)':
 'B': CDS_PINID='B';
NET_NAME
'VR_P5V_EN'
 '@T6G_MB_LIB.T6G(SCH_1):VR_P5V_EN':
 C_SIGNAL='@t6g_mb_lib.t6g(sch_1):vr_p5v_en';
NODE_NAME     R333 2
 '@T6G_MB_LIB.T6G(SCH_1):PAGE273_I4@PURE_QUANTA.Q_RES(CHIPS)':
 'B': CDS_PINID='B';
NODE_NAME     Q37 2
 '@T6G_MB_LIB.T6G(SCH_1):PAGE273_I9@PURE_QUANTA.MOSFET_NCH_DUAL(CHIPS)':
 'G1': CDS_PINID='G1';
NODE_NAME     R334 1
 '@T6G_MB_LIB.T6G(SCH_1):PAGE273_I7@PURE_QUANTA.Q_RES(CHIPS)':
 'A': CDS_PINID='A';
NET_NAME
'VR_P5V_EN_D'
 '@T6G_MB_LIB.T6G(SCH_1):VR_P5V_EN_D':
 C_SIGNAL='@t6g_mb_lib.t6g(sch_1):vr_p5v_en_d';
NODE_NAME     R4638 2
 '@T6G_MB_LIB.T6G(SCH_1):PAGE273_I45@PURE_QUANTA.Q_RES(CHIPS)':
 'B': CDS_PINID='B';
NODE_NAME     U324 D
 '@T6G_MB_LIB.T6G(SCH_1):PAGE273_I62@PURE_QUANTA.MOSFET_NCH_GDS_ESD_PROTECTED(CHIPS)':
 'D': CDS_PINID='D';
NODE_NAME     R4639 2
 '@T6G_MB_LIB.T6G(SCH_1):PAGE273_I74@PURE_QUANTA.Q_RES(CHIPS)':
 'B': CDS_PINID='B';
NODE_NAME     R4640 2
 '@T6G_MB_LIB.T6G(SCH_1):PAGE273_I75@PURE_QUANTA.Q_RES(CHIPS)':
 'B': CDS_PINID='B';
NODE_NAME     R4641 2
 '@T6G_MB_LIB.T6G(SCH_1):PAGE273_I76@PURE_QUANTA.Q_RES(CHIPS)':
 'B': CDS_PINID='B';
NET_NAME
'VR_P5V_EN_D_R'
 '@T6G_MB_LIB.T6G(SCH_1):VR_P5V_EN_D_R':
 C_SIGNAL='@t6g_mb_lib.t6g(sch_1):vr_p5v_en_d_r';
NODE_NAME     R1654 1
 '@T6G_MB_LIB.T6G(SCH_1):PAGE273_I22@PURE_QUANTA.Q_RES(CHIPS)':
 'A': CDS_PINID='A';
NODE_NAME     R335 2
 '@T6G_MB_LIB.T6G(SCH_1):PAGE273_I15@PURE_QUANTA.Q_RES(CHIPS)':
 'B': CDS_PINID='B';
NODE_NAME     Q57 4
 '@T6G_MB_LIB.T6G(SCH_1):PAGE273_I23@PURE_QUANTA.MOSFET_NCH_1D3S(CHIPS)':
 '4': CDS_PINID='\4\';
NODE_NAME     C9226 1
 '@T6G_MB_LIB.T6G(SCH_1):PAGE273_I38@PURE_QUANTA.Q_CAP(CHIPS)':
 'A': CDS_PINID='A';
NET_NAME
'VR_P5V_EN_D_R1'
 '@T6G_MB_LIB.T6G(SCH_1):VR_P5V_EN_D_R1':
 C_SIGNAL='@t6g_mb_lib.t6g(sch_1):vr_p5v_en_d_r1';
NODE_NAME     Q37 3
 '@T6G_MB_LIB.T6G(SCH_1):PAGE273_I14@PURE_QUANTA.MOSFET_NCH_DUAL(CHIPS)':
 'D2': CDS_PINID='D2';
NODE_NAME     R1654 2
 '@T6G_MB_LIB.T6G(SCH_1):PAGE273_I22@PURE_QUANTA.Q_RES(CHIPS)':
 'B': CDS_PINID='B';
NET_NAME
'VR_P5V_EN_N'
 '@T6G_MB_LIB.T6G(SCH_1):VR_P5V_EN_N':
 C_SIGNAL='@t6g_mb_lib.t6g(sch_1):vr_p5v_en_n';
NODE_NAME     Q37 6
 '@T6G_MB_LIB.T6G(SCH_1):PAGE273_I9@PURE_QUANTA.MOSFET_NCH_DUAL(CHIPS)':
 'D1': CDS_PINID='D1';
NODE_NAME     R336 2
 '@T6G_MB_LIB.T6G(SCH_1):PAGE273_I10@PURE_QUANTA.Q_RES(CHIPS)':
 'B': CDS_PINID='B';
NODE_NAME     Q37 5
 '@T6G_MB_LIB.T6G(SCH_1):PAGE273_I14@PURE_QUANTA.MOSFET_NCH_DUAL(CHIPS)':
 'G2': CDS_PINID='G2';
NODE_NAME     U324 G
 '@T6G_MB_LIB.T6G(SCH_1):PAGE273_I62@PURE_QUANTA.MOSFET_NCH_GDS_ESD_PROTECTED(CHIPS)':
 'G': CDS_PINID='G';
NET_NAME
'VSENSE_P12V_INA230_3_INN'
 '@T6G_MB_LIB.T6G(SCH_1):VSENSE_P12V_INA230_3_INN':
 C_SIGNAL='@t6g_mb_lib.t6g(sch_1):vsense_p12v_ina230_3_inn';
NODE_NAME     U263 12
 '@T6G_MB_LIB.T6G(SCH_1):PAGE360_I94@PURE_QUANTA.ISL28022FRZT(CHIPS)':
 'VINM': CDS_PINID='VINM';
NODE_NAME     C2020 2
 '@T6G_MB_LIB.T6G(SCH_1):PAGE360_I108@PURE_QUANTA.Q_CAP(CHIPS)':
 'B': CDS_PINID='B';
NODE_NAME     R3571 2
 '@T6G_MB_LIB.T6G(SCH_1):PAGE360_I110@PURE_QUANTA.Q_RES(CHIPS)':
 'B': CDS_PINID='B';
NET_NAME
'VSENSE_P12V_INA230_3_INP'
 '@T6G_MB_LIB.T6G(SCH_1):VSENSE_P12V_INA230_3_INP':
 C_SIGNAL='@t6g_mb_lib.t6g(sch_1):vsense_p12v_ina230_3_inp';
NODE_NAME     U263 13
 '@T6G_MB_LIB.T6G(SCH_1):PAGE360_I94@PURE_QUANTA.ISL28022FRZT(CHIPS)':
 'VINP': CDS_PINID='VINP';
NODE_NAME     C2020 1
 '@T6G_MB_LIB.T6G(SCH_1):PAGE360_I108@PURE_QUANTA.Q_CAP(CHIPS)':
 'A': CDS_PINID='A';
NODE_NAME     R3570 2
 '@T6G_MB_LIB.T6G(SCH_1):PAGE360_I109@PURE_QUANTA.Q_RES(CHIPS)':
 'B': CDS_PINID='B';
NET_NAME
'VSENSE_P12V_INA230_4_INN'
 '@T6G_MB_LIB.T6G(SCH_1):VSENSE_P12V_INA230_4_INN':
 C_SIGNAL='@t6g_mb_lib.t6g(sch_1):vsense_p12v_ina230_4_inn';
NODE_NAME     R3575 2
 '@T6G_MB_LIB.T6G(SCH_1):PAGE360_I33@PURE_QUANTA.Q_RES(CHIPS)':
 'B': CDS_PINID='B';
NODE_NAME     U264 12
 '@T6G_MB_LIB.T6G(SCH_1):PAGE360_I46@PURE_QUANTA.ISL28022FRZT(CHIPS)':
 'VINM': CDS_PINID='VINM';
NODE_NAME     C2021 2
 '@T6G_MB_LIB.T6G(SCH_1):PAGE360_I71@PURE_QUANTA.Q_CAP(CHIPS)':
 'B': CDS_PINID='B';
NET_NAME
'VSENSE_P12V_INA230_4_INP'
 '@T6G_MB_LIB.T6G(SCH_1):VSENSE_P12V_INA230_4_INP':
 C_SIGNAL='@t6g_mb_lib.t6g(sch_1):vsense_p12v_ina230_4_inp';
NODE_NAME     R3574 2
 '@T6G_MB_LIB.T6G(SCH_1):PAGE360_I35@PURE_QUANTA.Q_RES(CHIPS)':
 'B': CDS_PINID='B';
NODE_NAME     U264 13
 '@T6G_MB_LIB.T6G(SCH_1):PAGE360_I46@PURE_QUANTA.ISL28022FRZT(CHIPS)':
 'VINP': CDS_PINID='VINP';
NODE_NAME     C2021 1
 '@T6G_MB_LIB.T6G(SCH_1):PAGE360_I71@PURE_QUANTA.Q_CAP(CHIPS)':
 'A': CDS_PINID='A';
NET_NAME
'VSENSE_P12V_INA230_5_INN'
 '@T6G_MB_LIB.T6G(SCH_1):VSENSE_P12V_INA230_5_INN':
 C_SIGNAL='@t6g_mb_lib.t6g(sch_1):vsense_p12v_ina230_5_inn';
NODE_NAME     R3579 2
 '@T6G_MB_LIB.T6G(SCH_1):PAGE360_I56@PURE_QUANTA.Q_RES(CHIPS)':
 'B': CDS_PINID='B';
NODE_NAME     U265 12
 '@T6G_MB_LIB.T6G(SCH_1):PAGE360_I69@PURE_QUANTA.ISL28022FRZT(CHIPS)':
 'VINM': CDS_PINID='VINM';
NODE_NAME     C2022 2
 '@T6G_MB_LIB.T6G(SCH_1):PAGE360_I72@PURE_QUANTA.Q_CAP(CHIPS)':
 'B': CDS_PINID='B';
NET_NAME
'VSENSE_P12V_INA230_5_INP'
 '@T6G_MB_LIB.T6G(SCH_1):VSENSE_P12V_INA230_5_INP':
 C_SIGNAL='@t6g_mb_lib.t6g(sch_1):vsense_p12v_ina230_5_inp';
NODE_NAME     R3578 2
 '@T6G_MB_LIB.T6G(SCH_1):PAGE360_I58@PURE_QUANTA.Q_RES(CHIPS)':
 'B': CDS_PINID='B';
NODE_NAME     U265 13
 '@T6G_MB_LIB.T6G(SCH_1):PAGE360_I69@PURE_QUANTA.ISL28022FRZT(CHIPS)':
 'VINP': CDS_PINID='VINP';
NODE_NAME     C2022 1
 '@T6G_MB_LIB.T6G(SCH_1):PAGE360_I72@PURE_QUANTA.Q_CAP(CHIPS)':
 'A': CDS_PINID='A';
NET_NAME
'VSENSE_P12V_INA230_6_INN'
 '@T6G_MB_LIB.T6G(SCH_1):VSENSE_P12V_INA230_6_INN':
 C_SIGNAL='@t6g_mb_lib.t6g(sch_1):vsense_p12v_ina230_6_inn';
NODE_NAME     R1301 2
 '@T6G_MB_LIB.T6G(SCH_1):PAGE466_I11@PURE_QUANTA.Q_RES(CHIPS)':
 'B': CDS_PINID='B';
NODE_NAME     C1111 2
 '@T6G_MB_LIB.T6G(SCH_1):PAGE466_I15@PURE_QUANTA.Q_CAP(CHIPS)':
 'B': CDS_PINID='B';
NODE_NAME     U55 12
 '@T6G_MB_LIB.T6G(SCH_1):PAGE466_I28@PURE_QUANTA.ISL28022FRZT(CHIPS)':
 'VINM': CDS_PINID='VINM';
NET_NAME
'VSENSE_P12V_INA230_6_INP'
 '@T6G_MB_LIB.T6G(SCH_1):VSENSE_P12V_INA230_6_INP':
 C_SIGNAL='@t6g_mb_lib.t6g(sch_1):vsense_p12v_ina230_6_inp';
NODE_NAME     R1284 2
 '@T6G_MB_LIB.T6G(SCH_1):PAGE466_I10@PURE_QUANTA.Q_RES(CHIPS)':
 'B': CDS_PINID='B';
NODE_NAME     C1111 1
 '@T6G_MB_LIB.T6G(SCH_1):PAGE466_I15@PURE_QUANTA.Q_CAP(CHIPS)':
 'A': CDS_PINID='A';
NODE_NAME     U55 13
 '@T6G_MB_LIB.T6G(SCH_1):PAGE466_I28@PURE_QUANTA.ISL28022FRZT(CHIPS)':
 'VINP': CDS_PINID='VINP';
NET_NAME
'VSENSE_P12V_INA230_7_INN'
 '@T6G_MB_LIB.T6G(SCH_1):VSENSE_P12V_INA230_7_INN':
 C_SIGNAL='@t6g_mb_lib.t6g(sch_1):vsense_p12v_ina230_7_inn';
NODE_NAME     U56 12
 '@T6G_MB_LIB.T6G(SCH_1):PAGE466_I29@PURE_QUANTA.ISL28022FRZT(CHIPS)':
 'VINM': CDS_PINID='VINM';
NODE_NAME     C1112 2
 '@T6G_MB_LIB.T6G(SCH_1):PAGE466_I54@PURE_QUANTA.Q_CAP(CHIPS)':
 'B': CDS_PINID='B';
NODE_NAME     R1302 2
 '@T6G_MB_LIB.T6G(SCH_1):PAGE466_I55@PURE_QUANTA.Q_RES(CHIPS)':
 'B': CDS_PINID='B';
NET_NAME
'VSENSE_P12V_INA230_7_INP'
 '@T6G_MB_LIB.T6G(SCH_1):VSENSE_P12V_INA230_7_INP':
 C_SIGNAL='@t6g_mb_lib.t6g(sch_1):vsense_p12v_ina230_7_inp';
NODE_NAME     U56 13
 '@T6G_MB_LIB.T6G(SCH_1):PAGE466_I29@PURE_QUANTA.ISL28022FRZT(CHIPS)':
 'VINP': CDS_PINID='VINP';
NODE_NAME     R1291 2
 '@T6G_MB_LIB.T6G(SCH_1):PAGE466_I43@PURE_QUANTA.Q_RES(CHIPS)':
 'B': CDS_PINID='B';
NODE_NAME     C1112 1
 '@T6G_MB_LIB.T6G(SCH_1):PAGE466_I54@PURE_QUANTA.Q_CAP(CHIPS)':
 'A': CDS_PINID='A';
NET_NAME
'VSENSE_P12V_INA230_8_INN'
 '@T6G_MB_LIB.T6G(SCH_1):VSENSE_P12V_INA230_8_INN':
 C_SIGNAL='@t6g_mb_lib.t6g(sch_1):vsense_p12v_ina230_8_inn';
NODE_NAME     U52 12
 '@T6G_MB_LIB.T6G(SCH_1):PAGE466_I57@PURE_QUANTA.ISL28022FRZT(CHIPS)':
 'VINM': CDS_PINID='VINM';
NODE_NAME     C1110 2
 '@T6G_MB_LIB.T6G(SCH_1):PAGE466_I68@PURE_QUANTA.Q_CAP(CHIPS)':
 'B': CDS_PINID='B';
NODE_NAME     R1292 2
 '@T6G_MB_LIB.T6G(SCH_1):PAGE466_I75@PURE_QUANTA.Q_RES(CHIPS)':
 'B': CDS_PINID='B';
NET_NAME
'VSENSE_P12V_INA230_8_INP'
 '@T6G_MB_LIB.T6G(SCH_1):VSENSE_P12V_INA230_8_INP':
 C_SIGNAL='@t6g_mb_lib.t6g(sch_1):vsense_p12v_ina230_8_inp';
NODE_NAME     U52 13
 '@T6G_MB_LIB.T6G(SCH_1):PAGE466_I57@PURE_QUANTA.ISL28022FRZT(CHIPS)':
 'VINP': CDS_PINID='VINP';
NODE_NAME     C1110 1
 '@T6G_MB_LIB.T6G(SCH_1):PAGE466_I68@PURE_QUANTA.Q_CAP(CHIPS)':
 'A': CDS_PINID='A';
NODE_NAME     R1283 2
 '@T6G_MB_LIB.T6G(SCH_1):PAGE466_I74@PURE_QUANTA.Q_RES(CHIPS)':
 'B': CDS_PINID='B';
NET_NAME
'VSENSE_P3V3_INA230_1_INN'
 '@T6G_MB_LIB.T6G(SCH_1):VSENSE_P3V3_INA230_1_INN':
 C_SIGNAL='@t6g_mb_lib.t6g(sch_1):vsense_p3v3_ina230_1_inn';
NODE_NAME     U266 12
 '@T6G_MB_LIB.T6G(SCH_1):PAGE295_I30@PURE_QUANTA.ISL28022FRZT(CHIPS)':
 'VINM': CDS_PINID='VINM';
NODE_NAME     R3603 2
 '@T6G_MB_LIB.T6G(SCH_1):PAGE295_I43@PURE_QUANTA.Q_RES(CHIPS)':
 'B': CDS_PINID='B';
NODE_NAME     C2027 2
 '@T6G_MB_LIB.T6G(SCH_1):PAGE295_I77@PURE_QUANTA.Q_CAP(CHIPS)':
 'B': CDS_PINID='B';
NET_NAME
'VSENSE_P3V3_INA230_1_INP'
 '@T6G_MB_LIB.T6G(SCH_1):VSENSE_P3V3_INA230_1_INP':
 C_SIGNAL='@t6g_mb_lib.t6g(sch_1):vsense_p3v3_ina230_1_inp';
NODE_NAME     U266 13
 '@T6G_MB_LIB.T6G(SCH_1):PAGE295_I30@PURE_QUANTA.ISL28022FRZT(CHIPS)':
 'VINP': CDS_PINID='VINP';
NODE_NAME     R3602 2
 '@T6G_MB_LIB.T6G(SCH_1):PAGE295_I41@PURE_QUANTA.Q_RES(CHIPS)':
 'B': CDS_PINID='B';
NODE_NAME     C2027 1
 '@T6G_MB_LIB.T6G(SCH_1):PAGE295_I77@PURE_QUANTA.Q_CAP(CHIPS)':
 'A': CDS_PINID='A';
NET_NAME
'VSENSE_P3V3_INA230_2_INN'
 '@T6G_MB_LIB.T6G(SCH_1):VSENSE_P3V3_INA230_2_INN':
 C_SIGNAL='@t6g_mb_lib.t6g(sch_1):vsense_p3v3_ina230_2_inn';
NODE_NAME     U276 12
 '@T6G_MB_LIB.T6G(SCH_1):PAGE295_I129@PURE_QUANTA.ISL28022FRZT(CHIPS)':
 'VINM': CDS_PINID='VINM';
NODE_NAME     C2071 2
 '@T6G_MB_LIB.T6G(SCH_1):PAGE295_I133@PURE_QUANTA.Q_CAP(CHIPS)':
 'B': CDS_PINID='B';
NODE_NAME     R3760 2
 '@T6G_MB_LIB.T6G(SCH_1):PAGE295_I134@PURE_QUANTA.Q_RES(CHIPS)':
 'B': CDS_PINID='B';
NET_NAME
'VSENSE_P3V3_INA230_2_INP'
 '@T6G_MB_LIB.T6G(SCH_1):VSENSE_P3V3_INA230_2_INP':
 C_SIGNAL='@t6g_mb_lib.t6g(sch_1):vsense_p3v3_ina230_2_inp';
NODE_NAME     U276 13
 '@T6G_MB_LIB.T6G(SCH_1):PAGE295_I129@PURE_QUANTA.ISL28022FRZT(CHIPS)':
 'VINP': CDS_PINID='VINP';
NODE_NAME     R3758 2
 '@T6G_MB_LIB.T6G(SCH_1):PAGE295_I132@PURE_QUANTA.Q_RES(CHIPS)':
 'B': CDS_PINID='B';
NODE_NAME     C2071 1
 '@T6G_MB_LIB.T6G(SCH_1):PAGE295_I133@PURE_QUANTA.Q_CAP(CHIPS)':
 'A': CDS_PINID='A';
NET_NAME
'VSENSE_PVDD11_S3_P0_DP'
 '@T6G_MB_LIB.T6G(SCH_1):VSENSE_PVDD11_S3_P0_DP':
 C_SIGNAL='@t6g_mb_lib.t6g(sch_1):vsense_pvdd11_s3_p0_dp';
NODE_NAME     U25 DH3
 '@T6G_MB_LIB.T6G(SCH_1):PAGE27_I227@PURE_QUANTA.GENOA_SP5(CHIPS)':
 'VDD_11_S3_SENSE': CDS_PINID='VDD_11_S3_SENSE';
NODE_NAME     TP8 1
 '@T6G_MB_LIB.T6G(SCH_1):PAGE27_I356@PURE_QUANTA.TP(CHIPS)':
 'TP': CDS_PINID='TP';
NODE_NAME     PR121 1
 '@T6G_MB_LIB.T6G(SCH_1):PAGE182_I28@PURE_QUANTA.Q_RES(CHIPS)':
 'A': CDS_PINID='A';
NODE_NAME     PR114 2
 '@T6G_MB_LIB.T6G(SCH_1):PAGE182_I30@PURE_QUANTA.Q_RES(CHIPS)':
 'B': CDS_PINID='B';
NET_NAME
'VSENSE_PVDD11_S3_P0_R'
 '@T6G_MB_LIB.T6G(SCH_1):VSENSE_PVDD11_S3_P0_R':
 C_SIGNAL='@t6g_mb_lib.t6g(sch_1):vsense_pvdd11_s3_p0_r';
NODE_NAME     PU21 21
 '@T6G_MB_LIB.T6G(SCH_1):PAGE182_I24@PURE_QUANTA.RAA229621GNPHA0(CHIPS)':
 'VSEN0': CDS_PINID='VSEN0';
NODE_NAME     PR121 2
 '@T6G_MB_LIB.T6G(SCH_1):PAGE182_I28@PURE_QUANTA.Q_RES(CHIPS)':
 'B': CDS_PINID='B';
NODE_NAME     PC194 1
 '@T6G_MB_LIB.T6G(SCH_1):PAGE182_I29@PURE_QUANTA.Q_CAP(CHIPS)':
 'A': CDS_PINID='A';
NET_NAME
'VSENSE_PVDD11_S3_P1_DP'
 '@T6G_MB_LIB.T6G(SCH_1):VSENSE_PVDD11_S3_P1_DP':
 C_SIGNAL='@t6g_mb_lib.t6g(sch_1):vsense_pvdd11_s3_p1_dp';
NODE_NAME     U26 DH3
 '@T6G_MB_LIB.T6G(SCH_1):PAGE54_I190@PURE_QUANTA.GENOA_SP5(CHIPS)':
 'VDD_11_S3_SENSE': CDS_PINID='VDD_11_S3_SENSE';
NODE_NAME     TP18 1
 '@T6G_MB_LIB.T6G(SCH_1):PAGE54_I240@PURE_QUANTA.TP(CHIPS)':
 'TP': CDS_PINID='TP';
NODE_NAME     PR384 1
 '@T6G_MB_LIB.T6G(SCH_1):PAGE199_I27@PURE_QUANTA.Q_RES(CHIPS)':
 'A': CDS_PINID='A';
NODE_NAME     PR229 2
 '@T6G_MB_LIB.T6G(SCH_1):PAGE199_I29@PURE_QUANTA.Q_RES(CHIPS)':
 'B': CDS_PINID='B';
NET_NAME
'VSENSE_PVDD11_S3_P1_R'
 '@T6G_MB_LIB.T6G(SCH_1):VSENSE_PVDD11_S3_P1_R':
 C_SIGNAL='@t6g_mb_lib.t6g(sch_1):vsense_pvdd11_s3_p1_r';
NODE_NAME     PR384 2
 '@T6G_MB_LIB.T6G(SCH_1):PAGE199_I27@PURE_QUANTA.Q_RES(CHIPS)':
 'B': CDS_PINID='B';
NODE_NAME     PC639 1
 '@T6G_MB_LIB.T6G(SCH_1):PAGE199_I28@PURE_QUANTA.Q_CAP(CHIPS)':
 'A': CDS_PINID='A';
NODE_NAME     PU54 21
 '@T6G_MB_LIB.T6G(SCH_1):PAGE199_I86@PURE_QUANTA.RAA229621GNPHA0(CHIPS)':
 'VSEN0': CDS_PINID='VSEN0';
NET_NAME
'VSENSE_PVDD18_S5_P0_DN'
 '@T6G_MB_LIB.T6G(SCH_1):VSENSE_PVDD18_S5_P0_DN':
 C_SIGNAL='@t6g_mb_lib.t6g(sch_1):vsense_pvdd18_s5_p0_dn';
NODE_NAME     U25 B73
 '@T6G_MB_LIB.T6G(SCH_1):PAGE27_I227@PURE_QUANTA.GENOA_SP5(CHIPS)':
 'VSS_SENSE_D': CDS_PINID='VSS_SENSE_D';
NODE_NAME     TP4 1
 '@T6G_MB_LIB.T6G(SCH_1):PAGE27_I360@PURE_QUANTA.TP(CHIPS)':
 'TP': CDS_PINID='TP';
NODE_NAME     PR435 2
 '@T6G_MB_LIB.T6G(SCH_1):PAGE184_I37@PURE_QUANTA.Q_RES(CHIPS)':
 'B': CDS_PINID='B';
NET_NAME
'VSENSE_PVDD18_S5_P0_DP'
 '@T6G_MB_LIB.T6G(SCH_1):VSENSE_PVDD18_S5_P0_DP':
 C_SIGNAL='@t6g_mb_lib.t6g(sch_1):vsense_pvdd18_s5_p0_dp';
NODE_NAME     U25 C74
 '@T6G_MB_LIB.T6G(SCH_1):PAGE27_I227@PURE_QUANTA.GENOA_SP5(CHIPS)':
 'VDD_18_S5_SENSE': CDS_PINID='VDD_18_S5_SENSE';
NODE_NAME     TP9 1
 '@T6G_MB_LIB.T6G(SCH_1):PAGE27_I355@PURE_QUANTA.TP(CHIPS)':
 'TP': CDS_PINID='TP';
NODE_NAME     PR434 2
 '@T6G_MB_LIB.T6G(SCH_1):PAGE184_I38@PURE_QUANTA.Q_RES(CHIPS)':
 'B': CDS_PINID='B';
NET_NAME
'VSENSE_PVDD18_S5_P1_DN'
 '@T6G_MB_LIB.T6G(SCH_1):VSENSE_PVDD18_S5_P1_DN':
 C_SIGNAL='@t6g_mb_lib.t6g(sch_1):vsense_pvdd18_s5_p1_dn';
NODE_NAME     U26 B73
 '@T6G_MB_LIB.T6G(SCH_1):PAGE54_I190@PURE_QUANTA.GENOA_SP5(CHIPS)':
 'VSS_SENSE_D': CDS_PINID='VSS_SENSE_D';
NODE_NAME     TP14 1
 '@T6G_MB_LIB.T6G(SCH_1):PAGE54_I244@PURE_QUANTA.TP(CHIPS)':
 'TP': CDS_PINID='TP';
NODE_NAME     PR401 2
 '@T6G_MB_LIB.T6G(SCH_1):PAGE201_I35@PURE_QUANTA.Q_RES(CHIPS)':
 'B': CDS_PINID='B';
NET_NAME
'VSENSE_PVDD18_S5_P1_DP'
 '@T6G_MB_LIB.T6G(SCH_1):VSENSE_PVDD18_S5_P1_DP':
 C_SIGNAL='@t6g_mb_lib.t6g(sch_1):vsense_pvdd18_s5_p1_dp';
NODE_NAME     U26 C74
 '@T6G_MB_LIB.T6G(SCH_1):PAGE54_I190@PURE_QUANTA.GENOA_SP5(CHIPS)':
 'VDD_18_S5_SENSE': CDS_PINID='VDD_18_S5_SENSE';
NODE_NAME     TP19 1
 '@T6G_MB_LIB.T6G(SCH_1):PAGE54_I238@PURE_QUANTA.TP(CHIPS)':
 'TP': CDS_PINID='TP';
NODE_NAME     PR400 2
 '@T6G_MB_LIB.T6G(SCH_1):PAGE201_I36@PURE_QUANTA.Q_RES(CHIPS)':
 'B': CDS_PINID='B';
NET_NAME
'VSENSE_PVDDCR_CPU0_P0_DP'
 '@T6G_MB_LIB.T6G(SCH_1):VSENSE_PVDDCR_CPU0_P0_DP':
 C_SIGNAL='@t6g_mb_lib.t6g(sch_1):vsense_pvddcr_cpu0_p0_dp';
NODE_NAME     U25 C2
 '@T6G_MB_LIB.T6G(SCH_1):PAGE27_I227@PURE_QUANTA.GENOA_SP5(CHIPS)':
 'VDDCR_CPU0_SENSE': CDS_PINID='VDDCR_CPU0_SENSE';
NODE_NAME     TP7 1
 '@T6G_MB_LIB.T6G(SCH_1):PAGE27_I357@PURE_QUANTA.TP(CHIPS)':
 'TP': CDS_PINID='TP';
NODE_NAME     PR306 1
 '@T6G_MB_LIB.T6G(SCH_1):PAGE168_I61@PURE_QUANTA.Q_RES(CHIPS)':
 'A': CDS_PINID='A';
NODE_NAME     PR294 2
 '@T6G_MB_LIB.T6G(SCH_1):PAGE168_I72@PURE_QUANTA.Q_RES(CHIPS)':
 'B': CDS_PINID='B';
NET_NAME
'VSENSE_PVDDCR_CPU0_P0_VSEN0'
 '@T6G_MB_LIB.T6G(SCH_1):VSENSE_PVDDCR_CPU0_P0_VSEN0':
 C_SIGNAL='@t6g_mb_lib.t6g(sch_1):vsense_pvddcr_cpu0_p0_vsen0';
NODE_NAME     PC463 1
 '@T6G_MB_LIB.T6G(SCH_1):PAGE168_I62@PURE_QUANTA.Q_CAP(CHIPS)':
 'A': CDS_PINID='A';
NODE_NAME     PR306 2
 '@T6G_MB_LIB.T6G(SCH_1):PAGE168_I61@PURE_QUANTA.Q_RES(CHIPS)':
 'B': CDS_PINID='B';
NODE_NAME     PU42 25
 '@T6G_MB_LIB.T6G(SCH_1):PAGE168_I135@PURE_QUANTA.RAA229620GNPHA0(CHIPS)':
 'VSEN0': CDS_PINID='VSEN0';
NET_NAME
'VSENSE_PVDDCR_CPU0_P1_DP'
 '@T6G_MB_LIB.T6G(SCH_1):VSENSE_PVDDCR_CPU0_P1_DP':
 C_SIGNAL='@t6g_mb_lib.t6g(sch_1):vsense_pvddcr_cpu0_p1_dp';
NODE_NAME     U26 C2
 '@T6G_MB_LIB.T6G(SCH_1):PAGE54_I190@PURE_QUANTA.GENOA_SP5(CHIPS)':
 'VDDCR_CPU0_SENSE': CDS_PINID='VDDCR_CPU0_SENSE';
NODE_NAME     TP17 1
 '@T6G_MB_LIB.T6G(SCH_1):PAGE54_I241@PURE_QUANTA.TP(CHIPS)':
 'TP': CDS_PINID='TP';
NODE_NAME     PR173 1
 '@T6G_MB_LIB.T6G(SCH_1):PAGE185_I59@PURE_QUANTA.Q_RES(CHIPS)':
 'A': CDS_PINID='A';
NODE_NAME     PR161 2
 '@T6G_MB_LIB.T6G(SCH_1):PAGE185_I70@PURE_QUANTA.Q_RES(CHIPS)':
 'B': CDS_PINID='B';
NET_NAME
'VSENSE_PVDDCR_CPU0_P1_VSEN0'
 '@T6G_MB_LIB.T6G(SCH_1):VSENSE_PVDDCR_CPU0_P1_VSEN0':
 C_SIGNAL='@t6g_mb_lib.t6g(sch_1):vsense_pvddcr_cpu0_p1_vsen0';
NODE_NAME     PR173 2
 '@T6G_MB_LIB.T6G(SCH_1):PAGE185_I59@PURE_QUANTA.Q_RES(CHIPS)':
 'B': CDS_PINID='B';
NODE_NAME     PC244 1
 '@T6G_MB_LIB.T6G(SCH_1):PAGE185_I60@PURE_QUANTA.Q_CAP(CHIPS)':
 'A': CDS_PINID='A';
NODE_NAME     PU25 25
 '@T6G_MB_LIB.T6G(SCH_1):PAGE185_I133@PURE_QUANTA.RAA229620GNPHA0(CHIPS)':
 'VSEN0': CDS_PINID='VSEN0';
NET_NAME
'VSENSE_PVDDCR_CPU1_P0_DP'
 '@T6G_MB_LIB.T6G(SCH_1):VSENSE_PVDDCR_CPU1_P0_DP':
 C_SIGNAL='@t6g_mb_lib.t6g(sch_1):vsense_pvddcr_cpu1_p0_dp';
NODE_NAME     U25 DG3
 '@T6G_MB_LIB.T6G(SCH_1):PAGE27_I227@PURE_QUANTA.GENOA_SP5(CHIPS)':
 'VDDCR_CPU1_SENSE': CDS_PINID='VDDCR_CPU1_SENSE';
NODE_NAME     TP6 1
 '@T6G_MB_LIB.T6G(SCH_1):PAGE27_I358@PURE_QUANTA.TP(CHIPS)':
 'TP': CDS_PINID='TP';
NODE_NAME     PR51 1
 '@T6G_MB_LIB.T6G(SCH_1):PAGE175_I36@PURE_QUANTA.Q_RES(CHIPS)':
 'A': CDS_PINID='A';
NODE_NAME     PR68 1
 '@T6G_MB_LIB.T6G(SCH_1):PAGE175_I78@PURE_QUANTA.Q_RES(CHIPS)':
 'A': CDS_PINID='A';
NET_NAME
'VSENSE_PVDDCR_CPU1_P0_VSEN0'
 '@T6G_MB_LIB.T6G(SCH_1):VSENSE_PVDDCR_CPU1_P0_VSEN0':
 C_SIGNAL='@t6g_mb_lib.t6g(sch_1):vsense_pvddcr_cpu1_p0_vsen0';
NODE_NAME     PR68 2
 '@T6G_MB_LIB.T6G(SCH_1):PAGE175_I78@PURE_QUANTA.Q_RES(CHIPS)':
 'B': CDS_PINID='B';
NODE_NAME     PC68 1
 '@T6G_MB_LIB.T6G(SCH_1):PAGE175_I80@PURE_QUANTA.Q_CAP(CHIPS)':
 'A': CDS_PINID='A';
NODE_NAME     PU12 25
 '@T6G_MB_LIB.T6G(SCH_1):PAGE175_I128@PURE_QUANTA.RAA229620GNPHA0(CHIPS)':
 'VSEN0': CDS_PINID='VSEN0';
NET_NAME
'VSENSE_PVDDCR_CPU1_P1_DP'
 '@T6G_MB_LIB.T6G(SCH_1):VSENSE_PVDDCR_CPU1_P1_DP':
 C_SIGNAL='@t6g_mb_lib.t6g(sch_1):vsense_pvddcr_cpu1_p1_dp';
NODE_NAME     U26 DG3
 '@T6G_MB_LIB.T6G(SCH_1):PAGE54_I190@PURE_QUANTA.GENOA_SP5(CHIPS)':
 'VDDCR_CPU1_SENSE': CDS_PINID='VDDCR_CPU1_SENSE';
NODE_NAME     TP16 1
 '@T6G_MB_LIB.T6G(SCH_1):PAGE54_I242@PURE_QUANTA.TP(CHIPS)':
 'TP': CDS_PINID='TP';
NODE_NAME     PR228 1
 '@T6G_MB_LIB.T6G(SCH_1):PAGE192_I34@PURE_QUANTA.Q_RES(CHIPS)':
 'A': CDS_PINID='A';
NODE_NAME     PR245 1
 '@T6G_MB_LIB.T6G(SCH_1):PAGE192_I77@PURE_QUANTA.Q_RES(CHIPS)':
 'A': CDS_PINID='A';
NET_NAME
'VSENSE_PVDDCR_CPU1_P1_VSEN0'
 '@T6G_MB_LIB.T6G(SCH_1):VSENSE_PVDDCR_CPU1_P1_VSEN0':
 C_SIGNAL='@t6g_mb_lib.t6g(sch_1):vsense_pvddcr_cpu1_p1_vsen0';
NODE_NAME     PR245 2
 '@T6G_MB_LIB.T6G(SCH_1):PAGE192_I77@PURE_QUANTA.Q_RES(CHIPS)':
 'B': CDS_PINID='B';
NODE_NAME     PC358 1
 '@T6G_MB_LIB.T6G(SCH_1):PAGE192_I79@PURE_QUANTA.Q_CAP(CHIPS)':
 'A': CDS_PINID='A';
NODE_NAME     PU34 25
 '@T6G_MB_LIB.T6G(SCH_1):PAGE192_I128@PURE_QUANTA.RAA229620GNPHA0(CHIPS)':
 'VSEN0': CDS_PINID='VSEN0';
NET_NAME
'VSENSE_PVDDCR_SOC_P0_DP'
 '@T6G_MB_LIB.T6G(SCH_1):VSENSE_PVDDCR_SOC_P0_DP':
 C_SIGNAL='@t6g_mb_lib.t6g(sch_1):vsense_pvddcr_soc_p0_dp';
NODE_NAME     U25 B3
 '@T6G_MB_LIB.T6G(SCH_1):PAGE27_I227@PURE_QUANTA.GENOA_SP5(CHIPS)':
 'VDDCR_SOC_SENSE': CDS_PINID='VDDCR_SOC_SENSE';
NODE_NAME     TP10 1
 '@T6G_MB_LIB.T6G(SCH_1):PAGE27_I403@PURE_QUANTA.TP(CHIPS)':
 'TP': CDS_PINID='TP';
NODE_NAME     PR296 2
 '@T6G_MB_LIB.T6G(SCH_1):PAGE168_I40@PURE_QUANTA.Q_RES(CHIPS)':
 'B': CDS_PINID='B';
NODE_NAME     PR307 1
 '@T6G_MB_LIB.T6G(SCH_1):PAGE168_I59@PURE_QUANTA.Q_RES(CHIPS)':
 'A': CDS_PINID='A';
NET_NAME
'VSENSE_PVDDCR_SOC_P0_VSEN1'
 '@T6G_MB_LIB.T6G(SCH_1):VSENSE_PVDDCR_SOC_P0_VSEN1':
 C_SIGNAL='@t6g_mb_lib.t6g(sch_1):vsense_pvddcr_soc_p0_vsen1';
NODE_NAME     PR307 2
 '@T6G_MB_LIB.T6G(SCH_1):PAGE168_I59@PURE_QUANTA.Q_RES(CHIPS)':
 'B': CDS_PINID='B';
NODE_NAME     PC464 1
 '@T6G_MB_LIB.T6G(SCH_1):PAGE168_I60@PURE_QUANTA.Q_CAP(CHIPS)':
 'A': CDS_PINID='A';
NODE_NAME     PU42 40
 '@T6G_MB_LIB.T6G(SCH_1):PAGE168_I135@PURE_QUANTA.RAA229620GNPHA0(CHIPS)':
 'VSEN1': CDS_PINID='VSEN1';
NET_NAME
'VSENSE_PVDDCR_SOC_P1_DP'
 '@T6G_MB_LIB.T6G(SCH_1):VSENSE_PVDDCR_SOC_P1_DP':
 C_SIGNAL='@t6g_mb_lib.t6g(sch_1):vsense_pvddcr_soc_p1_dp';
NODE_NAME     U26 B3
 '@T6G_MB_LIB.T6G(SCH_1):PAGE54_I190@PURE_QUANTA.GENOA_SP5(CHIPS)':
 'VDDCR_SOC_SENSE': CDS_PINID='VDDCR_SOC_SENSE';
NODE_NAME     TP20 1
 '@T6G_MB_LIB.T6G(SCH_1):PAGE54_I237@PURE_QUANTA.TP(CHIPS)':
 'TP': CDS_PINID='TP';
NODE_NAME     PR174 1
 '@T6G_MB_LIB.T6G(SCH_1):PAGE185_I57@PURE_QUANTA.Q_RES(CHIPS)':
 'A': CDS_PINID='A';
NODE_NAME     PR163 2
 '@T6G_MB_LIB.T6G(SCH_1):PAGE185_I39@PURE_QUANTA.Q_RES(CHIPS)':
 'B': CDS_PINID='B';
NET_NAME
'VSENSE_PVDDCR_SOC_P1_VSEN1'
 '@T6G_MB_LIB.T6G(SCH_1):VSENSE_PVDDCR_SOC_P1_VSEN1':
 C_SIGNAL='@t6g_mb_lib.t6g(sch_1):vsense_pvddcr_soc_p1_vsen1';
NODE_NAME     PR174 2
 '@T6G_MB_LIB.T6G(SCH_1):PAGE185_I57@PURE_QUANTA.Q_RES(CHIPS)':
 'B': CDS_PINID='B';
NODE_NAME     PC245 1
 '@T6G_MB_LIB.T6G(SCH_1):PAGE185_I58@PURE_QUANTA.Q_CAP(CHIPS)':
 'A': CDS_PINID='A';
NODE_NAME     PU25 40
 '@T6G_MB_LIB.T6G(SCH_1):PAGE185_I133@PURE_QUANTA.RAA229620GNPHA0(CHIPS)':
 'VSEN1': CDS_PINID='VSEN1';
NET_NAME
'VSENSE_PVDDIO_P0_DP'
 '@T6G_MB_LIB.T6G(SCH_1):VSENSE_PVDDIO_P0_DP':
 C_SIGNAL='@t6g_mb_lib.t6g(sch_1):vsense_pvddio_p0_dp';
NODE_NAME     U25 BR53
 '@T6G_MB_LIB.T6G(SCH_1):PAGE27_I227@PURE_QUANTA.GENOA_SP5(CHIPS)':
 'VDDIO_SENSE': CDS_PINID='VDDIO_SENSE';
NODE_NAME     TP5 1
 '@T6G_MB_LIB.T6G(SCH_1):PAGE27_I359@PURE_QUANTA.TP(CHIPS)':
 'TP': CDS_PINID='TP';
NODE_NAME     PR52 1
 '@T6G_MB_LIB.T6G(SCH_1):PAGE175_I22@PURE_QUANTA.Q_RES(CHIPS)':
 'A': CDS_PINID='A';
NODE_NAME     PR69 1
 '@T6G_MB_LIB.T6G(SCH_1):PAGE175_I70@PURE_QUANTA.Q_RES(CHIPS)':
 'A': CDS_PINID='A';
NET_NAME
'VSENSE_PVDDIO_P0_VSEN1'
 '@T6G_MB_LIB.T6G(SCH_1):VSENSE_PVDDIO_P0_VSEN1':
 C_SIGNAL='@t6g_mb_lib.t6g(sch_1):vsense_pvddio_p0_vsen1';
NODE_NAME     PC71 1
 '@T6G_MB_LIB.T6G(SCH_1):PAGE175_I69@PURE_QUANTA.Q_CAP(CHIPS)':
 'A': CDS_PINID='A';
NODE_NAME     PR69 2
 '@T6G_MB_LIB.T6G(SCH_1):PAGE175_I70@PURE_QUANTA.Q_RES(CHIPS)':
 'B': CDS_PINID='B';
NODE_NAME     PU12 40
 '@T6G_MB_LIB.T6G(SCH_1):PAGE175_I128@PURE_QUANTA.RAA229620GNPHA0(CHIPS)':
 'VSEN1': CDS_PINID='VSEN1';
NET_NAME
'VSENSE_PVDDIO_P1_DP'
 '@T6G_MB_LIB.T6G(SCH_1):VSENSE_PVDDIO_P1_DP':
 C_SIGNAL='@t6g_mb_lib.t6g(sch_1):vsense_pvddio_p1_dp';
NODE_NAME     U26 BR53
 '@T6G_MB_LIB.T6G(SCH_1):PAGE54_I190@PURE_QUANTA.GENOA_SP5(CHIPS)':
 'VDDIO_SENSE': CDS_PINID='VDDIO_SENSE';
NODE_NAME     TP15 1
 '@T6G_MB_LIB.T6G(SCH_1):PAGE54_I243@PURE_QUANTA.TP(CHIPS)':
 'TP': CDS_PINID='TP';
NODE_NAME     PR227 1
 '@T6G_MB_LIB.T6G(SCH_1):PAGE192_I22@PURE_QUANTA.Q_RES(CHIPS)':
 'A': CDS_PINID='A';
NODE_NAME     PR246 1
 '@T6G_MB_LIB.T6G(SCH_1):PAGE192_I69@PURE_QUANTA.Q_RES(CHIPS)':
 'A': CDS_PINID='A';
NET_NAME
'VSENSE_PVDDIO_P1_VSEN1'
 '@T6G_MB_LIB.T6G(SCH_1):VSENSE_PVDDIO_P1_VSEN1':
 C_SIGNAL='@t6g_mb_lib.t6g(sch_1):vsense_pvddio_p1_vsen1';
NODE_NAME     PC361 1
 '@T6G_MB_LIB.T6G(SCH_1):PAGE192_I67@PURE_QUANTA.Q_CAP(CHIPS)':
 'A': CDS_PINID='A';
NODE_NAME     PR246 2
 '@T6G_MB_LIB.T6G(SCH_1):PAGE192_I69@PURE_QUANTA.Q_RES(CHIPS)':
 'B': CDS_PINID='B';
NODE_NAME     PU34 40
 '@T6G_MB_LIB.T6G(SCH_1):PAGE192_I128@PURE_QUANTA.RAA229620GNPHA0(CHIPS)':
 'VSEN1': CDS_PINID='VSEN1';
NET_NAME
'VSENSE_VSS_SENSE_A_P0'
 '@T6G_MB_LIB.T6G(SCH_1):VSENSE_VSS_SENSE_A_P0':
 C_SIGNAL='@t6g_mb_lib.t6g(sch_1):vsense_vss_sense_a_p0';
NODE_NAME     U25 C3
 '@T6G_MB_LIB.T6G(SCH_1):PAGE27_I227@PURE_QUANTA.GENOA_SP5(CHIPS)':
 'VSS_SENSE_A': CDS_PINID='VSS_SENSE_A';
NODE_NAME     TP1 1
 '@T6G_MB_LIB.T6G(SCH_1):PAGE27_I404@PURE_QUANTA.TP(CHIPS)':
 'TP': CDS_PINID='TP';
NODE_NAME     PR297 1
 '@T6G_MB_LIB.T6G(SCH_1):PAGE168_I36@PURE_QUANTA.Q_RES(CHIPS)':
 'A': CDS_PINID='A';
NODE_NAME     PC463 2
 '@T6G_MB_LIB.T6G(SCH_1):PAGE168_I62@PURE_QUANTA.Q_CAP(CHIPS)':
 'B': CDS_PINID='B';
NODE_NAME     PR295 1
 '@T6G_MB_LIB.T6G(SCH_1):PAGE168_I44@PURE_QUANTA.Q_RES(CHIPS)':
 'A': CDS_PINID='A';
NODE_NAME     PC464 2
 '@T6G_MB_LIB.T6G(SCH_1):PAGE168_I60@PURE_QUANTA.Q_CAP(CHIPS)':
 'B': CDS_PINID='B';
NODE_NAME     PU42 26
 '@T6G_MB_LIB.T6G(SCH_1):PAGE168_I135@PURE_QUANTA.RAA229620GNPHA0(CHIPS)':
 'RGND0': CDS_PINID='RGND0';
NODE_NAME     PU42 39
 '@T6G_MB_LIB.T6G(SCH_1):PAGE168_I135@PURE_QUANTA.RAA229620GNPHA0(CHIPS)':
 'RGND1': CDS_PINID='RGND1';
NET_NAME
'VSENSE_VSS_SENSE_A_P1'
 '@T6G_MB_LIB.T6G(SCH_1):VSENSE_VSS_SENSE_A_P1':
 C_SIGNAL='@t6g_mb_lib.t6g(sch_1):vsense_vss_sense_a_p1';
NODE_NAME     U26 C3
 '@T6G_MB_LIB.T6G(SCH_1):PAGE54_I190@PURE_QUANTA.GENOA_SP5(CHIPS)':
 'VSS_SENSE_A': CDS_PINID='VSS_SENSE_A';
NODE_NAME     TP11 1
 '@T6G_MB_LIB.T6G(SCH_1):PAGE54_I273@PURE_QUANTA.TP(CHIPS)':
 'TP': CDS_PINID='TP';
NODE_NAME     PR164 1
 '@T6G_MB_LIB.T6G(SCH_1):PAGE185_I36@PURE_QUANTA.Q_RES(CHIPS)':
 'A': CDS_PINID='A';
NODE_NAME     PC245 2
 '@T6G_MB_LIB.T6G(SCH_1):PAGE185_I58@PURE_QUANTA.Q_CAP(CHIPS)':
 'B': CDS_PINID='B';
NODE_NAME     PR162 1
 '@T6G_MB_LIB.T6G(SCH_1):PAGE185_I45@PURE_QUANTA.Q_RES(CHIPS)':
 'A': CDS_PINID='A';
NODE_NAME     PC244 2
 '@T6G_MB_LIB.T6G(SCH_1):PAGE185_I60@PURE_QUANTA.Q_CAP(CHIPS)':
 'B': CDS_PINID='B';
NODE_NAME     PU25 26
 '@T6G_MB_LIB.T6G(SCH_1):PAGE185_I133@PURE_QUANTA.RAA229620GNPHA0(CHIPS)':
 'RGND0': CDS_PINID='RGND0';
NODE_NAME     PU25 39
 '@T6G_MB_LIB.T6G(SCH_1):PAGE185_I133@PURE_QUANTA.RAA229620GNPHA0(CHIPS)':
 'RGND1': CDS_PINID='RGND1';
NET_NAME
'VSENSE_VSS_SENSE_B_P0'
 '@T6G_MB_LIB.T6G(SCH_1):VSENSE_VSS_SENSE_B_P0':
 C_SIGNAL='@t6g_mb_lib.t6g(sch_1):vsense_vss_sense_b_p0';
NODE_NAME     U25 BR54
 '@T6G_MB_LIB.T6G(SCH_1):PAGE27_I227@PURE_QUANTA.GENOA_SP5(CHIPS)':
 'VSS_SENSE_B': CDS_PINID='VSS_SENSE_B';
NODE_NAME     TP2 1
 '@T6G_MB_LIB.T6G(SCH_1):PAGE27_I362@PURE_QUANTA.TP(CHIPS)':
 'TP': CDS_PINID='TP';
NODE_NAME     PR50 1
 '@T6G_MB_LIB.T6G(SCH_1):PAGE175_I19@PURE_QUANTA.Q_RES(CHIPS)':
 'A': CDS_PINID='A';
NODE_NAME     PC71 2
 '@T6G_MB_LIB.T6G(SCH_1):PAGE175_I69@PURE_QUANTA.Q_CAP(CHIPS)':
 'B': CDS_PINID='B';
NODE_NAME     PU12 39
 '@T6G_MB_LIB.T6G(SCH_1):PAGE175_I128@PURE_QUANTA.RAA229620GNPHA0(CHIPS)':
 'RGND1': CDS_PINID='RGND1';
NET_NAME
'VSENSE_VSS_SENSE_B_P1'
 '@T6G_MB_LIB.T6G(SCH_1):VSENSE_VSS_SENSE_B_P1':
 C_SIGNAL='@t6g_mb_lib.t6g(sch_1):vsense_vss_sense_b_p1';
NODE_NAME     U26 BR54
 '@T6G_MB_LIB.T6G(SCH_1):PAGE54_I190@PURE_QUANTA.GENOA_SP5(CHIPS)':
 'VSS_SENSE_B': CDS_PINID='VSS_SENSE_B';
NODE_NAME     TP12 1
 '@T6G_MB_LIB.T6G(SCH_1):PAGE54_I272@PURE_QUANTA.TP(CHIPS)':
 'TP': CDS_PINID='TP';
NODE_NAME     PR460 1
 '@T6G_MB_LIB.T6G(SCH_1):PAGE192_I19@PURE_QUANTA.Q_RES(CHIPS)':
 'A': CDS_PINID='A';
NODE_NAME     PC361 2
 '@T6G_MB_LIB.T6G(SCH_1):PAGE192_I67@PURE_QUANTA.Q_CAP(CHIPS)':
 'B': CDS_PINID='B';
NODE_NAME     PU34 39
 '@T6G_MB_LIB.T6G(SCH_1):PAGE192_I128@PURE_QUANTA.RAA229620GNPHA0(CHIPS)':
 'RGND1': CDS_PINID='RGND1';
NET_NAME
'VSENSE_VSS_SENSE_C_P0'
 '@T6G_MB_LIB.T6G(SCH_1):VSENSE_VSS_SENSE_C_P0':
 C_SIGNAL='@t6g_mb_lib.t6g(sch_1):vsense_vss_sense_c_p0';
NODE_NAME     U25 DJ3
 '@T6G_MB_LIB.T6G(SCH_1):PAGE27_I227@PURE_QUANTA.GENOA_SP5(CHIPS)':
 'VSS_SENSE_C': CDS_PINID='VSS_SENSE_C';
NODE_NAME     TP3 1
 '@T6G_MB_LIB.T6G(SCH_1):PAGE27_I361@PURE_QUANTA.TP(CHIPS)':
 'TP': CDS_PINID='TP';
NODE_NAME     PR49 1
 '@T6G_MB_LIB.T6G(SCH_1):PAGE175_I23@PURE_QUANTA.Q_RES(CHIPS)':
 'A': CDS_PINID='A';
NODE_NAME     PC68 2
 '@T6G_MB_LIB.T6G(SCH_1):PAGE175_I80@PURE_QUANTA.Q_CAP(CHIPS)':
 'B': CDS_PINID='B';
NODE_NAME     PU12 26
 '@T6G_MB_LIB.T6G(SCH_1):PAGE175_I128@PURE_QUANTA.RAA229620GNPHA0(CHIPS)':
 'RGND0': CDS_PINID='RGND0';
NODE_NAME     PR115 1
 '@T6G_MB_LIB.T6G(SCH_1):PAGE182_I15@PURE_QUANTA.Q_RES(CHIPS)':
 'A': CDS_PINID='A';
NODE_NAME     PU21 22
 '@T6G_MB_LIB.T6G(SCH_1):PAGE182_I24@PURE_QUANTA.RAA229621GNPHA0(CHIPS)':
 'RGND0': CDS_PINID='RGND0';
NODE_NAME     PC194 2
 '@T6G_MB_LIB.T6G(SCH_1):PAGE182_I29@PURE_QUANTA.Q_CAP(CHIPS)':
 'B': CDS_PINID='B';
NET_NAME
'VSENSE_VSS_SENSE_C_P1'
 '@T6G_MB_LIB.T6G(SCH_1):VSENSE_VSS_SENSE_C_P1':
 C_SIGNAL='@t6g_mb_lib.t6g(sch_1):vsense_vss_sense_c_p1';
NODE_NAME     U26 DJ3
 '@T6G_MB_LIB.T6G(SCH_1):PAGE54_I190@PURE_QUANTA.GENOA_SP5(CHIPS)':
 'VSS_SENSE_C': CDS_PINID='VSS_SENSE_C';
NODE_NAME     TP13 1
 '@T6G_MB_LIB.T6G(SCH_1):PAGE54_I245@PURE_QUANTA.TP(CHIPS)':
 'TP': CDS_PINID='TP';
NODE_NAME     PR226 1
 '@T6G_MB_LIB.T6G(SCH_1):PAGE192_I23@PURE_QUANTA.Q_RES(CHIPS)':
 'A': CDS_PINID='A';
NODE_NAME     PC358 2
 '@T6G_MB_LIB.T6G(SCH_1):PAGE192_I79@PURE_QUANTA.Q_CAP(CHIPS)':
 'B': CDS_PINID='B';
NODE_NAME     PU34 26
 '@T6G_MB_LIB.T6G(SCH_1):PAGE192_I128@PURE_QUANTA.RAA229620GNPHA0(CHIPS)':
 'RGND0': CDS_PINID='RGND0';
NODE_NAME     PR288 1
 '@T6G_MB_LIB.T6G(SCH_1):PAGE199_I15@PURE_QUANTA.Q_RES(CHIPS)':
 'A': CDS_PINID='A';
NODE_NAME     PC639 2
 '@T6G_MB_LIB.T6G(SCH_1):PAGE199_I28@PURE_QUANTA.Q_CAP(CHIPS)':
 'B': CDS_PINID='B';
NODE_NAME     PU54 22
 '@T6G_MB_LIB.T6G(SCH_1):PAGE199_I86@PURE_QUANTA.RAA229621GNPHA0(CHIPS)':
 'RGND0': CDS_PINID='RGND0';
NET_NAME
'WAFL_CPU0_TX0_CPU1_RX1_DN'
 '@T6G_MB_LIB.T6G(SCH_1):WAFL_CPU0_TX0_CPU1_RX1_DN':
 C_SIGNAL='@t6g_mb_lib.t6g(sch_1):wafl_cpu0_tx0_cpu1_rx1_dn';
NODE_NAME     U25 C51
 '@T6G_MB_LIB.T6G(SCH_1):PAGE26_I59@PURE_QUANTA.GENOA_SP5(CHIPS)':
 'WAFL_TXN0||P5_TXN0': CDS_PINID='\wafl_txn0||p5_txn0\';
NODE_NAME     U26 E47
 '@T6G_MB_LIB.T6G(SCH_1):PAGE53_I145@PURE_QUANTA.GENOA_SP5(CHIPS)':
 'WAFL_RXN1||P5_RXN1': CDS_PINID='\wafl_rxn1||p5_rxn1\';
NET_NAME
'WAFL_CPU0_TX0_CPU1_RX1_DP'
 '@T6G_MB_LIB.T6G(SCH_1):WAFL_CPU0_TX0_CPU1_RX1_DP':
 C_SIGNAL='@t6g_mb_lib.t6g(sch_1):wafl_cpu0_tx0_cpu1_rx1_dp';
NODE_NAME     U25 C50
 '@T6G_MB_LIB.T6G(SCH_1):PAGE26_I59@PURE_QUANTA.GENOA_SP5(CHIPS)':
 'WAFL_TXP0||P5_TXP0': CDS_PINID='\wafl_txp0||p5_txp0\';
NODE_NAME     U26 E46
 '@T6G_MB_LIB.T6G(SCH_1):PAGE53_I145@PURE_QUANTA.GENOA_SP5(CHIPS)':
 'WAFL_RXP1||P5_RXP1': CDS_PINID='\wafl_rxp1||p5_rxp1\';
NET_NAME
'WAFL_CPU1_TX1_CPU0_RX0_DN'
 '@T6G_MB_LIB.T6G(SCH_1):WAFL_CPU1_TX1_CPU0_RX0_DN':
 C_SIGNAL='@t6g_mb_lib.t6g(sch_1):wafl_cpu1_tx1_cpu0_rx0_dn';
NODE_NAME     U25 E50
 '@T6G_MB_LIB.T6G(SCH_1):PAGE26_I59@PURE_QUANTA.GENOA_SP5(CHIPS)':
 'WAFL_RXN0||P5_RXN0': CDS_PINID='\wafl_rxn0||p5_rxn0\';
NODE_NAME     U26 C48
 '@T6G_MB_LIB.T6G(SCH_1):PAGE53_I145@PURE_QUANTA.GENOA_SP5(CHIPS)':
 'WAFL_TXN1||P5_TXN1': CDS_PINID='\wafl_txn1||p5_txn1\';
NET_NAME
'WAFL_CPU1_TX1_CPU0_RX0_DP'
 '@T6G_MB_LIB.T6G(SCH_1):WAFL_CPU1_TX1_CPU0_RX0_DP':
 C_SIGNAL='@t6g_mb_lib.t6g(sch_1):wafl_cpu1_tx1_cpu0_rx0_dp';
NODE_NAME     U25 E49
 '@T6G_MB_LIB.T6G(SCH_1):PAGE26_I59@PURE_QUANTA.GENOA_SP5(CHIPS)':
 'WAFL_RXP0||P5_RXP0': CDS_PINID='\wafl_rxp0||p5_rxp0\';
NODE_NAME     U26 C47
 '@T6G_MB_LIB.T6G(SCH_1):PAGE53_I145@PURE_QUANTA.GENOA_SP5(CHIPS)':
 'WAFL_TXP1||P5_TXP1': CDS_PINID='\wafl_txp1||p5_txp1\';
NET_NAME
'XTAL_CPU0_X32K_X1'
 '@T6G_MB_LIB.T6G(SCH_1):XTAL_CPU0_X32K_X1':
 C_SIGNAL='@t6g_mb_lib.t6g(sch_1):xtal_cpu0_x32k_x1';
NODE_NAME     Y3 1
 '@T6G_MB_LIB.T6G(SCH_1):PAGE28_I140@PURE_QUANTA.Q_CRYSTAL(CHIPS)':
 '1': CDS_PINID='\1\';
NODE_NAME     U25 DJ14
 '@T6G_MB_LIB.T6G(SCH_1):PAGE28_I188@PURE_QUANTA.GENOA_SP5(CHIPS)':
 'X32K_X1': CDS_PINID='X32K_X1';
NODE_NAME     R433 1
 '@T6G_MB_LIB.T6G(SCH_1):PAGE28_I221@PURE_QUANTA.Q_RES(CHIPS)':
 'A': CDS_PINID='A';
NODE_NAME     C215 1
 '@T6G_MB_LIB.T6G(SCH_1):PAGE28_I230@PURE_QUANTA.Q_CAP(CHIPS)':
 'A': CDS_PINID='A';
NET_NAME
'XTAL_CPU0_X32K_X2'
 '@T6G_MB_LIB.T6G(SCH_1):XTAL_CPU0_X32K_X2':
 C_SIGNAL='@t6g_mb_lib.t6g(sch_1):xtal_cpu0_x32k_x2';
NODE_NAME     Y3 2
 '@T6G_MB_LIB.T6G(SCH_1):PAGE28_I140@PURE_QUANTA.Q_CRYSTAL(CHIPS)':
 '2': CDS_PINID='\2\';
NODE_NAME     U25 DJ13
 '@T6G_MB_LIB.T6G(SCH_1):PAGE28_I188@PURE_QUANTA.GENOA_SP5(CHIPS)':
 'X32K_X2': CDS_PINID='X32K_X2';
NODE_NAME     R433 2
 '@T6G_MB_LIB.T6G(SCH_1):PAGE28_I221@PURE_QUANTA.Q_RES(CHIPS)':
 'B': CDS_PINID='B';
NODE_NAME     C216 1
 '@T6G_MB_LIB.T6G(SCH_1):PAGE28_I231@PURE_QUANTA.Q_CAP(CHIPS)':
 'A': CDS_PINID='A';
NET_NAME
'XTAL_CPU0_X48M_X1'
 '@T6G_MB_LIB.T6G(SCH_1):XTAL_CPU0_X48M_X1':
 C_SIGNAL='@t6g_mb_lib.t6g(sch_1):xtal_cpu0_x48m_x1';
NODE_NAME     Y2 1
 '@T6G_MB_LIB.T6G(SCH_1):PAGE28_I103@PURE_QUANTA.Q_XTAL_4P_13BI_24GND(CHIPS)':
 'X1': CDS_PINID='X1';
NODE_NAME     R432 1
 '@T6G_MB_LIB.T6G(SCH_1):PAGE28_I104@PURE_QUANTA.Q_RES(CHIPS)':
 'A': CDS_PINID='A';
NODE_NAME     U25 DJ17
 '@T6G_MB_LIB.T6G(SCH_1):PAGE28_I188@PURE_QUANTA.GENOA_SP5(CHIPS)':
 'X48M_X1': CDS_PINID='X48M_X1';
NODE_NAME     C213 1
 '@T6G_MB_LIB.T6G(SCH_1):PAGE28_I232@PURE_QUANTA.Q_CAP(CHIPS)':
 'A': CDS_PINID='A';
NET_NAME
'XTAL_CPU0_X48M_X2'
 '@T6G_MB_LIB.T6G(SCH_1):XTAL_CPU0_X48M_X2':
 C_SIGNAL='@t6g_mb_lib.t6g(sch_1):xtal_cpu0_x48m_x2';
NODE_NAME     U25 DJ16
 '@T6G_MB_LIB.T6G(SCH_1):PAGE28_I188@PURE_QUANTA.GENOA_SP5(CHIPS)':
 'X48M_X2': CDS_PINID='X48M_X2';
NODE_NAME     R5102 1
 '@T6G_MB_LIB.T6G(SCH_1):PAGE28_I195@PURE_QUANTA.Q_RES(CHIPS)':
 'A': CDS_PINID='A';
NET_NAME
'XTAL_CPU0_X48M_X2_R'
 '@T6G_MB_LIB.T6G(SCH_1):XTAL_CPU0_X48M_X2_R':
 C_SIGNAL='@t6g_mb_lib.t6g(sch_1):xtal_cpu0_x48m_x2_r';
NODE_NAME     Y2 3
 '@T6G_MB_LIB.T6G(SCH_1):PAGE28_I103@PURE_QUANTA.Q_XTAL_4P_13BI_24GND(CHIPS)':
 'X2': CDS_PINID='X2';
NODE_NAME     R432 2
 '@T6G_MB_LIB.T6G(SCH_1):PAGE28_I104@PURE_QUANTA.Q_RES(CHIPS)':
 'B': CDS_PINID='B';
NODE_NAME     R5102 2
 '@T6G_MB_LIB.T6G(SCH_1):PAGE28_I195@PURE_QUANTA.Q_RES(CHIPS)':
 'B': CDS_PINID='B';
NODE_NAME     C214 1
 '@T6G_MB_LIB.T6G(SCH_1):PAGE28_I233@PURE_QUANTA.Q_CAP(CHIPS)':
 'A': CDS_PINID='A';
NET_NAME
'XTAL_CPU1_R_X32K_X1'
 '@T6G_MB_LIB.T6G(SCH_1):XTAL_CPU1_R_X32K_X1':
 C_SIGNAL='@t6g_mb_lib.t6g(sch_1):xtal_cpu1_r_x32k_x1';
NODE_NAME     C238 1
 '@T6G_MB_LIB.T6G(SCH_1):PAGE55_I5@PURE_QUANTA.Q_CAP(CHIPS)':
 'A': CDS_PINID='A';
NODE_NAME     Y5 1
 '@T6G_MB_LIB.T6G(SCH_1):PAGE55_I7@PURE_QUANTA.Q_CRYSTAL(CHIPS)':
 '1': CDS_PINID='\1\';
NODE_NAME     R574 1
 '@T6G_MB_LIB.T6G(SCH_1):PAGE55_I24@PURE_QUANTA.Q_RES(CHIPS)':
 'A': CDS_PINID='A';
NODE_NAME     R572 1
 '@T6G_MB_LIB.T6G(SCH_1):PAGE55_I389@PURE_QUANTA.Q_RES(CHIPS)':
 'A': CDS_PINID='A';
NET_NAME
'XTAL_CPU1_R_X32K_X2'
 '@T6G_MB_LIB.T6G(SCH_1):XTAL_CPU1_R_X32K_X2':
 C_SIGNAL='@t6g_mb_lib.t6g(sch_1):xtal_cpu1_r_x32k_x2';
NODE_NAME     Y5 2
 '@T6G_MB_LIB.T6G(SCH_1):PAGE55_I7@PURE_QUANTA.Q_CRYSTAL(CHIPS)':
 '2': CDS_PINID='\2\';
NODE_NAME     C239 1
 '@T6G_MB_LIB.T6G(SCH_1):PAGE55_I9@PURE_QUANTA.Q_CAP(CHIPS)':
 'A': CDS_PINID='A';
NODE_NAME     R575 1
 '@T6G_MB_LIB.T6G(SCH_1):PAGE55_I296@PURE_QUANTA.Q_RES(CHIPS)':
 'A': CDS_PINID='A';
NODE_NAME     R572 2
 '@T6G_MB_LIB.T6G(SCH_1):PAGE55_I389@PURE_QUANTA.Q_RES(CHIPS)':
 'B': CDS_PINID='B';
NET_NAME
'XTAL_CPU1_X32K_X1'
 '@T6G_MB_LIB.T6G(SCH_1):XTAL_CPU1_X32K_X1':
 C_SIGNAL='@t6g_mb_lib.t6g(sch_1):xtal_cpu1_x32k_x1';
NODE_NAME     R574 2
 '@T6G_MB_LIB.T6G(SCH_1):PAGE55_I24@PURE_QUANTA.Q_RES(CHIPS)':
 'B': CDS_PINID='B';
NODE_NAME     R573 2
 '@T6G_MB_LIB.T6G(SCH_1):PAGE55_I26@PURE_QUANTA.Q_RES(CHIPS)':
 'B': CDS_PINID='B';
NODE_NAME     U26 DJ14
 '@T6G_MB_LIB.T6G(SCH_1):PAGE55_I182@PURE_QUANTA.GENOA_SP5(CHIPS)':
 'X32K_X1': CDS_PINID='X32K_X1';
NET_NAME
'XTAL_CPU1_X32K_X2'
 '@T6G_MB_LIB.T6G(SCH_1):XTAL_CPU1_X32K_X2':
 C_SIGNAL='@t6g_mb_lib.t6g(sch_1):xtal_cpu1_x32k_x2';
NODE_NAME     U26 DJ13
 '@T6G_MB_LIB.T6G(SCH_1):PAGE55_I182@PURE_QUANTA.GENOA_SP5(CHIPS)':
 'X32K_X2': CDS_PINID='X32K_X2';
NODE_NAME     R575 2
 '@T6G_MB_LIB.T6G(SCH_1):PAGE55_I296@PURE_QUANTA.Q_RES(CHIPS)':
 'B': CDS_PINID='B';
NET_NAME
'XTAL_CPU1_X48M_X1'
 '@T6G_MB_LIB.T6G(SCH_1):XTAL_CPU1_X48M_X1':
 C_SIGNAL='@t6g_mb_lib.t6g(sch_1):xtal_cpu1_x48m_x1';
NODE_NAME     C236 1
 '@T6G_MB_LIB.T6G(SCH_1):PAGE55_I3@PURE_QUANTA.Q_CAP(CHIPS)':
 'A': CDS_PINID='A';
NODE_NAME     R571 1
 '@T6G_MB_LIB.T6G(SCH_1):PAGE55_I10@PURE_QUANTA.Q_RES(CHIPS)':
 'A': CDS_PINID='A';
NODE_NAME     Y4 1
 '@T6G_MB_LIB.T6G(SCH_1):PAGE55_I12@PURE_QUANTA.Q_XTAL_4P_13BI_24GND(CHIPS)':
 'X1': CDS_PINID='X1';
NODE_NAME     U26 DJ17
 '@T6G_MB_LIB.T6G(SCH_1):PAGE55_I182@PURE_QUANTA.GENOA_SP5(CHIPS)':
 'X48M_X1': CDS_PINID='X48M_X1';
NET_NAME
'XTAL_CPU1_X48M_X2'
 '@T6G_MB_LIB.T6G(SCH_1):XTAL_CPU1_X48M_X2':
 C_SIGNAL='@t6g_mb_lib.t6g(sch_1):xtal_cpu1_x48m_x2';
NODE_NAME     U26 DJ16
 '@T6G_MB_LIB.T6G(SCH_1):PAGE55_I182@PURE_QUANTA.GENOA_SP5(CHIPS)':
 'X48M_X2': CDS_PINID='X48M_X2';
NODE_NAME     R5103 1
 '@T6G_MB_LIB.T6G(SCH_1):PAGE55_I386@PURE_QUANTA.Q_RES(CHIPS)':
 'A': CDS_PINID='A';
NET_NAME
'XTAL_CPU1_X48M_X2_R'
 '@T6G_MB_LIB.T6G(SCH_1):XTAL_CPU1_X48M_X2_R':
 C_SIGNAL='@t6g_mb_lib.t6g(sch_1):xtal_cpu1_x48m_x2_r';
NODE_NAME     R571 2
 '@T6G_MB_LIB.T6G(SCH_1):PAGE55_I10@PURE_QUANTA.Q_RES(CHIPS)':
 'B': CDS_PINID='B';
NODE_NAME     Y4 3
 '@T6G_MB_LIB.T6G(SCH_1):PAGE55_I12@PURE_QUANTA.Q_XTAL_4P_13BI_24GND(CHIPS)':
 'X2': CDS_PINID='X2';
NODE_NAME     C237 1
 '@T6G_MB_LIB.T6G(SCH_1):PAGE55_I15@PURE_QUANTA.Q_CAP(CHIPS)':
 'A': CDS_PINID='A';
NODE_NAME     R5103 2
 '@T6G_MB_LIB.T6G(SCH_1):PAGE55_I386@PURE_QUANTA.Q_RES(CHIPS)':
 'B': CDS_PINID='B';
NET_NAME
'XTAL_USB_CPU0_HUB1_XIN'
 '@T6G_MB_LIB.T6G(SCH_1):XTAL_USB_CPU0_HUB1_XIN':
 C_SIGNAL='@t6g_mb_lib.t6g(sch_1):xtal_usb_cpu0_hub1_xin';
NODE_NAME     U6001 55
 '@T6G_MB_LIB.T6G(SCH_1):PAGE153_I1@PURE_QUANTA.CYUSB330468LTXI(CHIPS)':
 'XTL_IN': CDS_PINID='XTL_IN';
NODE_NAME     Y9 1
 '@T6G_MB_LIB.T6G(SCH_1):PAGE153_I14@PURE_QUANTA.Q_XTAL_4P_13BI_24GND(CHIPS)':
 'X1': CDS_PINID='X1';
NODE_NAME     C91 1
 '@T6G_MB_LIB.T6G(SCH_1):PAGE153_I92@PURE_QUANTA.Q_CAP(CHIPS)':
 'A': CDS_PINID='A';
NET_NAME
'XTAL_USB_CPU0_HUB1_XOUT'
 '@T6G_MB_LIB.T6G(SCH_1):XTAL_USB_CPU0_HUB1_XOUT':
 C_SIGNAL='@t6g_mb_lib.t6g(sch_1):xtal_usb_cpu0_hub1_xout';
NODE_NAME     U6001 54
 '@T6G_MB_LIB.T6G(SCH_1):PAGE153_I1@PURE_QUANTA.CYUSB330468LTXI(CHIPS)':
 'XTL_OUT': CDS_PINID='XTL_OUT';
NODE_NAME     Y9 3
 '@T6G_MB_LIB.T6G(SCH_1):PAGE153_I14@PURE_QUANTA.Q_XTAL_4P_13BI_24GND(CHIPS)':
 'X2': CDS_PINID='X2';
NODE_NAME     C93 1
 '@T6G_MB_LIB.T6G(SCH_1):PAGE153_I91@PURE_QUANTA.Q_CAP(CHIPS)':
 'A': CDS_PINID='A';
NET_NAME
'XTAL_USB_CPU0_HUB2_XIN'
 '@T6G_MB_LIB.T6G(SCH_1):XTAL_USB_CPU0_HUB2_XIN':
 C_SIGNAL='@t6g_mb_lib.t6g(sch_1):xtal_usb_cpu0_hub2_xin';
NODE_NAME     U6002 62
 '@T6G_MB_LIB.T6G(SCH_1):PAGE157_I119@PURE_QUANTA.TUSB8042AIRGCR(CHIPS)':
 'XI': CDS_PINID='XI';
NODE_NAME     R6257 2
 '@T6G_MB_LIB.T6G(SCH_1):PAGE157_I160@PURE_QUANTA.Q_RES(CHIPS)':
 'B': CDS_PINID='B';
NODE_NAME     Y6000 1
 '@T6G_MB_LIB.T6G(SCH_1):PAGE157_I164@PURE_QUANTA.Q_XTAL_4P_13BI_24GND(CHIPS)':
 'X1': CDS_PINID='X1';
NODE_NAME     C6091 1
 '@T6G_MB_LIB.T6G(SCH_1):PAGE157_I175@PURE_QUANTA.Q_CAP(CHIPS)':
 'A': CDS_PINID='A';
NET_NAME
'XTAL_USB_CPU0_HUB2_XOUT'
 '@T6G_MB_LIB.T6G(SCH_1):XTAL_USB_CPU0_HUB2_XOUT':
 C_SIGNAL='@t6g_mb_lib.t6g(sch_1):xtal_usb_cpu0_hub2_xout';
NODE_NAME     U6002 61
 '@T6G_MB_LIB.T6G(SCH_1):PAGE157_I119@PURE_QUANTA.TUSB8042AIRGCR(CHIPS)':
 'XO': CDS_PINID='XO';
NODE_NAME     R6257 1
 '@T6G_MB_LIB.T6G(SCH_1):PAGE157_I160@PURE_QUANTA.Q_RES(CHIPS)':
 'A': CDS_PINID='A';
NODE_NAME     Y6000 3
 '@T6G_MB_LIB.T6G(SCH_1):PAGE157_I164@PURE_QUANTA.Q_XTAL_4P_13BI_24GND(CHIPS)':
 'X2': CDS_PINID='X2';
NODE_NAME     C6090 1
 '@T6G_MB_LIB.T6G(SCH_1):PAGE157_I174@PURE_QUANTA.Q_CAP(CHIPS)':
 'A': CDS_PINID='A';
END.
